G04 ================== begin FILE IDENTIFICATION RECORD ==================*
G04 Layout Name:  E:/<user>/9332_F0TG_MB_C/brd/0417/9332_F0TG_MB_C_V02_0417_0820.brd*
G04 Film Name:    ssb*
G04 File Format:  Gerber RS274X*
G04 File Origin:  Cadence Allegro 17.2-S081*
G04 Origin Date:  Wed Apr 19 14:50:16 2023*
G04 *
G04 Layer:  DRAWING FORMAT/TITLE_BLOCK_A*
G04 Layer:  BOARD GEOMETRY/DESIGN_OUTLINE*
G04 Layer:  BOARD GEOMETRY/CUTOUT*
G04 Layer:  DRAWING FORMAT/TITLE_BLOCK*
G04 Layer:  MANUFACTURING/TP_TEXT_BOTTOM*
G04 Layer:  REF DES/SILKSCREEN_BOTTOM*
G04 Layer:  PACKAGE GEOMETRY/SILKSCREEN_BOTTOM*
G04 Layer:  MANUFACTURING/PHOTOPLOT_OUTLINE*
G04 Layer:  DRAWING FORMAT/TITLE_DATA_SSB*
G04 Layer:  BOARD GEOMETRY/SILKSCREEN_BOTTOM*
G04 *
G04 Offset:    (0.00 0.00)*
G04 Mirror:    No*
G04 Mode:      Positive*
G04 Rotation:  0*
G04 FullContactRelief:  No*
G04 UndefLineWidth:     6.00*
G04 ================== end FILE IDENTIFICATION RECORD ====================*
%FSLAX25Y25*MOIN*%
%IR0*IPPOS*OFA0.00000B0.00000*MIA0B0*SFA1.00000B1.00000*%
%ADD10C,.006*%
G75*
%LPD*%
G75*
G36*
G01X50310Y433412D02*
X49239Y436624D01*
X52452Y435554D01*
X50310Y433412D01*
G37*
G36*
G01X195504Y1666357D02*
X196820Y1669153D01*
X194057Y1669088D01*
X195504Y1666357D01*
G37*
G36*
G01X197823Y1679421D02*
X200754Y1680398D01*
X198800Y1682353D01*
X197823Y1679421D01*
G37*
G36*
G01X198128Y1692957D02*
X201217Y1692856D01*
X200062Y1695367D01*
X198128Y1692957D01*
G37*
G36*
G01X197596Y1707106D02*
X200360Y1705724D01*
Y1708488D01*
X197596Y1707106D01*
G37*
G36*
G01X385650Y548289D02*
X381816Y549432D01*
X384878Y552694D01*
X385650Y548289D01*
G37*
G36*
G01X389126Y1671600D02*
Y1668836D01*
X391890Y1670218D01*
X389126Y1671600D01*
G37*
G36*
G01X417406Y1648674D02*
X418788Y1651438D01*
X416024D01*
X417406Y1648674D01*
G37*
G36*
G01X435162Y1631979D02*
X438131Y1632837D01*
X436257Y1634869D01*
X435162Y1631979D01*
G37*
G36*
G01X452099Y1649077D02*
X453451Y1651855D01*
X450688Y1651826D01*
X452099Y1649077D01*
G37*
G36*
G01X582044Y1256441D02*
X580338Y1259852D01*
X583749D01*
X582044Y1256441D01*
G37*
G36*
G01X625670Y1640962D02*
X623978Y1643018D01*
X623010Y1640842D01*
X625670Y1640962D01*
G37*
G36*
G01X650839Y1635085D02*
X652221Y1637848D01*
X649457D01*
X650839Y1635085D01*
G37*
G36*
G01X654094Y1693453D02*
X651163Y1692476D01*
X653117Y1690522D01*
X654094Y1693453D01*
G37*
G36*
G01X655442Y1706980D02*
X654060Y1704217D01*
X656824D01*
X655442Y1706980D01*
G37*
G36*
G01X668963Y1664799D02*
X670166Y1662423D01*
X671585Y1664336D01*
X668963Y1664799D01*
G37*
G36*
G01X682776Y1630301D02*
X682846Y1627302D01*
X685810Y1628872D01*
X682776Y1630301D01*
G37*
G36*
G01X701626Y1683583D02*
X703626Y1687583D01*
X699626D01*
X701626Y1683583D01*
G37*
G36*
G01X720147Y561934D02*
X718348Y564334D01*
X721648Y564933D01*
X720147Y561934D01*
G37*
G36*
G01X716281Y1652440D02*
X714542Y1654180D01*
X713914Y1651725D01*
X716281Y1652440D01*
G37*
G36*
G01X748955Y1669982D02*
X746636Y1666723D01*
X744536Y1670671D01*
X748955Y1669982D01*
G37*
G36*
G01X796395Y286646D02*
X798575Y287938D01*
Y285478D01*
X796395Y286646D01*
G37*
G36*
G01X791411Y311806D02*
X793591Y313098D01*
Y310638D01*
X791411Y311806D01*
G37*
G36*
G01X788074Y560650D02*
X788941Y558915D01*
X789808Y560650D01*
X788074D01*
G37*
G36*
G01X842592Y283097D02*
X841468Y285369D01*
X843921Y285183D01*
X842592Y283097D01*
G37*
G36*
G01X838999Y311688D02*
X841179Y312980D01*
Y310520D01*
X838999Y311688D01*
G37*
G36*
G01X856140Y1273089D02*
X858730Y1270041D01*
X860483Y1274155D01*
X856140Y1273089D01*
G37*
G36*
G01X872334Y1306246D02*
X868334D01*
X870334Y1310246D01*
X872334Y1306246D01*
G37*
G36*
G01X904743Y934207D02*
X900273Y934102D01*
X902145Y930568D01*
X904743Y934207D01*
G37*
G36*
G01X912081Y863235D02*
X913301Y865675D01*
X914521Y863235D01*
X912081D01*
G37*
G36*
G01X923876Y982619D02*
Y980237D01*
X921494Y981428D01*
X923876Y982619D01*
G37*
G36*
G01X938725Y891404D02*
X936524Y892457D01*
X936572Y889729D01*
X938725Y891404D01*
G37*
G36*
G01X946827Y928130D02*
X944413Y929254D01*
X944962Y926649D01*
X946827Y928130D01*
G37*
G36*
G01X955221Y892050D02*
X952781D01*
X954001Y889610D01*
X955221Y892050D01*
G37*
G36*
G01X964292Y1305587D02*
X960300Y1305331D01*
X962040Y1309451D01*
X964292Y1305587D01*
G37*
G36*
G01X1004450Y1292658D02*
Y1288658D01*
X1000450Y1290658D01*
X1004450Y1292658D01*
G37*
G36*
G01X1180185Y1677319D02*
X1182567Y1676128D01*
Y1678510D01*
X1180185Y1677319D01*
G37*
G36*
G01X1231941Y299853D02*
X1229177Y298471D01*
Y301235D01*
X1231941Y299853D01*
G37*
G36*
G01X1218170Y292153D02*
X1220934Y293535D01*
Y290771D01*
X1218170Y292153D01*
G37*
G36*
G01X1234952Y292066D02*
X1237716Y293448D01*
Y290684D01*
X1234952Y292066D01*
G37*
G36*
G01X1266780Y294190D02*
X1267757Y297121D01*
X1269711Y295167D01*
X1266780Y294190D01*
G37*
G36*
G01X1282170Y292066D02*
X1284934Y293448D01*
Y290684D01*
X1282170Y292066D01*
G37*
G36*
G01X1300995Y298153D02*
X1298231Y296771D01*
Y299535D01*
X1300995Y298153D01*
G37*
G36*
G01X1298300Y292066D02*
X1301064Y293448D01*
Y290684D01*
X1298300Y292066D01*
G37*
G36*
G01X1314952D02*
X1317716Y293448D01*
Y290684D01*
X1314952Y292066D01*
G37*
G36*
G01X1338343Y291979D02*
X1341107Y293361D01*
Y290597D01*
X1338343Y291979D01*
G37*
G36*
G01X1354214Y292066D02*
X1356978Y293448D01*
Y290684D01*
X1354214Y292066D01*
G37*
G36*
G01X1370517D02*
X1373281Y293448D01*
Y290684D01*
X1370517Y292066D01*
G37*
G36*
G01X1402382Y1650652D02*
X1403764Y1653415D01*
X1401000D01*
X1402382Y1650652D01*
G37*
G36*
G01X1480646Y1685599D02*
X1484646D01*
X1482646Y1681599D01*
X1480646Y1685599D01*
G37*
G36*
G01X1496812Y544322D02*
X1498388Y547455D01*
X1499945Y544322D01*
X1496812D01*
G37*
G36*
G01X1560130Y1253451D02*
X1558424Y1256862D01*
X1561835D01*
X1560130Y1253451D01*
G37*
G36*
G01X1592855Y801246D02*
X1595035Y802538D01*
Y800078D01*
X1592855Y801246D01*
G37*
G36*
G01X1600924Y1345033D02*
X1603104Y1343865D01*
Y1346325D01*
X1600924Y1345033D01*
G37*
G36*
G01Y1359513D02*
X1603104Y1358345D01*
Y1360805D01*
X1600924Y1359513D01*
G37*
G36*
G01X1666022Y1683239D02*
X1668404Y1682048D01*
Y1684430D01*
X1666022Y1683239D01*
G37*
G36*
G01X1696687Y1716065D02*
X1693755Y1715088D01*
X1695710Y1713133D01*
X1696687Y1716065D01*
G37*
G36*
G01X1900275Y-26974D02*
X1897275Y-20974D01*
X1903275D01*
X1900275Y-26974D01*
G37*
G36*
G01X1910275Y559228D02*
X1913275Y553228D01*
X1907275D01*
X1910275Y559228D01*
G37*
G36*
G01X1918395Y591236D02*
X1924395D01*
X1921395Y585236D01*
X1918395Y591236D01*
G37*
G36*
G01X1934395Y1165438D02*
X1928395D01*
X1931395Y1171438D01*
X1934395Y1165438D01*
G37*
G36*
G01X1919766Y1211159D02*
X1916766Y1217159D01*
X1922766D01*
X1919766Y1211159D01*
G37*
G36*
G01X1929766Y1797361D02*
X1932766Y1791361D01*
X1926766D01*
X1929766Y1797361D01*
G37*
G36*
G01X1942395Y-26784D02*
X1939395Y-20784D01*
X1945395D01*
X1942395Y-26784D01*
G37*
G36*
G01X1952395Y559418D02*
X1955395Y553418D01*
X1949395D01*
X1952395Y559418D01*
G37*
G36*
G01X1961856Y1211169D02*
X1958856Y1217169D01*
X1964856D01*
X1961856Y1211169D01*
G37*
G36*
G01X1960362Y591378D02*
X1966362D01*
X1963362Y585378D01*
X1960362Y591378D01*
G37*
G36*
G01X1976362Y1165580D02*
X1970362D01*
X1973362Y1171580D01*
X1976362Y1165580D01*
G37*
G36*
G01X1971856Y1797371D02*
X1974856Y1791371D01*
X1968856D01*
X1971856Y1797371D01*
G37*
G36*
G01X1984482Y-26812D02*
X1981482Y-20812D01*
X1987482D01*
X1984482Y-26812D01*
G37*
G36*
G01X1994482Y559390D02*
X1997482Y553390D01*
X1991482D01*
X1994482Y559390D01*
G37*
G36*
G01X2002452Y591388D02*
X2008452D01*
X2005452Y585388D01*
X2002452Y591388D01*
G37*
G36*
G01X2003823Y1211311D02*
X2000823Y1217311D01*
X2006823D01*
X2003823Y1211311D01*
G37*
G36*
G01X2018452Y1165590D02*
X2012452D01*
X2015452Y1171590D01*
X2018452Y1165590D01*
G37*
G36*
G01X2013823Y1797513D02*
X2016823Y1791513D01*
X2010823D01*
X2013823Y1797513D01*
G37*
G36*
G01X2026452Y-26632D02*
X2023452Y-20632D01*
X2029452D01*
X2026452Y-26632D01*
G37*
G36*
G01X2036452Y559570D02*
X2039452Y553570D01*
X2033452D01*
X2036452Y559570D01*
G37*
G36*
G01X2044419Y591530D02*
X2050419D01*
X2047419Y585530D01*
X2044419Y591530D01*
G37*
G36*
G01X2060419Y1165732D02*
X2054419D01*
X2057419Y1171732D01*
X2060419Y1165732D01*
G37*
G36*
G01X102636Y1316821D02*
Y1320203D01*
X120952D01*
Y1316821D01*
X102636D01*
G37*
G36*
G01X138736Y1317021D02*
Y1320403D01*
X157052D01*
Y1317021D01*
X138736D01*
G37*
G36*
G01X199836Y1316921D02*
Y1320303D01*
X218152D01*
Y1316921D01*
X199836D01*
G37*
G36*
G01X268403Y1271075D02*
Y1274457D01*
X286719D01*
Y1271075D01*
X268403D01*
G37*
G36*
G01X279223Y743610D02*
Y746992D01*
X297539D01*
Y743610D01*
X279223D01*
G37*
G36*
G01X297825Y1271075D02*
Y1274457D01*
X316141D01*
Y1271075D01*
X297825D01*
G37*
G36*
G01X317793Y763760D02*
Y767142D01*
X336109D01*
Y763760D01*
X317793D01*
G37*
G36*
G01X332418Y1270990D02*
Y1274372D01*
X350734D01*
Y1270990D01*
X332418D01*
G37*
G36*
G01X347499Y763760D02*
Y767142D01*
X365815D01*
Y763760D01*
X347499D01*
G37*
G36*
G01X377993Y763726D02*
Y767108D01*
X396309D01*
Y763726D01*
X377993D01*
G37*
G36*
G01X366818Y1270965D02*
Y1274347D01*
X385134D01*
Y1270965D01*
X366818D01*
G37*
G36*
G01X401503Y1290289D02*
Y1293671D01*
X419819D01*
Y1290289D01*
X401503D01*
G37*
G36*
G01X413793Y745826D02*
Y749208D01*
X432109D01*
Y745826D01*
X413793D01*
G37*
G36*
G01X447993Y721226D02*
Y724608D01*
X466309D01*
Y721226D01*
X447993D01*
G37*
G36*
G01X475593Y694660D02*
Y698042D01*
X493909D01*
Y694660D01*
X475593D01*
G37*
G36*
G01X495453Y694740D02*
Y698122D01*
X513769D01*
Y694740D01*
X495453D01*
G37*
G36*
G01X683113Y1332258D02*
Y1335640D01*
X701429D01*
Y1332258D01*
X683113D01*
G37*
G36*
G01X711113Y1333888D02*
Y1337270D01*
X729429D01*
Y1333888D01*
X711113D01*
G37*
G36*
G01X743583Y1333798D02*
Y1337180D01*
X761899D01*
Y1333798D01*
X743583D01*
G37*
G36*
G01X1074374Y1316802D02*
Y1320184D01*
X1092690D01*
Y1316802D01*
X1074374D01*
G37*
G36*
G01X1110474Y1317002D02*
Y1320384D01*
X1128790D01*
Y1317002D01*
X1110474D01*
G37*
G36*
G01X1171574Y1316902D02*
Y1320284D01*
X1189890D01*
Y1316902D01*
X1171574D01*
G37*
G36*
G01X1244532Y1271056D02*
Y1274438D01*
X1262848D01*
Y1271056D01*
X1244532D01*
G37*
G36*
G01X1273954D02*
Y1274438D01*
X1292270D01*
Y1271056D01*
X1273954D01*
G37*
G36*
G01X1308547Y1270971D02*
Y1274353D01*
X1326863D01*
Y1270971D01*
X1308547D01*
G37*
G36*
G01X1342947Y1270946D02*
Y1274328D01*
X1361263D01*
Y1270946D01*
X1342947D01*
G37*
G36*
G01X1377632Y1290270D02*
Y1293652D01*
X1395948D01*
Y1290270D01*
X1377632D01*
G37*
G36*
G01D02*
Y1293652D01*
X1395948D01*
Y1290270D01*
X1377632D01*
G37*
G36*
G01X1392131Y711724D02*
Y715106D01*
X1410447D01*
Y711724D01*
X1392131D01*
G37*
G36*
G01X1428103Y744183D02*
Y747565D01*
X1446419D01*
Y744183D01*
X1428103D01*
G37*
G36*
G01X1458631Y763928D02*
Y767310D01*
X1476947D01*
Y763928D01*
X1458631D01*
G37*
G36*
G01X1487493Y763760D02*
Y767142D01*
X1505809D01*
Y763760D01*
X1487493D01*
G37*
G36*
G01X1521872Y763773D02*
Y767155D01*
X1540188D01*
Y763773D01*
X1521872D01*
G37*
G36*
G01X1557283Y741820D02*
Y745202D01*
X1575599D01*
Y741820D01*
X1557283D01*
G37*
G36*
G01D02*
Y745202D01*
X1575599D01*
Y741820D01*
X1557283D01*
G37*
G36*
G01X1591893Y708198D02*
Y711580D01*
X1610209D01*
Y708198D01*
X1591893D01*
G37*
G36*
G01X1626943Y689068D02*
Y692450D01*
X1645259D01*
Y689068D01*
X1626943D01*
G37*
G36*
G01X1658829Y1332948D02*
Y1336330D01*
X1677145D01*
Y1332948D01*
X1658829D01*
G37*
G36*
G01X1691309Y1333128D02*
Y1336510D01*
X1709625D01*
Y1333128D01*
X1691309D01*
G37*
G36*
G01X1718809Y1331748D02*
Y1335130D01*
X1737125D01*
Y1331748D01*
X1718809D01*
G37*
G54D10*
G01X-476840Y-884638D02*
Y2768362D01*
X5911000D01*
Y-884638D01*
X-476840D01*
G01X8000Y-625138D02*
Y-630138D01*
G01X6543Y-625138D02*
X9457D01*
G01X14367Y-630138D02*
X11833D01*
Y-625138D01*
X14367D01*
G01X13353Y-627555D02*
X11833D01*
G01X16933Y-625138D02*
Y-630138D01*
X19467D01*
G01X23300Y-630305D02*
X23173Y-630221D01*
Y-630055D01*
X23300Y-629971D01*
X23427Y-630055D01*
Y-630221D01*
X23300Y-630305D01*
G01Y-628055D02*
X23173Y-627971D01*
Y-627805D01*
X23300Y-627721D01*
X23427Y-627805D01*
Y-627971D01*
X23300Y-628055D01*
G01X28083Y-631805D02*
X27450Y-630971D01*
X27133Y-630138D01*
Y-626805D01*
X27450Y-625971D01*
X28083Y-625138D01*
G01X33500D02*
X32993Y-625305D01*
X32613Y-625721D01*
X32360Y-626221D01*
X32170Y-626888D01*
X32107Y-627638D01*
X32170Y-628388D01*
X32360Y-629055D01*
X32613Y-629555D01*
X32993Y-629971D01*
X33500Y-630138D01*
X34007Y-629971D01*
X34387Y-629555D01*
X34640Y-629055D01*
X34830Y-628388D01*
X34893Y-627638D01*
X34830Y-626888D01*
X34640Y-626221D01*
X34387Y-625721D01*
X34007Y-625305D01*
X33500Y-625138D01*
G01X37207Y-629138D02*
X37587Y-629721D01*
X38093Y-630055D01*
X38663Y-630138D01*
X39170Y-630055D01*
X39677Y-629638D01*
X39993Y-629138D01*
X40057Y-628638D01*
X39930Y-628055D01*
X39487Y-627638D01*
X39043Y-627471D01*
X38473D01*
G01X39043D02*
X39423Y-627221D01*
X39740Y-626805D01*
X39867Y-626305D01*
X39740Y-625805D01*
X39423Y-625388D01*
X38853Y-625138D01*
X38283Y-625221D01*
X37713Y-625555D01*
G01X44017Y-631805D02*
X44650Y-630971D01*
X44967Y-630138D01*
Y-626805D01*
X44650Y-625971D01*
X44017Y-625138D01*
G01X47407Y-629138D02*
X47787Y-629721D01*
X48293Y-630055D01*
X48863Y-630138D01*
X49370Y-630055D01*
X49877Y-629638D01*
X50193Y-629138D01*
X50257Y-628638D01*
X50130Y-628055D01*
X49687Y-627638D01*
X49243Y-627471D01*
X48673D01*
G01X49243D02*
X49623Y-627221D01*
X49940Y-626805D01*
X50067Y-626305D01*
X49940Y-625805D01*
X49623Y-625388D01*
X49053Y-625138D01*
X48483Y-625221D01*
X47913Y-625555D01*
G01X52697Y-625971D02*
X53077Y-625471D01*
X53520Y-625221D01*
X54027Y-625138D01*
X54660Y-625305D01*
X55103Y-625721D01*
X55230Y-626221D01*
X55167Y-626721D01*
X54913Y-627138D01*
X53647Y-627971D01*
X53077Y-628555D01*
X52697Y-629388D01*
X52570Y-630138D01*
X55230D01*
G01X58873D02*
X59000Y-629055D01*
X59190Y-628138D01*
X59443Y-627305D01*
X59760Y-626388D01*
X60267Y-625138D01*
X57733D01*
G01X63277Y-628471D02*
X64923D01*
G01X67997Y-625971D02*
X68377Y-625471D01*
X68820Y-625221D01*
X69327Y-625138D01*
X69960Y-625305D01*
X70403Y-625721D01*
X70530Y-626221D01*
X70467Y-626721D01*
X70213Y-627138D01*
X68947Y-627971D01*
X68377Y-628555D01*
X67997Y-629388D01*
X67870Y-630138D01*
X70530D01*
G01X72907Y-629138D02*
X73287Y-629721D01*
X73793Y-630055D01*
X74363Y-630138D01*
X74870Y-630055D01*
X75377Y-629638D01*
X75693Y-629138D01*
X75757Y-628638D01*
X75630Y-628055D01*
X75187Y-627638D01*
X74743Y-627471D01*
X74173D01*
G01X74743D02*
X75123Y-627221D01*
X75440Y-626805D01*
X75567Y-626305D01*
X75440Y-625805D01*
X75123Y-625388D01*
X74553Y-625138D01*
X73983Y-625221D01*
X73413Y-625555D01*
G01X80160Y-630138D02*
Y-625138D01*
X77817Y-628721D01*
X80983D01*
G01X83107Y-629388D02*
X83487Y-629805D01*
X83930Y-630055D01*
X84500Y-630138D01*
X85070Y-629971D01*
X85513Y-629638D01*
X85830Y-629055D01*
X85893Y-628388D01*
X85767Y-627721D01*
X85450Y-627305D01*
X85007Y-626971D01*
X84563Y-626888D01*
X84120Y-626971D01*
X83550Y-627305D01*
X83740Y-625138D01*
X85450D01*
G01X93497Y-630138D02*
Y-625138D01*
X95903D01*
G01X95017Y-627555D02*
X93497D01*
G01X98217Y-630138D02*
X99800Y-625138D01*
X101383Y-630138D01*
G01X100813Y-628388D02*
X98787D01*
G01X103570Y-630138D02*
X106230Y-625138D01*
G01X103570D02*
X106230Y-630138D01*
G01X110000Y-630305D02*
X109873Y-630221D01*
Y-630055D01*
X110000Y-629971D01*
X110127Y-630055D01*
Y-630221D01*
X110000Y-630305D01*
G01Y-628055D02*
X109873Y-627971D01*
Y-627805D01*
X110000Y-627721D01*
X110127Y-627805D01*
Y-627971D01*
X110000Y-628055D01*
G01X114783Y-631805D02*
X114150Y-630971D01*
X113833Y-630138D01*
Y-626805D01*
X114150Y-625971D01*
X114783Y-625138D01*
G01X120200D02*
X119693Y-625305D01*
X119313Y-625721D01*
X119060Y-626221D01*
X118870Y-626888D01*
X118807Y-627638D01*
X118870Y-628388D01*
X119060Y-629055D01*
X119313Y-629555D01*
X119693Y-629971D01*
X120200Y-630138D01*
X120707Y-629971D01*
X121087Y-629555D01*
X121340Y-629055D01*
X121530Y-628388D01*
X121593Y-627638D01*
X121530Y-626888D01*
X121340Y-626221D01*
X121087Y-625721D01*
X120707Y-625305D01*
X120200Y-625138D01*
G01X123907Y-629138D02*
X124287Y-629721D01*
X124793Y-630055D01*
X125363Y-630138D01*
X125870Y-630055D01*
X126377Y-629638D01*
X126693Y-629138D01*
X126757Y-628638D01*
X126630Y-628055D01*
X126187Y-627638D01*
X125743Y-627471D01*
X125173D01*
G01X125743D02*
X126123Y-627221D01*
X126440Y-626805D01*
X126567Y-626305D01*
X126440Y-625805D01*
X126123Y-625388D01*
X125553Y-625138D01*
X124983Y-625221D01*
X124413Y-625555D01*
G01X130717Y-631805D02*
X131350Y-630971D01*
X131667Y-630138D01*
Y-626805D01*
X131350Y-625971D01*
X130717Y-625138D01*
G01X134107Y-629138D02*
X134487Y-629721D01*
X134993Y-630055D01*
X135563Y-630138D01*
X136070Y-630055D01*
X136577Y-629638D01*
X136893Y-629138D01*
X136957Y-628638D01*
X136830Y-628055D01*
X136387Y-627638D01*
X135943Y-627471D01*
X135373D01*
G01X135943D02*
X136323Y-627221D01*
X136640Y-626805D01*
X136767Y-626305D01*
X136640Y-625805D01*
X136323Y-625388D01*
X135753Y-625138D01*
X135183Y-625221D01*
X134613Y-625555D01*
G01X139523Y-629555D02*
X139967Y-629971D01*
X140473Y-630138D01*
X140980Y-629971D01*
X141423Y-629471D01*
X141740Y-628721D01*
X141867Y-627971D01*
Y-627055D01*
X141740Y-626305D01*
X141423Y-625638D01*
X141043Y-625305D01*
X140600Y-625138D01*
X140093Y-625305D01*
X139713Y-625638D01*
X139460Y-626138D01*
X139333Y-626805D01*
X139460Y-627388D01*
X139777Y-627971D01*
X140157Y-628305D01*
X140600Y-628388D01*
X141107Y-628221D01*
X141487Y-627805D01*
X141867Y-627055D01*
G01X145573Y-630138D02*
X145700Y-629055D01*
X145890Y-628138D01*
X146143Y-627305D01*
X146460Y-626388D01*
X146967Y-625138D01*
X144433D01*
G01X149977Y-628471D02*
X151623D01*
G01X154507Y-629138D02*
X154887Y-629721D01*
X155393Y-630055D01*
X155963Y-630138D01*
X156470Y-630055D01*
X156977Y-629638D01*
X157293Y-629138D01*
X157357Y-628638D01*
X157230Y-628055D01*
X156787Y-627638D01*
X156343Y-627471D01*
X155773D01*
G01X156343D02*
X156723Y-627221D01*
X157040Y-626805D01*
X157167Y-626305D01*
X157040Y-625805D01*
X156723Y-625388D01*
X156153Y-625138D01*
X155583Y-625221D01*
X155013Y-625555D01*
G01X159797Y-628055D02*
X160240Y-627471D01*
X160620Y-627138D01*
X161127Y-626971D01*
X161570Y-627138D01*
X161887Y-627471D01*
X162140Y-627971D01*
X162203Y-628555D01*
X162140Y-629055D01*
X161887Y-629555D01*
X161507Y-629971D01*
X161063Y-630138D01*
X160557Y-629971D01*
X160113Y-629471D01*
X159860Y-628721D01*
X159797Y-627888D01*
X159923Y-626805D01*
X160113Y-626221D01*
X160430Y-625638D01*
X160873Y-625221D01*
X161317Y-625138D01*
X161760Y-625305D01*
X162077Y-625721D01*
G01X166100Y-630138D02*
Y-625138D01*
X165340Y-626138D01*
G01Y-630138D02*
X166860D01*
G01X171960D02*
Y-625138D01*
X169617Y-628721D01*
X172783D01*
G01X-4000Y-560138D02*
Y-635138D01*
X496000D01*
Y-560138D01*
X-4000D01*
G01X2306Y311361D02*
G03X0Y305794I5567J-5567D01*
G01Y54252D01*
G03X7874Y46378I7874J0D01*
G01X43709D01*
G02X51583Y38504I0J-7874D01*
G01Y1969D01*
G03X53551Y0I1968J0D01*
G01X319693D01*
G03X321661Y1969I0J1969D01*
G01Y38504D01*
G02X329535Y46378I7874J0D01*
G01X488591D01*
G02X496465Y38504I0J-7874D01*
G01Y22756D01*
G03X498433Y20787I1968J-1D01*
G01X764575D01*
G03X766543Y22756I-1J1969D01*
G01Y38504D01*
G02X774417Y46378I7874J0D01*
G01X871260D01*
G03X879134Y54252I0J7874D01*
G01Y134331D01*
G02X887008Y142205I7874J0D01*
G01X1011024D01*
G02X1018898Y134331I0J-7874D01*
G01Y54252D01*
G03X1026772Y46378I7874J0D01*
G01X1518118D01*
G02X1525992Y38504I0J-7874D01*
G01Y1969D01*
G03X1527961Y0I1969J0D01*
G01X1794102D01*
G03X1796071Y1969I0J1969D01*
G01Y38504D01*
G02X1803945Y46378I7874J0D01*
G01X1849606D01*
G03X1857480Y54252I0J7874D01*
G01Y305794D01*
G03X1855174Y311361I-7873J0D01*
G01X1846007Y320528D01*
G02X1843701Y326096I5568J5568D01*
G01Y1593983D01*
G03X1841395Y1599550I-7873J0D01*
G01X1834196Y1606749D01*
G02X1831890Y1612317I5568J5568D01*
G01Y1732244D01*
G03X1824016Y1740118I-7874J0D01*
G01X1091791D01*
G03X1089823Y1738150I0J-1968D01*
G01Y1736890D01*
G02X1087854Y1734921I-1969J0D01*
G01X769705D01*
G02X767736Y1736890I0J1969D01*
G01Y1738150D01*
G03X765768Y1740118I-1968J0D01*
G01X33465D01*
G03X25591Y1732244I0J-7874D01*
G01Y1612317D01*
G02X23284Y1606749I-7875J1D01*
G01X10180Y1593645D01*
G03X7874Y1588077I5568J-5568D01*
G01Y320191D01*
G02X5568Y314623I-7874J0D01*
G01X2306Y311361D01*
G01X38583Y87795D02*
G02X16535I-11024J0D01*
G02X38583I11024J0D01*
G01X34390Y1533228D02*
G02X19705I-7342J0D01*
G02X34390I7343J0D01*
G01X51732Y631890D02*
G02X29685I-11024J0D01*
G02X51732I11023J0D01*
G01Y1368898D02*
G02X29685I-11024J0D01*
G02X51732I11023J0D01*
G01X52141Y119148D02*
X56741Y123451D01*
G02X65079Y114538I4169J-4456D01*
G01X60479Y110235D01*
G02X52141Y119148I-4169J4456D01*
G01X40157Y1714961D02*
G02X62205I11024J0D01*
G02X40157I-11024J0D01*
G01X86933Y1369350D02*
G02X72248I-7343J0D01*
G02X86933I7342J0D01*
G01X137618Y605378D02*
G02X98248I-19685J0D01*
G02X137618I19685J0D01*
G01X146929Y1482244D02*
G02X129213I-8858J0D01*
G02X146929I8858J0D01*
G01X144626Y1533228D02*
G02X129941I-7343J0D01*
G02X144626I7342J0D01*
G01X172520Y1593661D02*
G02X154803I-8858J0D01*
G02X172520I8859J0D01*
G01X157728Y294335D02*
G02X197098I19685J0D01*
G01Y260083D01*
G02X157728I-19685J0D01*
G01Y294335D01*
G01X191000Y-560138D02*
Y-635138D01*
G01Y-610138D02*
X294000D01*
Y-585138D01*
G01X191000D02*
X294000D01*
G01X222760Y658012D02*
G02X208075I-7342J0D01*
G02X222760I7343J0D01*
G01X247177Y191535D02*
X253476D01*
G02Y178937I0J-6299D01*
G01X247177D01*
G02Y191535I0J6299D01*
G01X284579Y185236D02*
G02X269618I-7481J0D01*
G02X284579I7481J0D01*
G01X282795Y1019252D02*
G02X267047I-7874J0D01*
G02X282795I7874J0D01*
G01X283783Y1357539D02*
G02X269098I-7342J0D01*
G02X283783I7343J0D01*
G01X296000Y-560138D02*
Y-635138D01*
G01X294000Y-560138D02*
Y-635138D01*
G01X301507Y-620138D02*
Y-615138D01*
X302773D01*
X303280Y-615388D01*
X303660Y-615721D01*
X303977Y-616221D01*
X304230Y-616805D01*
X304293Y-617638D01*
X304230Y-618471D01*
X303977Y-619055D01*
X303660Y-619555D01*
X303280Y-619888D01*
X302773Y-620138D01*
X301507D01*
G01X306417D02*
X308000Y-615138D01*
X309583Y-620138D01*
G01X309013Y-618388D02*
X306987D01*
G01X313100Y-615138D02*
Y-620138D01*
G01X311643Y-615138D02*
X314557D01*
G01X319467Y-620138D02*
X316933D01*
Y-615138D01*
X319467D01*
G01X318453Y-617555D02*
X316933D01*
G01X323300Y-620305D02*
X323173Y-620221D01*
Y-620055D01*
X323300Y-619971D01*
X323427Y-620055D01*
Y-620221D01*
X323300Y-620305D01*
G01Y-618055D02*
X323173Y-617971D01*
Y-617805D01*
X323300Y-617721D01*
X323427Y-617805D01*
Y-617971D01*
X323300Y-618055D01*
G01X296000Y-610138D02*
X496000D01*
G01X301633Y-595138D02*
Y-590138D01*
X303153D01*
X303660Y-590388D01*
X304040Y-590971D01*
X304167Y-591638D01*
X304040Y-592305D01*
X303723Y-592805D01*
X303153Y-593055D01*
X301633D01*
G01X306860Y-595305D02*
X309140Y-590138D01*
G01X311643Y-595138D02*
Y-590138D01*
X314557Y-595138D01*
Y-590138D01*
G01X318200Y-595305D02*
X318073Y-595221D01*
Y-595055D01*
X318200Y-594971D01*
X318327Y-595055D01*
Y-595221D01*
X318200Y-595305D01*
G01Y-593055D02*
X318073Y-592971D01*
Y-592805D01*
X318200Y-592721D01*
X318327Y-592805D01*
Y-592971D01*
X318200Y-593055D01*
G01X296000Y-585138D02*
X496000D01*
G01X301633Y-570138D02*
Y-565138D01*
X303153D01*
X303660Y-565388D01*
X304040Y-565971D01*
X304167Y-566638D01*
X304040Y-567305D01*
X303723Y-567805D01*
X303153Y-568055D01*
X301633D01*
G01X306733Y-570138D02*
Y-565138D01*
X308317D01*
X308823Y-565388D01*
X309140Y-565721D01*
X309267Y-566388D01*
X309140Y-567055D01*
X308760Y-567471D01*
X308317Y-567721D01*
X306733D01*
G01X308317D02*
X309267Y-570138D01*
G01X313100D02*
X312593Y-570055D01*
X312150Y-569721D01*
X311770Y-569221D01*
X311517Y-568638D01*
X311390Y-567971D01*
Y-567305D01*
X311517Y-566638D01*
X311770Y-566055D01*
X312150Y-565555D01*
X312593Y-565221D01*
X313100Y-565138D01*
X313607Y-565221D01*
X314050Y-565555D01*
X314430Y-566055D01*
X314683Y-566638D01*
X314810Y-567305D01*
Y-567971D01*
X314683Y-568638D01*
X314430Y-569221D01*
X314050Y-569721D01*
X313607Y-570055D01*
X313100Y-570138D01*
G01X316933Y-569138D02*
X317250Y-569638D01*
X317630Y-569971D01*
X318073Y-570138D01*
X318580Y-569971D01*
X318960Y-569638D01*
X319340Y-569138D01*
X319467Y-568471D01*
Y-565138D01*
G01X324567Y-570138D02*
X322033D01*
Y-565138D01*
X324567D01*
G01X323553Y-567555D02*
X322033D01*
G01X329793Y-565555D02*
X329413Y-565305D01*
X328970Y-565138D01*
X328463D01*
X327893Y-565388D01*
X327450Y-565805D01*
X327133Y-566305D01*
X326880Y-567138D01*
X326817Y-567888D01*
X326943Y-568638D01*
X327133Y-569138D01*
X327513Y-569638D01*
X327957Y-569971D01*
X328400Y-570138D01*
X328843D01*
X329287Y-569971D01*
X329667Y-569721D01*
X329983Y-569388D01*
G01X333500Y-565138D02*
Y-570138D01*
G01X332043Y-565138D02*
X334957D01*
G01X338600Y-570305D02*
X338473Y-570221D01*
Y-570055D01*
X338600Y-569971D01*
X338727Y-570055D01*
Y-570221D01*
X338600Y-570305D01*
G01Y-568055D02*
X338473Y-567971D01*
Y-567805D01*
X338600Y-567721D01*
X338727Y-567805D01*
Y-567971D01*
X338600Y-568055D01*
G01X328071Y838543D02*
G02X312323I-7874J0D01*
G02X328071I7874J0D01*
G01Y1199961D02*
G02X312323I-7874J0D01*
G02X328071I7874J0D01*
G01X384646Y87795D02*
G02X362598I-11024J0D01*
G02X384646I11024J0D01*
G01X365287Y191535D02*
X371587D01*
G02Y178937I0J-6299D01*
G01X365287D01*
G02Y191535I0J6299D01*
G01X402689Y185236D02*
G02X387728I-7480J0D01*
G02X402689I7481J0D01*
G01X406694Y1714961D02*
G02X384647I-11023J0D01*
G02X406694I11023J0D01*
G01X411000Y-610138D02*
Y-635138D01*
G01X413633Y-612638D02*
Y-617638D01*
X416167D01*
G01X419240Y-612638D02*
X420760D01*
G01X420000D02*
Y-617638D01*
G01X419240D02*
X420760D01*
G01X425607Y-614971D02*
X425860Y-614721D01*
X426050Y-614305D01*
X426177Y-613721D01*
X426050Y-613221D01*
X425797Y-612888D01*
X425353Y-612638D01*
X423643D01*
Y-617638D01*
X425733D01*
X426177Y-617305D01*
X426430Y-616805D01*
X426557Y-616221D01*
X426430Y-615638D01*
X426050Y-615138D01*
X425607Y-614971D01*
X423643D01*
G01X430200Y-617805D02*
X430073Y-617721D01*
Y-617555D01*
X430200Y-617471D01*
X430327Y-617555D01*
Y-617721D01*
X430200Y-617805D01*
G01Y-615555D02*
X430073Y-615471D01*
Y-615305D01*
X430200Y-615221D01*
X430327Y-615305D01*
Y-615471D01*
X430200Y-615555D01*
G01X427484Y655965D02*
G02X412799I-7343J0D01*
G02X427484I7343J0D01*
G01X451106Y1339823D02*
G02X436421I-7343J0D01*
G02X451106I7343J0D01*
G01X434793Y1698268D02*
G02X447293I6250J0D01*
G02X434793I-6250J0D01*
G01X454000Y-610138D02*
Y-635138D01*
G01Y-585138D02*
Y-610138D01*
G01X459013Y-637305D02*
X459120Y-637180D01*
X459200Y-636971D01*
X459253Y-636680D01*
X459200Y-636430D01*
X459093Y-636263D01*
X458907Y-636138D01*
X458187D01*
Y-638638D01*
X459067D01*
X459253Y-638471D01*
X459360Y-638221D01*
X459413Y-637930D01*
X459360Y-637638D01*
X459200Y-637388D01*
X459013Y-637305D01*
X458187D01*
G01X461480Y-638638D02*
Y-636971D01*
G01Y-637263D02*
X461373Y-637096D01*
X461213Y-637013D01*
X461027Y-636971D01*
X460840Y-637055D01*
X460680Y-637221D01*
X460573Y-637471D01*
X460520Y-637805D01*
X460573Y-638138D01*
X460680Y-638388D01*
X460840Y-638555D01*
X461027Y-638638D01*
X461213Y-638596D01*
X461373Y-638471D01*
X461480Y-638305D01*
G01X462800Y-638346D02*
X462933Y-638513D01*
X463120Y-638638D01*
X463280D01*
X463440Y-638555D01*
X463547Y-638430D01*
X463600Y-638263D01*
X463573Y-638013D01*
X463467Y-637888D01*
X462987Y-637638D01*
X462880Y-637346D01*
X462933Y-637138D01*
X463040Y-637013D01*
X463200Y-636971D01*
X463360Y-637013D01*
X463520Y-637138D01*
G01X465000Y-637513D02*
X465853D01*
X465773Y-637221D01*
X465640Y-637055D01*
X465453Y-636971D01*
X465267Y-637013D01*
X465107Y-637138D01*
X465000Y-637430D01*
X464947Y-637680D01*
Y-637930D01*
X465000Y-638180D01*
X465133Y-638430D01*
X465293Y-638596D01*
X465480Y-638638D01*
X465667Y-638555D01*
X465853Y-638305D01*
G01X467120Y-638638D02*
Y-636138D01*
G01Y-637388D02*
X467253Y-637138D01*
X467413Y-637013D01*
X467573Y-636971D01*
X467813Y-637055D01*
X467973Y-637221D01*
X468080Y-637513D01*
Y-637846D01*
X468027Y-638180D01*
X467920Y-638430D01*
X467733Y-638596D01*
X467573Y-638638D01*
X467413Y-638596D01*
X467253Y-638471D01*
X467120Y-638263D01*
G01X469800Y-638638D02*
X469640Y-638596D01*
X469480Y-638430D01*
X469373Y-638138D01*
X469320Y-637805D01*
X469373Y-637471D01*
X469480Y-637180D01*
X469640Y-637013D01*
X469800Y-636971D01*
X469960Y-637013D01*
X470120Y-637180D01*
X470227Y-637471D01*
X470253Y-637805D01*
X470227Y-638138D01*
X470120Y-638430D01*
X469960Y-638596D01*
X469800Y-638638D01*
G01X472480D02*
Y-636971D01*
G01Y-637263D02*
X472373Y-637096D01*
X472213Y-637013D01*
X472027Y-636971D01*
X471840Y-637055D01*
X471680Y-637221D01*
X471573Y-637471D01*
X471520Y-637805D01*
X471573Y-638138D01*
X471680Y-638388D01*
X471840Y-638555D01*
X472027Y-638638D01*
X472213Y-638596D01*
X472373Y-638471D01*
X472480Y-638305D01*
G01X473827Y-638638D02*
Y-636971D01*
G01Y-637305D02*
X473960Y-637138D01*
X474093Y-637013D01*
X474280Y-636971D01*
X474413Y-637013D01*
X474573Y-637138D01*
G01X476880Y-636138D02*
Y-638638D01*
G01Y-638263D02*
X476773Y-638471D01*
X476613Y-638596D01*
X476427Y-638638D01*
X476213Y-638555D01*
X476053Y-638346D01*
X475947Y-638096D01*
X475920Y-637805D01*
X475947Y-637513D01*
X476053Y-637263D01*
X476213Y-637055D01*
X476427Y-636971D01*
X476613Y-637013D01*
X476747Y-637096D01*
X476880Y-637263D01*
G01X480267Y-638638D02*
Y-636138D01*
X480933D01*
X481147Y-636263D01*
X481280Y-636430D01*
X481333Y-636763D01*
X481280Y-637096D01*
X481120Y-637305D01*
X480933Y-637430D01*
X480267D01*
G01X480933D02*
X481333Y-638638D01*
G01X482600Y-637513D02*
X483453D01*
X483373Y-637221D01*
X483240Y-637055D01*
X483053Y-636971D01*
X482867Y-637013D01*
X482707Y-637138D01*
X482600Y-637430D01*
X482547Y-637680D01*
Y-637930D01*
X482600Y-638180D01*
X482733Y-638430D01*
X482893Y-638596D01*
X483080Y-638638D01*
X483267Y-638555D01*
X483453Y-638305D01*
G01X484720Y-636971D02*
X485200Y-638638D01*
X485680Y-636971D01*
G01X487400Y-638721D02*
X487347Y-638680D01*
Y-638596D01*
X487400Y-638555D01*
X487453Y-638596D01*
Y-638680D01*
X487400Y-638721D01*
G01X489147Y-638346D02*
X489333Y-638555D01*
X489547Y-638638D01*
X489760Y-638555D01*
X489947Y-638305D01*
X490080Y-637930D01*
X490133Y-637555D01*
Y-637096D01*
X490080Y-636721D01*
X489947Y-636388D01*
X489787Y-636221D01*
X489600Y-636138D01*
X489387Y-636221D01*
X489227Y-636388D01*
X489120Y-636638D01*
X489067Y-636971D01*
X489120Y-637263D01*
X489253Y-637555D01*
X489413Y-637721D01*
X489600Y-637763D01*
X489813Y-637680D01*
X489973Y-637471D01*
X490133Y-637096D01*
G01X492013Y-637305D02*
X492120Y-637180D01*
X492200Y-636971D01*
X492253Y-636680D01*
X492200Y-636430D01*
X492093Y-636263D01*
X491907Y-636138D01*
X491187D01*
Y-638638D01*
X492067D01*
X492253Y-638471D01*
X492360Y-638221D01*
X492413Y-637930D01*
X492360Y-637638D01*
X492200Y-637388D01*
X492013Y-637305D01*
X491187D01*
G01X457900Y-612638D02*
Y-617638D01*
G01X456443Y-612638D02*
X459357D01*
G01X463000Y-617638D02*
X462620Y-617555D01*
X462240Y-617221D01*
X461987Y-616638D01*
X461860Y-615971D01*
X461987Y-615305D01*
X462240Y-614721D01*
X462620Y-614388D01*
X463000Y-614305D01*
X463380Y-614388D01*
X463760Y-614721D01*
X464013Y-615305D01*
X464077Y-615971D01*
X464013Y-616638D01*
X463760Y-617221D01*
X463380Y-617555D01*
X463000Y-617638D01*
G01X468100D02*
X467720Y-617555D01*
X467340Y-617221D01*
X467087Y-616638D01*
X466960Y-615971D01*
X467087Y-615305D01*
X467340Y-614721D01*
X467720Y-614388D01*
X468100Y-614305D01*
X468480Y-614388D01*
X468860Y-614721D01*
X469113Y-615305D01*
X469177Y-615971D01*
X469113Y-616638D01*
X468860Y-617221D01*
X468480Y-617555D01*
X468100Y-617638D01*
G01X473200D02*
Y-612638D01*
G01X478300Y-617805D02*
X478173Y-617721D01*
Y-617555D01*
X478300Y-617471D01*
X478427Y-617555D01*
Y-617721D01*
X478300Y-617805D01*
G01Y-615555D02*
X478173Y-615471D01*
Y-615305D01*
X478300Y-615221D01*
X478427Y-615305D01*
Y-615471D01*
X478300Y-615555D01*
G01X456633Y-592638D02*
Y-587638D01*
X458217D01*
X458723Y-587888D01*
X459040Y-588221D01*
X459167Y-588888D01*
X459040Y-589555D01*
X458660Y-589971D01*
X458217Y-590221D01*
X456633D01*
G01X458217D02*
X459167Y-592638D01*
G01X464267D02*
X461733D01*
Y-587638D01*
X464267D01*
G01X463253Y-590055D02*
X461733D01*
G01X466517Y-587638D02*
X468100Y-592638D01*
X469683Y-587638D01*
G01X473200Y-592805D02*
X473073Y-592721D01*
Y-592555D01*
X473200Y-592471D01*
X473327Y-592555D01*
Y-592721D01*
X473200Y-592805D01*
G01Y-590555D02*
X473073Y-590471D01*
Y-590305D01*
X473200Y-590221D01*
X473327Y-590305D01*
Y-590471D01*
X473200Y-590555D01*
G01X530516Y578130D02*
G02X515831I-7343J0D01*
G02X530516I7342J0D01*
G01X569016Y838543D02*
G02X553268I-7874J0D01*
G02X569016I7874J0D01*
G01Y1199961D02*
G02X553268I-7874J0D01*
G02X569016I7874J0D01*
G01X614291Y1019252D02*
G02X598543I-7874J0D01*
G02X614291I7874J0D01*
G01X672047Y631890D02*
G02X650000I-11024J0D01*
G02X672047I11023J0D01*
G01X688783Y1385138D02*
G02X674098I-7343J0D01*
G02X688783I7343J0D01*
G01X682087Y1593661D02*
G02X664370I-8859J0D01*
G02X682087I8859J0D01*
G01X684500Y294362D02*
G02X723870I19685J0D01*
G01Y260110D01*
G02X684500I-19685J0D01*
G01Y294362D01*
G01X707677Y1482244D02*
G02X689961I-8858J0D01*
G02X707677I8858J0D01*
G01X718701Y1714961D02*
G02X696654I-11024J0D01*
G02X718701I11023J0D01*
G01X783287Y605413D02*
G02X743917I-19685J0D01*
G02X783287I19685J0D01*
G01X811811Y87795D02*
G02X789764I-11023J0D01*
G02X811811I11023J0D01*
G01X816535Y204724D02*
G02X794882I-10826J0D01*
G02X816535I10827J0D01*
G01X799020Y1385138D02*
G02X784335I-7343J0D01*
G02X799020I7342J0D01*
G01X849114Y1420331D02*
G02X833366I-7874J0D01*
G02X849114I7874J0D01*
G01X880965Y1145276D02*
G02X866280I-7342J0D01*
G02X880965I7343J0D01*
G01X895789Y1528196D02*
G02X879254I-8267J0D01*
G02X895789I8268J0D01*
G01X904134Y175177D02*
G02X896260I-3937J0D01*
G02X904134I3937J0D01*
G01X936673Y311614D02*
X920807D01*
G02X936673I7933J10039D01*
G01X942717Y757874D02*
G02X920669I-11024J0D01*
G02X942717I11024J0D01*
G01Y1072835D02*
G02X920669I-11024J0D01*
G02X942717I11024J0D01*
G01Y1387795D02*
G02X920669I-11024J0D01*
G02X942717I11024J0D01*
G01X948622Y155197D02*
G02X940748I-3937J0D01*
G02X948622I3937J0D01*
G01X991201Y1145276D02*
G02X976516I-7343J0D01*
G02X991201I7343J0D01*
G01X1024114Y1420331D02*
G02X1008366I-7874J0D01*
G02X1024114I7874J0D01*
G01X1056890Y87795D02*
G02X1034843I-11023J0D01*
G02X1056890I11024J0D01*
G01X1068504Y204724D02*
G02X1046850I-10827J0D01*
G02X1068504I10827J0D01*
G01X1060303Y1369350D02*
G02X1045618I-7343J0D01*
G02X1060303I7343J0D01*
G01X1113760Y605378D02*
G02X1074390I-19685J0D01*
G02X1113760I19685J0D01*
G01X1133870Y294335D02*
G02X1173240I19685J0D01*
G01Y260083D01*
G02X1133870I-19685J0D01*
G01Y294335D01*
G01X1154803Y1515236D02*
G02X1137087I-8858J0D01*
G02X1154803I8858J0D01*
G01X1166732Y1714961D02*
G02X1144685I-11024J0D01*
G02X1166732I11023J0D01*
G01X1180394Y1626654D02*
G02X1162677I-8859J0D01*
G02X1180394I8859J0D01*
G01X1258937Y1019252D02*
G02X1243189I-7874J0D01*
G02X1258937I7874J0D01*
G01X1257154Y1357539D02*
G02X1242469I-7343J0D01*
G02X1257154I7343J0D01*
G01X1282283Y631890D02*
G02X1260236I-11023J0D01*
G02X1282283I11023J0D01*
G01X1304213Y838543D02*
G02X1288465I-7874J0D01*
G02X1304213I7874J0D01*
G01Y1199961D02*
G02X1288465I-7874J0D01*
G02X1304213I7874J0D01*
G01X1377626Y582303D02*
G02X1362941I-7343J0D01*
G02X1377626I7342J0D01*
G01X1424476Y1339823D02*
G02X1409791I-7343J0D01*
G02X1424476I7342J0D01*
G01X1410187Y1698268D02*
G02X1422687I6250J0D01*
G02X1410187I-6250J0D01*
G01X1472829Y1714961D02*
G02X1450782I-11024J0D01*
G02X1472829I11023J0D01*
G01X1510630Y87795D02*
G02X1488583I-11023J0D01*
G02X1510630I11024J0D01*
G01X1540894Y682343D02*
G02X1526209I-7343J0D01*
G02X1540894I7342J0D01*
G01X1545157Y838543D02*
G02X1529409I-7874J0D01*
G02X1545157I7874J0D01*
G01Y1199961D02*
G02X1529409I-7874J0D01*
G02X1545157I7874J0D01*
G01X1590433Y1019252D02*
G02X1574685I-7874J0D01*
G02X1590433I7874J0D01*
G01X1637075Y1383524D02*
G02X1622390I-7343J0D01*
G02X1637075I7343J0D01*
G01X1660642Y294362D02*
G02X1700012I19685J0D01*
G01Y260110D01*
G02X1660642I-19685J0D01*
G01Y294362D01*
G01X1672232Y642972D02*
G02X1657547I-7343J0D01*
G02X1672232I7342J0D01*
G01X1689961Y1626654D02*
G02X1672244I-8859J0D01*
G02X1689961I8859J0D01*
G01X1715551Y1515236D02*
G02X1697835I-8858J0D01*
G02X1715551I8858J0D01*
G01X1759429Y605413D02*
G02X1720059I-19685J0D01*
G02X1759429I19685J0D01*
G01X1721673Y1570984D02*
G02X1706988I-7342J0D01*
G02X1721673I7343J0D01*
G01X1747311Y1383524D02*
G02X1732626I-7343J0D01*
G02X1747311I7343J0D01*
G01X1768917Y159134D02*
G02X1754232I-7342J0D01*
G02X1768917I7343J0D01*
G01X1773031Y1714961D02*
G02X1760827I-6102J0D01*
G02X1773031I6102J0D01*
G01X1817323D02*
G02X1795276I-11023J0D01*
G02X1817323I11024J0D01*
G01X1827795Y631890D02*
G02X1805748I-11023J0D01*
G02X1827795I11024J0D01*
G01Y1368898D02*
G02X1805748I-11023J0D01*
G02X1827795I11024J0D01*
G01X1840945Y87795D02*
G02X1818898I-11023J0D01*
G02X1840945I11023J0D01*
G01X1823819Y133465D02*
G02X1836024I6103J0D01*
G01Y127165D01*
G02X1823819I-6103J0D01*
G01Y133465D01*
G01X1831909Y1570984D02*
G02X1817224I-7342J0D01*
G02X1831909I7343J0D01*
G01X1845492Y201929D02*
G02X1830807I-7342J0D01*
G02X1845492I7343J0D01*
G01X-476840Y-884638D02*
Y2768362D01*
X5911000D01*
Y-884638D01*
X-476840D01*
G01X8820Y-607488D02*
X10387D01*
Y-609378D01*
X9917Y-610008D01*
X9368Y-610428D01*
X8585Y-610638D01*
X7802Y-610428D01*
X7253Y-610008D01*
X6783Y-609378D01*
X6470Y-608643D01*
X6313Y-607803D01*
Y-607068D01*
X6470Y-606438D01*
X6783Y-605703D01*
X7253Y-605073D01*
X7723Y-604653D01*
X8350Y-604338D01*
X8898D01*
X9525Y-604548D01*
X9995Y-604968D01*
G01X12927Y-604338D02*
Y-608853D01*
X13240Y-609798D01*
X13867Y-610428D01*
X14650Y-610638D01*
X15433Y-610428D01*
X16060Y-609798D01*
X16373Y-608853D01*
Y-604338D01*
G01X20010D02*
X21890D01*
G01X20950D02*
Y-610638D01*
G01X20010D02*
X21890D01*
G01X25605Y-609798D02*
X26232Y-610323D01*
X26937Y-610638D01*
X27563D01*
X28190Y-610323D01*
X28660Y-609798D01*
X28895Y-609063D01*
X28738Y-608328D01*
X28347Y-607698D01*
X27642Y-607278D01*
X26702Y-607068D01*
X26153Y-606648D01*
X25918Y-605913D01*
X26075Y-605178D01*
X26467Y-604653D01*
X27015Y-604338D01*
X27563D01*
X28112Y-604548D01*
X28582Y-605073D01*
G01X31905Y-610638D02*
Y-604338D01*
G01X35195D02*
Y-610638D01*
G01Y-607488D02*
X31905D01*
G01X37892Y-610638D02*
X39850Y-604338D01*
X41808Y-610638D01*
G01X41103Y-608433D02*
X38597D01*
G01X44348Y-610638D02*
Y-604338D01*
X47952Y-610638D01*
Y-604338D01*
G01X57027Y-610638D02*
Y-604338D01*
X58593D01*
X59220Y-604653D01*
X59690Y-605073D01*
X60082Y-605703D01*
X60395Y-606438D01*
X60473Y-607488D01*
X60395Y-608538D01*
X60082Y-609273D01*
X59690Y-609903D01*
X59220Y-610323D01*
X58593Y-610638D01*
X57027D01*
G01X64110Y-604338D02*
X65990D01*
G01X65050D02*
Y-610638D01*
G01X64110D02*
X65990D01*
G01X69705Y-609798D02*
X70332Y-610323D01*
X71037Y-610638D01*
X71663D01*
X72290Y-610323D01*
X72760Y-609798D01*
X72995Y-609063D01*
X72838Y-608328D01*
X72447Y-607698D01*
X71742Y-607278D01*
X70802Y-607068D01*
X70253Y-606648D01*
X70018Y-605913D01*
X70175Y-605178D01*
X70567Y-604653D01*
X71115Y-604338D01*
X71663D01*
X72212Y-604548D01*
X72682Y-605073D01*
G01X77650Y-604338D02*
Y-610638D01*
G01X75848Y-604338D02*
X79452D01*
G01X83950Y-610848D02*
X83793Y-610743D01*
Y-610533D01*
X83950Y-610428D01*
X84107Y-610533D01*
Y-610743D01*
X83950Y-610848D01*
G01X90093Y-611793D02*
X90407Y-610428D01*
G01X96550Y-604338D02*
Y-610638D01*
G01X94748Y-604338D02*
X98352D01*
G01X100892Y-610638D02*
X102850Y-604338D01*
X104808Y-610638D01*
G01X104103Y-608433D02*
X101597D01*
G01X109150Y-610638D02*
X108523Y-610533D01*
X107975Y-610113D01*
X107505Y-609483D01*
X107192Y-608748D01*
X107035Y-607908D01*
Y-607068D01*
X107192Y-606228D01*
X107505Y-605493D01*
X107975Y-604863D01*
X108523Y-604443D01*
X109150Y-604338D01*
X109777Y-604443D01*
X110325Y-604863D01*
X110795Y-605493D01*
X111108Y-606228D01*
X111265Y-607068D01*
Y-607908D01*
X111108Y-608748D01*
X110795Y-609483D01*
X110325Y-610113D01*
X109777Y-610533D01*
X109150Y-610638D01*
G01X115450D02*
Y-607803D01*
X113883Y-604338D01*
G01X117017D02*
X115450Y-607803D01*
G01X120027Y-604338D02*
Y-608853D01*
X120340Y-609798D01*
X120967Y-610428D01*
X121750Y-610638D01*
X122533Y-610428D01*
X123160Y-609798D01*
X123473Y-608853D01*
Y-604338D01*
G01X126092Y-610638D02*
X128050Y-604338D01*
X130008Y-610638D01*
G01X129303Y-608433D02*
X126797D01*
G01X132548Y-610638D02*
Y-604338D01*
X136152Y-610638D01*
Y-604338D01*
G01X10073Y-614863D02*
X9603Y-614548D01*
X9055Y-614338D01*
X8428D01*
X7723Y-614653D01*
X7175Y-615178D01*
X6783Y-615808D01*
X6470Y-616858D01*
X6392Y-617803D01*
X6548Y-618748D01*
X6783Y-619378D01*
X7253Y-620008D01*
X7802Y-620428D01*
X8350Y-620638D01*
X8898D01*
X9447Y-620428D01*
X9917Y-620113D01*
X10308Y-619693D01*
G01X13710Y-614338D02*
X15590D01*
G01X14650D02*
Y-620638D01*
G01X13710D02*
X15590D01*
G01X20950Y-614338D02*
Y-620638D01*
G01X19148Y-614338D02*
X22752D01*
G01X27250Y-620638D02*
Y-617803D01*
X25683Y-614338D01*
G01X28817D02*
X27250Y-617803D01*
G01X38127Y-619378D02*
X38597Y-620113D01*
X39223Y-620533D01*
X39928Y-620638D01*
X40555Y-620533D01*
X41182Y-620008D01*
X41573Y-619378D01*
X41652Y-618748D01*
X41495Y-618013D01*
X40947Y-617488D01*
X40398Y-617278D01*
X39693D01*
G01X40398D02*
X40868Y-616963D01*
X41260Y-616438D01*
X41417Y-615808D01*
X41260Y-615178D01*
X40868Y-614653D01*
X40163Y-614338D01*
X39458Y-614443D01*
X38753Y-614863D01*
G01X44427Y-619378D02*
X44897Y-620113D01*
X45523Y-620533D01*
X46228Y-620638D01*
X46855Y-620533D01*
X47482Y-620008D01*
X47873Y-619378D01*
X47952Y-618748D01*
X47795Y-618013D01*
X47247Y-617488D01*
X46698Y-617278D01*
X45993D01*
G01X46698D02*
X47168Y-616963D01*
X47560Y-616438D01*
X47717Y-615808D01*
X47560Y-615178D01*
X47168Y-614653D01*
X46463Y-614338D01*
X45758Y-614443D01*
X45053Y-614863D01*
G01X50727Y-619378D02*
X51197Y-620113D01*
X51823Y-620533D01*
X52528Y-620638D01*
X53155Y-620533D01*
X53782Y-620008D01*
X54173Y-619378D01*
X54252Y-618748D01*
X54095Y-618013D01*
X53547Y-617488D01*
X52998Y-617278D01*
X52293D01*
G01X52998D02*
X53468Y-616963D01*
X53860Y-616438D01*
X54017Y-615808D01*
X53860Y-615178D01*
X53468Y-614653D01*
X52763Y-614338D01*
X52058Y-614443D01*
X51353Y-614863D01*
G01X58593Y-620638D02*
X58750Y-619273D01*
X58985Y-618118D01*
X59298Y-617068D01*
X59690Y-615913D01*
X60317Y-614338D01*
X57183D01*
G01X64893Y-620638D02*
X65050Y-619273D01*
X65285Y-618118D01*
X65598Y-617068D01*
X65990Y-615913D01*
X66617Y-614338D01*
X63483D01*
G01X71193Y-621793D02*
X71507Y-620428D01*
G01X77650Y-614338D02*
Y-620638D01*
G01X75848Y-614338D02*
X79452D01*
G01X81992Y-620638D02*
X83950Y-614338D01*
X85908Y-620638D01*
G01X85203Y-618433D02*
X82697D01*
G01X89310Y-614338D02*
X91190D01*
G01X90250D02*
Y-620638D01*
G01X89310D02*
X91190D01*
G01X94200Y-614338D02*
X95297Y-620638D01*
X96550Y-614338D01*
X97803Y-620638D01*
X98900Y-614338D01*
G01X100892Y-620638D02*
X102850Y-614338D01*
X104808Y-620638D01*
G01X104103Y-618433D02*
X101597D01*
G01X107348Y-620638D02*
Y-614338D01*
X110952Y-620638D01*
Y-614338D01*
G01X121358Y-622738D02*
X120575Y-621688D01*
X120183Y-620638D01*
Y-616438D01*
X120575Y-615388D01*
X121358Y-614338D01*
G01X132783Y-620638D02*
Y-614338D01*
X134742D01*
X135368Y-614653D01*
X135760Y-615073D01*
X135917Y-615913D01*
X135760Y-616753D01*
X135290Y-617278D01*
X134742Y-617593D01*
X132783D01*
G01X134742D02*
X135917Y-620638D01*
G01X140650Y-620848D02*
X140493Y-620743D01*
Y-620533D01*
X140650Y-620428D01*
X140807Y-620533D01*
Y-620743D01*
X140650Y-620848D01*
G01X146950Y-620638D02*
X146323Y-620533D01*
X145775Y-620113D01*
X145305Y-619483D01*
X144992Y-618748D01*
X144835Y-617908D01*
Y-617068D01*
X144992Y-616228D01*
X145305Y-615493D01*
X145775Y-614863D01*
X146323Y-614443D01*
X146950Y-614338D01*
X147577Y-614443D01*
X148125Y-614863D01*
X148595Y-615493D01*
X148908Y-616228D01*
X149065Y-617068D01*
Y-617908D01*
X148908Y-618748D01*
X148595Y-619483D01*
X148125Y-620113D01*
X147577Y-620533D01*
X146950Y-620638D01*
G01X153250Y-620848D02*
X153093Y-620743D01*
Y-620533D01*
X153250Y-620428D01*
X153407Y-620533D01*
Y-620743D01*
X153250Y-620848D01*
G01X161273Y-614863D02*
X160803Y-614548D01*
X160255Y-614338D01*
X159628D01*
X158923Y-614653D01*
X158375Y-615178D01*
X157983Y-615808D01*
X157670Y-616858D01*
X157592Y-617803D01*
X157748Y-618748D01*
X157983Y-619378D01*
X158453Y-620008D01*
X159002Y-620428D01*
X159550Y-620638D01*
X160098D01*
X160647Y-620428D01*
X161117Y-620113D01*
X161508Y-619693D01*
G01X165850Y-620848D02*
X165693Y-620743D01*
Y-620533D01*
X165850Y-620428D01*
X166007Y-620533D01*
Y-620743D01*
X165850Y-620848D01*
G01X172542Y-622738D02*
X173325Y-621688D01*
X173717Y-620638D01*
Y-616438D01*
X173325Y-615388D01*
X172542Y-614338D01*
G01X6548Y-600638D02*
Y-594338D01*
X10152Y-600638D01*
Y-594338D01*
G01X14650Y-600638D02*
X14023Y-600533D01*
X13475Y-600113D01*
X13005Y-599483D01*
X12692Y-598748D01*
X12535Y-597908D01*
Y-597068D01*
X12692Y-596228D01*
X13005Y-595493D01*
X13475Y-594863D01*
X14023Y-594443D01*
X14650Y-594338D01*
X15277Y-594443D01*
X15825Y-594863D01*
X16295Y-595493D01*
X16608Y-596228D01*
X16765Y-597068D01*
Y-597908D01*
X16608Y-598748D01*
X16295Y-599483D01*
X15825Y-600113D01*
X15277Y-600533D01*
X14650Y-600638D01*
G01X20950Y-600848D02*
X20793Y-600743D01*
Y-600533D01*
X20950Y-600428D01*
X21107Y-600533D01*
Y-600743D01*
X20950Y-600848D01*
G01X25762Y-595388D02*
X26232Y-594758D01*
X26780Y-594443D01*
X27407Y-594338D01*
X28190Y-594548D01*
X28738Y-595073D01*
X28895Y-595703D01*
X28817Y-596333D01*
X28503Y-596858D01*
X26937Y-597908D01*
X26232Y-598643D01*
X25762Y-599693D01*
X25605Y-600638D01*
X28895D01*
G01X33550D02*
Y-594338D01*
X32610Y-595598D01*
G01Y-600638D02*
X34490D01*
G01X39850D02*
Y-594338D01*
X38910Y-595598D01*
G01Y-600638D02*
X40790D01*
G01X45993Y-601793D02*
X46307Y-600428D01*
G01X50100Y-594338D02*
X51197Y-600638D01*
X52450Y-594338D01*
X53703Y-600638D01*
X54800Y-594338D01*
G01X60317Y-600638D02*
X57183D01*
Y-594338D01*
X60317D01*
G01X59063Y-597383D02*
X57183D01*
G01X63248Y-600638D02*
Y-594338D01*
X66852Y-600638D01*
Y-594338D01*
G01X69705Y-600638D02*
Y-594338D01*
G01X72995D02*
Y-600638D01*
G01Y-597488D02*
X69705D01*
G01X75927Y-594338D02*
Y-598853D01*
X76240Y-599798D01*
X76867Y-600428D01*
X77650Y-600638D01*
X78433Y-600428D01*
X79060Y-599798D01*
X79373Y-598853D01*
Y-594338D01*
G01X81992Y-600638D02*
X83950Y-594338D01*
X85908Y-600638D01*
G01X85203Y-598433D02*
X82697D01*
G01X95062Y-595388D02*
X95532Y-594758D01*
X96080Y-594443D01*
X96707Y-594338D01*
X97490Y-594548D01*
X98038Y-595073D01*
X98195Y-595703D01*
X98117Y-596333D01*
X97803Y-596858D01*
X96237Y-597908D01*
X95532Y-598643D01*
X95062Y-599693D01*
X94905Y-600638D01*
X98195D01*
G01X101048D02*
Y-594338D01*
X104652Y-600638D01*
Y-594338D01*
G01X107427Y-600638D02*
Y-594338D01*
X108993D01*
X109620Y-594653D01*
X110090Y-595073D01*
X110482Y-595703D01*
X110795Y-596438D01*
X110873Y-597488D01*
X110795Y-598538D01*
X110482Y-599273D01*
X110090Y-599903D01*
X109620Y-600323D01*
X108993Y-600638D01*
X107427D01*
G01X120183D02*
Y-594338D01*
X122142D01*
X122768Y-594653D01*
X123160Y-595073D01*
X123317Y-595913D01*
X123160Y-596753D01*
X122690Y-597278D01*
X122142Y-597593D01*
X120183D01*
G01X122142D02*
X123317Y-600638D01*
G01X126327D02*
Y-594338D01*
X127893D01*
X128520Y-594653D01*
X128990Y-595073D01*
X129382Y-595703D01*
X129695Y-596438D01*
X129773Y-597488D01*
X129695Y-598538D01*
X129382Y-599273D01*
X128990Y-599903D01*
X128520Y-600323D01*
X127893Y-600638D01*
X126327D01*
G01X134350Y-600848D02*
X134193Y-600743D01*
Y-600533D01*
X134350Y-600428D01*
X134507Y-600533D01*
Y-600743D01*
X134350Y-600848D01*
G01X57768Y1424257D02*
G02I-25950J0D01*
G01X30650Y-589938D02*
X28130Y-589521D01*
X25925Y-587855D01*
X24035Y-585355D01*
X22775Y-582438D01*
X22145Y-579105D01*
Y-575771D01*
X22775Y-572438D01*
X24035Y-569521D01*
X25925Y-567022D01*
X28130Y-565355D01*
X30650Y-564938D01*
X33170Y-565355D01*
X35375Y-567022D01*
X37265Y-569521D01*
X38525Y-572438D01*
X39155Y-575771D01*
Y-579105D01*
X38525Y-582438D01*
X37265Y-585355D01*
X35375Y-587855D01*
X33170Y-589521D01*
X30650Y-589938D01*
G01X33170Y-583271D02*
X36950Y-589938D01*
G01X50495Y-573272D02*
Y-584938D01*
X51755Y-587855D01*
X53645Y-589521D01*
X55850Y-589938D01*
X58055Y-589521D01*
X59945Y-587855D01*
X61205Y-584938D01*
G01Y-589938D02*
Y-573272D01*
G01X86720Y-589938D02*
Y-573272D01*
G01Y-576188D02*
X85460Y-574522D01*
X83570Y-573688D01*
X81365Y-573272D01*
X79160Y-574105D01*
X77270Y-575771D01*
X76010Y-578272D01*
X75380Y-581605D01*
X76010Y-584938D01*
X77270Y-587439D01*
X79160Y-589105D01*
X81365Y-589938D01*
X83570Y-589521D01*
X85460Y-588272D01*
X86720Y-586605D01*
G01X100895Y-589938D02*
Y-573272D01*
G01Y-577438D02*
X102155Y-575355D01*
X104045Y-573688D01*
X106565Y-573272D01*
X108770Y-573688D01*
X110660Y-575355D01*
X111605Y-578272D01*
Y-589938D01*
G01X131450Y-564938D02*
Y-589938D01*
G01X127040Y-573272D02*
X135860D01*
G01X162320Y-589938D02*
Y-573272D01*
G01Y-576188D02*
X161060Y-574522D01*
X159170Y-573688D01*
X156965Y-573272D01*
X154760Y-574105D01*
X152870Y-575771D01*
X151610Y-578272D01*
X150980Y-581605D01*
X151610Y-584938D01*
X152870Y-587439D01*
X154760Y-589105D01*
X156965Y-589938D01*
X159170Y-589521D01*
X161060Y-588272D01*
X162320Y-586605D01*
G01X18837Y147858D02*
G02X69950Y154200I25163J6342D01*
G01X19500Y1450913D02*
Y1448487D01*
G01X13000Y1456883D02*
X16100D01*
Y1457803D01*
X15945Y1458110D01*
X15583Y1458340D01*
X15170Y1458417D01*
X14757Y1458340D01*
X14447Y1458148D01*
X14292Y1457803D01*
Y1456883D01*
G01X15842Y1461593D02*
X15997Y1461363D01*
X16100Y1461095D01*
Y1460788D01*
X15945Y1460443D01*
X15687Y1460175D01*
X15377Y1459983D01*
X14860Y1459830D01*
X14395Y1459792D01*
X13930Y1459868D01*
X13620Y1459983D01*
X13310Y1460213D01*
X13103Y1460482D01*
X13000Y1460750D01*
Y1461018D01*
X13103Y1461287D01*
X13258Y1461517D01*
X13465Y1461708D01*
G01X14292Y1463122D02*
X14653Y1463390D01*
X14860Y1463620D01*
X14963Y1463927D01*
X14860Y1464195D01*
X14653Y1464387D01*
X14343Y1464540D01*
X13982Y1464578D01*
X13672Y1464540D01*
X13362Y1464387D01*
X13103Y1464157D01*
X13000Y1463888D01*
X13103Y1463582D01*
X13413Y1463313D01*
X13878Y1463160D01*
X14395Y1463122D01*
X15067Y1463198D01*
X15428Y1463313D01*
X15790Y1463505D01*
X16048Y1463773D01*
X16100Y1464042D01*
X15997Y1464310D01*
X15738Y1464502D01*
G01X14292Y1466222D02*
X14653Y1466490D01*
X14860Y1466720D01*
X14963Y1467027D01*
X14860Y1467295D01*
X14653Y1467487D01*
X14343Y1467640D01*
X13982Y1467678D01*
X13672Y1467640D01*
X13362Y1467487D01*
X13103Y1467257D01*
X13000Y1466988D01*
X13103Y1466682D01*
X13413Y1466413D01*
X13878Y1466260D01*
X14395Y1466222D01*
X15067Y1466298D01*
X15428Y1466413D01*
X15790Y1466605D01*
X16048Y1466873D01*
X16100Y1467142D01*
X15997Y1467410D01*
X15738Y1467602D01*
G01X15583Y1469322D02*
X15893Y1469552D01*
X16048Y1469820D01*
X16100Y1470127D01*
X15997Y1470510D01*
X15738Y1470778D01*
X15428Y1470855D01*
X15118Y1470817D01*
X14860Y1470663D01*
X14343Y1469897D01*
X13982Y1469552D01*
X13465Y1469322D01*
X13000Y1469245D01*
Y1470855D01*
G01Y1473150D02*
X13052Y1473418D01*
X13207Y1473725D01*
X13465Y1473917D01*
X13827Y1473993D01*
X14188Y1473917D01*
X14498Y1473687D01*
X14653Y1473342D01*
Y1472958D01*
X14757Y1472728D01*
X15015Y1472537D01*
X15377Y1472460D01*
X15738Y1472575D01*
X15997Y1472843D01*
X16100Y1473150D01*
X15997Y1473457D01*
X15738Y1473725D01*
X15377Y1473840D01*
X15015Y1473763D01*
X14757Y1473572D01*
X14653Y1473342D01*
Y1472958D01*
X14498Y1472613D01*
X14188Y1472383D01*
X13827Y1472307D01*
X13465Y1472383D01*
X13207Y1472575D01*
X13052Y1472882D01*
X13000Y1473150D01*
G01X17716Y1487711D02*
Y1454800D01*
G01X18500Y1451971D02*
X34646D01*
G01X25729Y1492536D02*
Y1490296D01*
G01X24104Y1491509D02*
X27354D01*
G01X17714Y1487711D02*
X34654Y1487714D01*
G01X17714Y1488311D02*
X34689Y1488315D01*
G01X17714Y1488911D02*
X34697Y1488905D01*
G01X17714Y1488911D02*
Y1487711D01*
G01X34646D02*
X17716D01*
G01X69950Y154200D02*
G02X27080Y134525I-25950J0D01*
G01X34900Y316400D02*
X38100D01*
G01X34900Y322600D02*
Y316400D01*
G01X38100Y322600D02*
X34900D01*
G01X34600D02*
X31400D01*
G01X34600Y316400D02*
Y322600D01*
G01X31400Y316400D02*
X34600D01*
G01X31400Y322600D02*
Y316400D01*
G01X35355Y439530D02*
Y442730D01*
G01X29155Y439530D02*
X35355D01*
G01X29155Y442730D02*
Y439530D01*
G01X35355Y442730D02*
X29155D01*
G01X35355Y447119D02*
X29155D01*
G01X35355Y443919D02*
Y447119D01*
G01X29155Y443919D02*
X35355D01*
G01X29155Y447119D02*
Y443919D01*
G01X36861Y542285D02*
Y536285D01*
G01D02*
X48861D01*
G01Y542285D02*
X36861D01*
G01X36112Y543805D02*
Y550205D01*
G01Y543805D02*
X48992D01*
G01Y550205D02*
X36112D01*
G01X36500Y1456383D02*
X39600D01*
Y1457303D01*
X39445Y1457610D01*
X39083Y1457840D01*
X38670Y1457917D01*
X38257Y1457840D01*
X37947Y1457648D01*
X37792Y1457303D01*
Y1456383D01*
G01X39342Y1461093D02*
X39497Y1460863D01*
X39600Y1460595D01*
Y1460288D01*
X39445Y1459943D01*
X39187Y1459675D01*
X38877Y1459483D01*
X38360Y1459330D01*
X37895Y1459292D01*
X37430Y1459368D01*
X37120Y1459483D01*
X36810Y1459713D01*
X36603Y1459982D01*
X36500Y1460250D01*
Y1460518D01*
X36603Y1460787D01*
X36758Y1461017D01*
X36965Y1461208D01*
G01X37792Y1462622D02*
X38153Y1462890D01*
X38360Y1463120D01*
X38463Y1463427D01*
X38360Y1463695D01*
X38153Y1463887D01*
X37843Y1464040D01*
X37482Y1464078D01*
X37172Y1464040D01*
X36862Y1463887D01*
X36603Y1463657D01*
X36500Y1463388D01*
X36603Y1463082D01*
X36913Y1462813D01*
X37378Y1462660D01*
X37895Y1462622D01*
X38567Y1462698D01*
X38928Y1462813D01*
X39290Y1463005D01*
X39548Y1463273D01*
X39600Y1463542D01*
X39497Y1463810D01*
X39238Y1464002D01*
G01X37792Y1465722D02*
X38153Y1465990D01*
X38360Y1466220D01*
X38463Y1466527D01*
X38360Y1466795D01*
X38153Y1466987D01*
X37843Y1467140D01*
X37482Y1467178D01*
X37172Y1467140D01*
X36862Y1466987D01*
X36603Y1466757D01*
X36500Y1466488D01*
X36603Y1466182D01*
X36913Y1465913D01*
X37378Y1465760D01*
X37895Y1465722D01*
X38567Y1465798D01*
X38928Y1465913D01*
X39290Y1466105D01*
X39548Y1466373D01*
X39600Y1466642D01*
X39497Y1466910D01*
X39238Y1467102D01*
G01X39083Y1468822D02*
X39393Y1469052D01*
X39548Y1469320D01*
X39600Y1469627D01*
X39497Y1470010D01*
X39238Y1470278D01*
X38928Y1470355D01*
X38618Y1470317D01*
X38360Y1470163D01*
X37843Y1469397D01*
X37482Y1469052D01*
X36965Y1468822D01*
X36500Y1468745D01*
Y1470355D01*
G01X37792Y1471922D02*
X38153Y1472190D01*
X38360Y1472420D01*
X38463Y1472727D01*
X38360Y1472995D01*
X38153Y1473187D01*
X37843Y1473340D01*
X37482Y1473378D01*
X37172Y1473340D01*
X36862Y1473187D01*
X36603Y1472957D01*
X36500Y1472688D01*
X36603Y1472382D01*
X36913Y1472113D01*
X37378Y1471960D01*
X37895Y1471922D01*
X38567Y1471998D01*
X38928Y1472113D01*
X39290Y1472305D01*
X39548Y1472573D01*
X39600Y1472842D01*
X39497Y1473110D01*
X39238Y1473302D01*
G01X34646Y1451971D02*
Y1487711D01*
G01X39210Y1488567D02*
Y1486327D01*
G01X37585Y1487540D02*
X40835D01*
G01X34647Y1488861D02*
X34643Y1487352D01*
G01X27700Y1502900D02*
X32300D01*
G01X27700Y1513100D02*
Y1502900D01*
G01X32300D02*
Y1513100D01*
G01X33147Y1502077D02*
X39147D01*
G01X33147Y1514077D02*
Y1502077D01*
G01X32300Y1513100D02*
X27700D01*
G01X39147Y1514077D02*
X33147D01*
G01X36533Y1600496D02*
Y1597296D01*
G01X42733Y1600496D02*
X36533D01*
G01Y1597296D02*
X42733D01*
G01X36533Y1601796D02*
X42733D01*
G01X36533Y1604996D02*
Y1601796D01*
G01X42733Y1604996D02*
X36533D01*
G01Y1621596D02*
X42733D01*
G01X36533Y1624796D02*
Y1621596D01*
G01X42733Y1624796D02*
X36533D01*
G01X38100Y316400D02*
Y322600D01*
G01X38400Y316400D02*
X41600D01*
G01X38400Y322600D02*
Y316400D01*
G01X41600Y322600D02*
X38400D01*
G01X41600Y316400D02*
Y322600D01*
G01X45100D02*
X41900D01*
G01X45100Y316400D02*
Y322600D01*
G01X41900Y316400D02*
X45100D01*
G01X41900Y322600D02*
Y316400D01*
G01X50191Y385393D02*
Y388593D01*
G01X43991D02*
Y385393D01*
G01X50191Y388593D02*
X43991D01*
G01Y385393D02*
X50191D01*
G01X50358Y391808D02*
Y395008D01*
G01X44158D02*
Y391808D01*
G01X50358Y395008D02*
X44158D01*
G01Y391808D02*
X50358D01*
G01X49540Y447102D02*
X52446D01*
G01Y437302D02*
X49880D01*
G01X42646Y447102D02*
X45660D01*
G01X42646Y437302D02*
Y447102D01*
G01X45210Y437302D02*
X42646D01*
G01X54643Y457665D02*
Y455443D01*
X54490Y454978D01*
X54183Y454668D01*
X53800Y454565D01*
X53417Y454668D01*
X53110Y454978D01*
X52957Y455443D01*
Y457665D01*
G01X51543Y455030D02*
X51313Y454772D01*
X51045Y454617D01*
X50700Y454565D01*
X50355Y454668D01*
X50087Y454875D01*
X49895Y455237D01*
X49857Y455650D01*
X49933Y456063D01*
X50125Y456322D01*
X50393Y456528D01*
X50662Y456580D01*
X50930Y456528D01*
X51275Y456322D01*
X51160Y457665D01*
X50125D01*
G01X48328Y457148D02*
X48098Y457458D01*
X47830Y457613D01*
X47523Y457665D01*
X47140Y457562D01*
X46872Y457303D01*
X46795Y456993D01*
X46833Y456683D01*
X46987Y456425D01*
X47753Y455908D01*
X48098Y455547D01*
X48328Y455030D01*
X48405Y454565D01*
X46795D01*
G01X44500Y457665D02*
X44807Y457562D01*
X45037Y457303D01*
X45190Y456993D01*
X45305Y456580D01*
X45343Y456115D01*
X45305Y455650D01*
X45190Y455237D01*
X45037Y454927D01*
X44807Y454668D01*
X44500Y454565D01*
X44193Y454668D01*
X43963Y454927D01*
X43810Y455237D01*
X43695Y455650D01*
X43657Y456115D01*
X43695Y456580D01*
X43810Y456993D01*
X43963Y457303D01*
X44193Y457562D01*
X44500Y457665D01*
G01X41400Y454565D02*
Y457665D01*
X41860Y457045D01*
G01Y454565D02*
X40940D01*
G01X44502Y518775D02*
X47702D01*
G01X44502Y524975D02*
Y518775D01*
G01X47702D02*
Y524975D01*
G01D02*
X44502D01*
G01X44244Y529904D02*
Y526704D01*
G01X50444Y529904D02*
X44244D01*
G01X50444Y526704D02*
Y529904D01*
G01X44244Y526704D02*
X50444D01*
G01X44382Y535585D02*
Y532385D01*
G01X50582Y535585D02*
X44382D01*
G01X50582Y532385D02*
Y535585D01*
G01X44382Y532385D02*
X50582D01*
G01X48861Y536285D02*
Y542285D01*
G01X48992Y543805D02*
Y550205D01*
G01X50584Y1451273D02*
Y1448847D01*
G01X41616Y1451971D02*
X58546D01*
G01X41616Y1487711D02*
Y1451971D01*
G01X41614Y1487711D02*
X58554Y1487714D01*
G01X41614Y1488311D02*
X58589Y1488315D01*
G01X41614Y1488911D02*
X58597Y1488905D01*
G01X41614Y1488911D02*
Y1487711D01*
G01X58546D02*
X41616D01*
G01X64925Y1492125D02*
X47985Y1492122D01*
G01X64925Y1491525D02*
X47950Y1491521D01*
G01X64925Y1490925D02*
X47942Y1490931D01*
G01X47992Y1490975D02*
X47996Y1492484D01*
G01X47993Y1492125D02*
X64923D01*
G01X47993Y1527865D02*
Y1492125D01*
G01X39147Y1502077D02*
Y1514077D01*
G01X45955Y1502077D02*
Y1514077D01*
G01X39955Y1502077D02*
X45955D01*
G01X39955Y1514077D02*
Y1502077D01*
G01X45955Y1514077D02*
X39955D01*
G01X49653Y1530469D02*
X52853D01*
G01X49653Y1536669D02*
Y1530469D01*
G01X52853Y1536669D02*
X49653D01*
G01X42500Y1522883D02*
X45600D01*
Y1523803D01*
X45445Y1524110D01*
X45083Y1524340D01*
X44670Y1524417D01*
X44257Y1524340D01*
X43947Y1524148D01*
X43792Y1523803D01*
Y1522883D01*
G01X45342Y1527593D02*
X45497Y1527363D01*
X45600Y1527095D01*
Y1526788D01*
X45445Y1526443D01*
X45187Y1526175D01*
X44877Y1525983D01*
X44360Y1525830D01*
X43895Y1525792D01*
X43430Y1525868D01*
X43120Y1525983D01*
X42810Y1526213D01*
X42603Y1526482D01*
X42500Y1526750D01*
Y1527018D01*
X42603Y1527287D01*
X42758Y1527517D01*
X42965Y1527708D01*
G01X43792Y1529122D02*
X44153Y1529390D01*
X44360Y1529620D01*
X44463Y1529927D01*
X44360Y1530195D01*
X44153Y1530387D01*
X43843Y1530540D01*
X43482Y1530578D01*
X43172Y1530540D01*
X42862Y1530387D01*
X42603Y1530157D01*
X42500Y1529888D01*
X42603Y1529582D01*
X42913Y1529313D01*
X43378Y1529160D01*
X43895Y1529122D01*
X44567Y1529198D01*
X44928Y1529313D01*
X45290Y1529505D01*
X45548Y1529773D01*
X45600Y1530042D01*
X45497Y1530310D01*
X45238Y1530502D01*
G01X42500Y1532950D02*
X42552Y1533218D01*
X42707Y1533525D01*
X42965Y1533717D01*
X43327Y1533793D01*
X43688Y1533717D01*
X43998Y1533487D01*
X44153Y1533142D01*
Y1532758D01*
X44257Y1532528D01*
X44515Y1532337D01*
X44877Y1532260D01*
X45238Y1532375D01*
X45497Y1532643D01*
X45600Y1532950D01*
X45497Y1533257D01*
X45238Y1533525D01*
X44877Y1533640D01*
X44515Y1533563D01*
X44257Y1533372D01*
X44153Y1533142D01*
Y1532758D01*
X43998Y1532413D01*
X43688Y1532183D01*
X43327Y1532107D01*
X42965Y1532183D01*
X42707Y1532375D01*
X42552Y1532682D01*
X42500Y1532950D01*
G01Y1536050D02*
X45600D01*
X44980Y1535590D01*
G01X42500D02*
Y1536510D01*
G01X43120Y1538307D02*
X42758Y1538537D01*
X42552Y1538843D01*
X42500Y1539188D01*
X42552Y1539495D01*
X42810Y1539802D01*
X43120Y1539993D01*
X43430Y1540032D01*
X43792Y1539955D01*
X44050Y1539687D01*
X44153Y1539418D01*
Y1539073D01*
G01Y1539418D02*
X44308Y1539648D01*
X44567Y1539840D01*
X44877Y1539917D01*
X45187Y1539840D01*
X45445Y1539648D01*
X45600Y1539303D01*
X45548Y1538958D01*
X45342Y1538613D01*
G01X64923Y1527865D02*
X47993D01*
G01X50675Y1591581D02*
Y1588381D01*
G01X56875Y1591581D02*
X50675D01*
G01Y1588381D02*
X56875D01*
G01X50675Y1587581D02*
Y1584381D01*
G01X56875Y1587581D02*
X50675D01*
G01Y1584381D02*
X56875D01*
G01X40333Y1608996D02*
Y1615196D01*
G01X37133Y1608996D02*
X40333D01*
G01X37133Y1615196D02*
Y1608996D01*
G01X42733Y1597296D02*
Y1600496D01*
G01Y1601796D02*
Y1604996D01*
G01X49033Y1614296D02*
Y1611096D01*
G01D02*
X55233D01*
G01X40333Y1615196D02*
X37133D01*
G01X42733Y1621596D02*
Y1624796D01*
G01X43567Y1627005D02*
Y1623805D01*
G01X49767D02*
Y1627005D01*
G01X43567Y1623805D02*
X49767D01*
G01X55233Y1614296D02*
X49033D01*
G01X49767Y1627005D02*
X43567D01*
G01X49767Y1634505D02*
X46567D01*
G01X49767Y1628305D02*
Y1634505D01*
G01X46567Y1628305D02*
X49767D01*
G01X46567Y1634505D02*
Y1628305D01*
G01X66997Y386228D02*
X63797D01*
G01Y380028D02*
X66997D01*
G01X63797Y386228D02*
Y380028D01*
G01X60713Y386862D02*
X66913D01*
G01X60713Y390062D02*
Y386862D01*
G01X59144Y401596D02*
X55944D01*
G01X59144Y395396D02*
Y401596D01*
G01X55944Y395396D02*
X59144D01*
G01X55944Y401596D02*
Y395396D01*
G01X55338Y401570D02*
X52138D01*
G01X55338Y395370D02*
Y401570D01*
G01X52138Y395370D02*
X55338D01*
G01X52138Y401570D02*
Y395370D01*
G01X60711Y391479D02*
X66911D01*
G01X60711Y394679D02*
Y391479D01*
G01X66911Y394679D02*
X60711D01*
G01X66913Y390062D02*
X60713D01*
G01X58322Y440126D02*
X55122D01*
G01X58322Y433926D02*
Y440126D01*
G01X55122Y433926D02*
X58322D01*
G01X55122Y440126D02*
Y433926D01*
G01X62361Y433859D02*
Y440059D01*
G01D02*
X59161D01*
G01Y433859D02*
X62361D01*
G01X59161Y440059D02*
Y433859D01*
G01X60828Y445277D02*
Y442077D01*
G01X67028Y445277D02*
X60828D01*
G01Y442077D02*
X67028D01*
G01X52446Y447102D02*
Y437302D01*
G01X62422Y519695D02*
Y525895D01*
G01X59222Y519695D02*
X62422D01*
G01X59222Y525895D02*
Y519695D01*
G01X62422Y525895D02*
X59222D01*
G01X62322Y529805D02*
X56122D01*
G01D02*
Y526605D01*
G01D02*
X62322D01*
G01D02*
Y529805D01*
G01X52142Y536365D02*
Y530165D01*
G01D02*
X55342D01*
G01D02*
Y536365D01*
G01D02*
X52142D01*
G01X59172Y530315D02*
X62372D01*
G01Y536515D02*
X59172D01*
G01X62372Y530315D02*
Y536515D01*
G01X59172D02*
Y530315D01*
G01X53903Y754232D02*
X57103D01*
G01X53903Y760432D02*
Y754232D01*
G01X57103Y760432D02*
X53903D01*
G01X57103Y754232D02*
Y760432D01*
G01X61103D02*
X57903D01*
G01X61103Y754232D02*
Y760432D01*
G01X57903Y754232D02*
X61103D01*
G01X57903Y760432D02*
Y754232D01*
G01X63323Y755505D02*
X75323D01*
G01X63323Y761505D02*
Y755505D01*
G01X75323Y761505D02*
X63323D01*
G01X63559Y772304D02*
X66759D01*
G01X63559Y778504D02*
Y772304D01*
G01X66759D02*
Y778504D01*
G01D02*
X63559D01*
G01X61000Y1455883D02*
X64100D01*
Y1456803D01*
X63945Y1457110D01*
X63583Y1457340D01*
X63170Y1457417D01*
X62757Y1457340D01*
X62447Y1457148D01*
X62292Y1456803D01*
Y1455883D01*
G01X63842Y1460593D02*
X63997Y1460363D01*
X64100Y1460095D01*
Y1459788D01*
X63945Y1459443D01*
X63687Y1459175D01*
X63377Y1458983D01*
X62860Y1458830D01*
X62395Y1458792D01*
X61930Y1458868D01*
X61620Y1458983D01*
X61310Y1459213D01*
X61103Y1459482D01*
X61000Y1459750D01*
Y1460018D01*
X61103Y1460287D01*
X61258Y1460517D01*
X61465Y1460708D01*
G01X62292Y1462122D02*
X62653Y1462390D01*
X62860Y1462620D01*
X62963Y1462927D01*
X62860Y1463195D01*
X62653Y1463387D01*
X62343Y1463540D01*
X61982Y1463578D01*
X61672Y1463540D01*
X61362Y1463387D01*
X61103Y1463157D01*
X61000Y1462888D01*
X61103Y1462582D01*
X61413Y1462313D01*
X61878Y1462160D01*
X62395Y1462122D01*
X63067Y1462198D01*
X63428Y1462313D01*
X63790Y1462505D01*
X64048Y1462773D01*
X64100Y1463042D01*
X63997Y1463310D01*
X63738Y1463502D01*
G01X62292Y1465222D02*
X62653Y1465490D01*
X62860Y1465720D01*
X62963Y1466027D01*
X62860Y1466295D01*
X62653Y1466487D01*
X62343Y1466640D01*
X61982Y1466678D01*
X61672Y1466640D01*
X61362Y1466487D01*
X61103Y1466257D01*
X61000Y1465988D01*
X61103Y1465682D01*
X61413Y1465413D01*
X61878Y1465260D01*
X62395Y1465222D01*
X63067Y1465298D01*
X63428Y1465413D01*
X63790Y1465605D01*
X64048Y1465873D01*
X64100Y1466142D01*
X63997Y1466410D01*
X63738Y1466602D01*
G01X63583Y1468322D02*
X63893Y1468552D01*
X64048Y1468820D01*
X64100Y1469127D01*
X63997Y1469510D01*
X63738Y1469778D01*
X63428Y1469855D01*
X63118Y1469817D01*
X62860Y1469663D01*
X62343Y1468897D01*
X61982Y1468552D01*
X61465Y1468322D01*
X61000Y1468245D01*
Y1469855D01*
G01Y1472073D02*
X61672Y1472150D01*
X62240Y1472265D01*
X62757Y1472418D01*
X63325Y1472610D01*
X64100Y1472917D01*
Y1471383D01*
G01X65716Y1451971D02*
X82646D01*
G01X65716Y1487711D02*
Y1451971D01*
G01X58546D02*
Y1487711D01*
G01X70410Y1493024D02*
Y1490784D01*
G01X68785Y1491997D02*
X72035D01*
G01X65714Y1487711D02*
X82654Y1487714D01*
G01X65714Y1488311D02*
X82689Y1488315D01*
G01X65714Y1488911D02*
X82697Y1488905D01*
G01X65714Y1488911D02*
Y1487711D01*
G01X82646D02*
X65716D01*
G01X58547Y1488861D02*
X58543Y1487352D01*
G01X61493Y1487270D02*
Y1489510D01*
G01X63118Y1488297D02*
X59868D01*
G01X64925Y1490925D02*
Y1492125D01*
G01X64923D02*
Y1527865D01*
G01X52853Y1530469D02*
Y1536669D01*
G01X60982Y1529439D02*
Y1531865D01*
G01X65022Y1561789D02*
X77022D01*
G01X65022Y1567789D02*
Y1561789D01*
G01X77022Y1560889D02*
X65022D01*
G01Y1554889D02*
X77022D01*
G01X65022Y1560889D02*
Y1554889D01*
G01X64935Y1575558D02*
X76935D01*
G01X64935Y1581558D02*
Y1575558D01*
G01X76935Y1581558D02*
X64935D01*
G01X77022Y1567789D02*
X65022D01*
G01X77022Y1574689D02*
X65022D01*
G01Y1568689D02*
X77022D01*
G01X65022Y1574689D02*
Y1568689D01*
G01X56875Y1588381D02*
Y1591581D01*
G01Y1584381D02*
Y1587581D01*
G01X55233Y1611096D02*
Y1614296D01*
G01X65271Y1599690D02*
X68471D01*
G01X65271Y1605890D02*
Y1599690D01*
G01X68471Y1605890D02*
X65271D01*
G01X52033Y1633296D02*
X55233D01*
G01X52033Y1639496D02*
Y1633296D01*
G01X55233Y1639496D02*
X52033D01*
G01X55233Y1633296D02*
Y1639496D01*
G01X57033Y1633296D02*
X60233D01*
G01X57033Y1639496D02*
Y1633296D01*
G01X60233Y1639496D02*
X57033D01*
G01X60233Y1633296D02*
Y1639496D01*
G01X62527Y1652787D02*
Y1655987D01*
G01X56327Y1652787D02*
X62527D01*
G01X56327Y1655987D02*
Y1652787D01*
G01X62527Y1655987D02*
X56327D01*
G01X64427Y1651887D02*
X52427D01*
G01X64427Y1645887D02*
Y1651887D01*
G01X52427Y1645887D02*
X64427D01*
G01X52427Y1651887D02*
Y1645887D01*
G01X66038Y1662919D02*
X62838D01*
G01Y1656719D02*
X66038D01*
G01X62838Y1662919D02*
Y1656719D01*
G01X66038D02*
Y1662919D01*
G01X78549Y293529D02*
X78187Y293759D01*
X77981Y294065D01*
X77929Y294410D01*
X77981Y294717D01*
X78239Y295024D01*
X78549Y295215D01*
X78859Y295254D01*
X79221Y295177D01*
X79479Y294909D01*
X79582Y294640D01*
Y294295D01*
G01Y294640D02*
X79737Y294870D01*
X79996Y295062D01*
X80306Y295139D01*
X80616Y295062D01*
X80874Y294870D01*
X81029Y294525D01*
X80977Y294180D01*
X80771Y293835D01*
G01X78549Y313963D02*
X78187Y314193D01*
X77981Y314499D01*
X77929Y314844D01*
X77981Y315151D01*
X78239Y315458D01*
X78549Y315649D01*
X78859Y315688D01*
X79221Y315611D01*
X79479Y315343D01*
X79582Y315074D01*
Y314729D01*
G01Y315074D02*
X79737Y315304D01*
X79996Y315496D01*
X80306Y315573D01*
X80616Y315496D01*
X80874Y315304D01*
X81029Y314959D01*
X80977Y314614D01*
X80771Y314269D01*
G01X66997Y380028D02*
Y386228D01*
G01X71598Y386337D02*
X68398D01*
G01X71598Y380137D02*
Y386337D01*
G01X68398Y380137D02*
X71598D01*
G01X68398Y386337D02*
Y380137D01*
G01X66913Y386862D02*
Y390062D01*
G01X75769Y386292D02*
X72569D01*
G01Y380092D02*
X75769D01*
G01X72569Y386292D02*
Y380092D01*
G01X75769D02*
Y386292D01*
G01X66911Y391479D02*
Y394679D01*
G01X67028Y442077D02*
Y445277D01*
G01X91465Y761505D02*
X79465D01*
G01Y755505D02*
X91465D01*
G01X79465Y761505D02*
Y755505D01*
G01X75323D02*
Y761505D01*
G01X79259Y762166D02*
X85459D01*
G01X79259Y765366D02*
Y762166D01*
G01X85459Y765366D02*
X79259D01*
G01Y769366D02*
Y766166D01*
G01X85459Y769366D02*
X79259D01*
G01Y766166D02*
X85459D01*
G01X79259Y769766D02*
X85459D01*
Y772966D01*
X79259D01*
Y769766D01*
G01X76900Y1450100D02*
Y1446900D01*
G01D02*
X83100D01*
G01Y1446100D02*
X76900D01*
G01D02*
Y1442900D01*
G01D02*
X83100D01*
G01X74684Y1451273D02*
Y1448847D01*
G01X83100Y1450100D02*
X76900D01*
G01X85201Y1484703D02*
Y1486943D01*
G01X86826Y1485730D02*
X83576D01*
G01X73864Y1501987D02*
Y1513987D01*
G01X67864Y1501987D02*
X73864D01*
G01X67864Y1513987D02*
Y1501987D01*
G01X80749Y1502024D02*
Y1514024D01*
G01X74749Y1502024D02*
X80749D01*
G01X74749Y1514024D02*
Y1502024D01*
G01X73864Y1513987D02*
X67864D01*
G01X80749Y1514024D02*
X74749D01*
G01X67475Y1536669D02*
Y1524669D01*
G01X73475Y1536669D02*
X67475D01*
G01Y1524669D02*
X73475D01*
G01D02*
Y1536669D01*
G01X75405D02*
Y1524669D01*
G01X81405Y1536669D02*
X75405D01*
G01X81405Y1524669D02*
Y1536669D01*
G01X75405Y1524669D02*
X81405D01*
G01X77022Y1561789D02*
Y1567789D01*
G01Y1554889D02*
Y1560889D01*
G01X76935Y1575558D02*
Y1581558D01*
G01X77022Y1568689D02*
Y1574689D01*
G01X68471Y1599690D02*
Y1605890D01*
G01X80067Y1607305D02*
X83267D01*
G01X80067Y1613505D02*
Y1607305D01*
G01X79267D02*
Y1613505D01*
G01X76067Y1607305D02*
X79267D01*
G01X76067Y1613505D02*
Y1607305D01*
G01X83267Y1613505D02*
X80067D01*
G01X79267D02*
X76067D01*
G01X77533Y1626996D02*
Y1623796D01*
G01D02*
X83733D01*
G01X77533Y1622496D02*
Y1619296D01*
G01X83733Y1622496D02*
X77533D01*
G01Y1619296D02*
X83733D01*
G01X77533Y1617996D02*
Y1614796D01*
G01X83733Y1617996D02*
X77533D01*
G01Y1614796D02*
X83733D01*
G01Y1626996D02*
X77533D01*
G01X77567Y1628305D02*
X83767D01*
G01X77567Y1631505D02*
Y1628305D01*
G01X83767Y1631505D02*
X77567D01*
G01X140833Y605376D02*
G02I-22900J0D01*
G01X96559Y753366D02*
Y750166D01*
G01X102759Y753366D02*
X96559D01*
G01Y750166D02*
X102759D01*
G01X91465Y755505D02*
Y761505D01*
G01X93024Y755505D02*
X105024D01*
G01X93024Y761505D02*
Y755505D01*
G01X105024Y761505D02*
X93024D01*
G01X85459Y762166D02*
Y765366D01*
G01Y766166D02*
Y769366D01*
G01X86290Y962566D02*
Y959366D01*
G01X92490Y962566D02*
X86290D01*
G01X92490Y959366D02*
Y962566D01*
G01X86290Y959366D02*
X92490D01*
G01X91226Y1327955D02*
X94426D01*
G01X91226Y1334155D02*
Y1327955D01*
G01X94426D02*
Y1334155D01*
G01X94994Y1324651D02*
X100994D01*
G01X94994Y1336651D02*
Y1324651D01*
G01X94426Y1334155D02*
X91226D01*
G01X100994Y1336651D02*
X94994D01*
G01X96586Y1372437D02*
X99786D01*
G01X96586Y1378637D02*
Y1372437D01*
G01X99786Y1378637D02*
X96586D01*
G01X91600Y1415400D02*
Y1418600D01*
G01X85400D02*
Y1415400D01*
G01D02*
X91600D01*
G01X85400Y1410900D02*
X91600D01*
G01D02*
Y1414100D01*
G01D02*
X85400D01*
G01D02*
Y1410900D01*
G01Y1406400D02*
X91600D01*
G01D02*
Y1409600D01*
G01D02*
X85400D01*
G01D02*
Y1406400D01*
G01X94400Y1410900D02*
X100600D01*
G01Y1414100D02*
X94400D01*
G01D02*
Y1410900D01*
G01X91600Y1427600D02*
X85400D01*
G01D02*
Y1424400D01*
G01X91600D02*
Y1427600D01*
G01X85400Y1424400D02*
X91600D01*
G01X85400Y1419900D02*
X91600D01*
G01D02*
Y1423100D01*
G01D02*
X85400D01*
G01D02*
Y1419900D01*
G01X94400D02*
X100600D01*
G01Y1423100D02*
X94400D01*
G01D02*
Y1419900D01*
G01X91600Y1418600D02*
X85400D01*
G01X94400Y1424400D02*
X100600D01*
G01Y1427600D02*
X94400D01*
G01D02*
Y1424400D01*
G01Y1428900D02*
X100600D01*
G01Y1432100D02*
X94400D01*
G01D02*
Y1428900D01*
G01X85400D02*
X91600D01*
G01D02*
Y1432100D01*
G01D02*
X85400D01*
G01D02*
Y1428900D01*
G01Y1438400D02*
X91600D01*
G01D02*
Y1441600D01*
G01D02*
X85400D01*
G01D02*
Y1438400D01*
G01X94400D02*
X100600D01*
G01Y1441600D02*
X94400D01*
G01D02*
Y1438400D01*
G01Y1433900D02*
X100600D01*
G01Y1437100D02*
X94400D01*
G01D02*
Y1433900D01*
G01X83100Y1446900D02*
Y1450100D01*
G01Y1442900D02*
Y1446100D01*
G01X96584Y1451273D02*
Y1448847D01*
G01X87616Y1487711D02*
Y1454600D01*
G01X88800Y1451971D02*
X104546D01*
G01X82646D02*
Y1487711D01*
G01X87614D02*
X104554Y1487714D01*
G01X87614Y1488311D02*
X104589Y1488315D01*
G01X87614Y1488911D02*
X104597Y1488905D01*
G01X87614Y1488911D02*
Y1487711D01*
G01X104546D02*
X87616D01*
G01X82647Y1488861D02*
X82643Y1487352D01*
G01X99944Y1492125D02*
X83004Y1492122D01*
G01X99944Y1491525D02*
X82969Y1491521D01*
G01X99944Y1490925D02*
X82961Y1490931D01*
G01X83011Y1490975D02*
X83015Y1492484D01*
G01X83012Y1492125D02*
X99942D01*
G01X83012Y1527865D02*
Y1492125D01*
G01X85396Y1530469D02*
X88596D01*
G01X85396Y1536669D02*
Y1530469D01*
G01X88596Y1536669D02*
X85396D01*
G01X88596Y1530469D02*
Y1536669D01*
G01X90974Y1528563D02*
Y1530989D01*
G01X99942Y1527865D02*
X83012D01*
G01X83267Y1607305D02*
Y1613505D01*
G01X83733Y1623796D02*
Y1626996D01*
G01Y1619296D02*
Y1622496D01*
G01Y1614796D02*
Y1617996D01*
G01X83767Y1628305D02*
Y1631505D01*
G01X98229Y294322D02*
X101329D01*
X100709Y293862D01*
G01X98229D02*
Y294782D01*
G01Y314756D02*
X101329D01*
X100709Y314296D01*
G01X98229D02*
Y315216D01*
G01X102759Y750166D02*
Y753366D01*
G01X121166Y761505D02*
X109166D01*
G01Y755505D02*
X121166D01*
G01X109166Y761505D02*
Y755505D01*
G01X105024D02*
Y761505D01*
G01X108960Y762166D02*
X115160D01*
G01X108960Y765366D02*
Y762166D01*
G01X115160Y765366D02*
X108960D01*
G01Y769366D02*
Y766166D01*
G01X115160Y769366D02*
X108960D01*
G01Y766166D02*
X115160D01*
G01X98960Y762166D02*
X105160D01*
G01X98960Y765366D02*
Y762166D01*
G01X105160Y765366D02*
X98960D01*
G01X105160Y762166D02*
Y765366D01*
G01X98960Y768866D02*
Y765666D01*
G01X105160Y768866D02*
X98960D01*
G01Y765666D02*
X105160D01*
G01D02*
Y768866D01*
G01X108960Y769766D02*
X115160D01*
Y772966D01*
X108960D01*
Y769766D01*
G01X110471Y1314035D02*
X112711D01*
G01X111498Y1312410D02*
Y1315660D01*
G01X102936Y1320203D02*
X120652D01*
G01X102936Y1355899D02*
Y1320203D01*
G01X100994Y1324651D02*
Y1336651D01*
G01X102489Y1357759D02*
Y1360185D01*
G01X120652Y1355899D02*
X102936D01*
G01X99786Y1372437D02*
Y1378637D01*
G01X101903Y1366114D02*
X105103D01*
G01X101903Y1372314D02*
Y1366114D01*
G01X105103Y1372314D02*
X101903D01*
G01X105103Y1366114D02*
Y1372314D01*
G01X100600Y1410900D02*
Y1414100D01*
G01Y1419900D02*
Y1423100D01*
G01Y1424400D02*
Y1427600D01*
G01Y1428900D02*
Y1432100D01*
G01Y1438400D02*
Y1441600D01*
G01Y1433900D02*
Y1437100D01*
G01X97400Y1448600D02*
Y1442400D01*
G01D02*
X100600D01*
G01D02*
Y1448600D01*
G01D02*
X97400D01*
G01X106000Y1454883D02*
X109100D01*
Y1455803D01*
X108945Y1456110D01*
X108583Y1456340D01*
X108170Y1456417D01*
X107757Y1456340D01*
X107447Y1456148D01*
X107292Y1455803D01*
Y1454883D01*
G01X108842Y1459593D02*
X108997Y1459363D01*
X109100Y1459095D01*
Y1458788D01*
X108945Y1458443D01*
X108687Y1458175D01*
X108377Y1457983D01*
X107860Y1457830D01*
X107395Y1457792D01*
X106930Y1457868D01*
X106620Y1457983D01*
X106310Y1458213D01*
X106103Y1458482D01*
X106000Y1458750D01*
Y1459018D01*
X106103Y1459287D01*
X106258Y1459517D01*
X106465Y1459708D01*
G01X107292Y1461122D02*
X107653Y1461390D01*
X107860Y1461620D01*
X107963Y1461927D01*
X107860Y1462195D01*
X107653Y1462387D01*
X107343Y1462540D01*
X106982Y1462578D01*
X106672Y1462540D01*
X106362Y1462387D01*
X106103Y1462157D01*
X106000Y1461888D01*
X106103Y1461582D01*
X106413Y1461313D01*
X106878Y1461160D01*
X107395Y1461122D01*
X108067Y1461198D01*
X108428Y1461313D01*
X108790Y1461505D01*
X109048Y1461773D01*
X109100Y1462042D01*
X108997Y1462310D01*
X108738Y1462502D01*
G01X106000Y1464950D02*
X106052Y1465218D01*
X106207Y1465525D01*
X106465Y1465717D01*
X106827Y1465793D01*
X107188Y1465717D01*
X107498Y1465487D01*
X107653Y1465142D01*
Y1464758D01*
X107757Y1464528D01*
X108015Y1464337D01*
X108377Y1464260D01*
X108738Y1464375D01*
X108997Y1464643D01*
X109100Y1464950D01*
X108997Y1465257D01*
X108738Y1465525D01*
X108377Y1465640D01*
X108015Y1465563D01*
X107757Y1465372D01*
X107653Y1465142D01*
Y1464758D01*
X107498Y1464413D01*
X107188Y1464183D01*
X106827Y1464107D01*
X106465Y1464183D01*
X106207Y1464375D01*
X106052Y1464682D01*
X106000Y1464950D01*
G01Y1468050D02*
X109100D01*
X108480Y1467590D01*
G01X106000D02*
Y1468510D01*
G01Y1471610D02*
X109100D01*
X106878Y1470192D01*
Y1472108D01*
G01X104546Y1451971D02*
Y1487711D01*
G01X102963Y1494996D02*
Y1492756D01*
G01X101338Y1493969D02*
X104588D01*
G01X104547Y1488861D02*
X104543Y1487352D01*
G01X99944Y1490925D02*
Y1492125D01*
G01X99942D02*
Y1527865D01*
G01X101577Y1504278D02*
X104777D01*
G01X101577Y1510478D02*
Y1504278D01*
G01X104777D02*
Y1510478D01*
G01X106000Y1503883D02*
X109100D01*
Y1504803D01*
X108945Y1505110D01*
X108583Y1505340D01*
X108170Y1505417D01*
X107757Y1505340D01*
X107447Y1505148D01*
X107292Y1504803D01*
Y1503883D01*
G01X108842Y1508593D02*
X108997Y1508363D01*
X109100Y1508095D01*
Y1507788D01*
X108945Y1507443D01*
X108687Y1507175D01*
X108377Y1506983D01*
X107860Y1506830D01*
X107395Y1506792D01*
X106930Y1506868D01*
X106620Y1506983D01*
X106310Y1507213D01*
X106103Y1507482D01*
X106000Y1507750D01*
Y1508018D01*
X106103Y1508287D01*
X106258Y1508517D01*
X106465Y1508708D01*
G01X107292Y1510122D02*
X107653Y1510390D01*
X107860Y1510620D01*
X107963Y1510927D01*
X107860Y1511195D01*
X107653Y1511387D01*
X107343Y1511540D01*
X106982Y1511578D01*
X106672Y1511540D01*
X106362Y1511387D01*
X106103Y1511157D01*
X106000Y1510888D01*
X106103Y1510582D01*
X106413Y1510313D01*
X106878Y1510160D01*
X107395Y1510122D01*
X108067Y1510198D01*
X108428Y1510313D01*
X108790Y1510505D01*
X109048Y1510773D01*
X109100Y1511042D01*
X108997Y1511310D01*
X108738Y1511502D01*
G01X106000Y1513950D02*
X106052Y1514218D01*
X106207Y1514525D01*
X106465Y1514717D01*
X106827Y1514793D01*
X107188Y1514717D01*
X107498Y1514487D01*
X107653Y1514142D01*
Y1513758D01*
X107757Y1513528D01*
X108015Y1513337D01*
X108377Y1513260D01*
X108738Y1513375D01*
X108997Y1513643D01*
X109100Y1513950D01*
X108997Y1514257D01*
X108738Y1514525D01*
X108377Y1514640D01*
X108015Y1514563D01*
X107757Y1514372D01*
X107653Y1514142D01*
Y1513758D01*
X107498Y1513413D01*
X107188Y1513183D01*
X106827Y1513107D01*
X106465Y1513183D01*
X106207Y1513375D01*
X106052Y1513682D01*
X106000Y1513950D01*
G01Y1517050D02*
X109100D01*
X108480Y1516590D01*
G01X106000D02*
Y1517510D01*
G01X106465Y1519307D02*
X106207Y1519537D01*
X106052Y1519805D01*
X106000Y1520150D01*
X106103Y1520495D01*
X106310Y1520763D01*
X106672Y1520955D01*
X107085Y1520993D01*
X107498Y1520917D01*
X107757Y1520725D01*
X107963Y1520457D01*
X108015Y1520188D01*
X107963Y1519920D01*
X107757Y1519575D01*
X109100Y1519690D01*
Y1520725D01*
G01X104777Y1510478D02*
X101577D01*
G01X109826Y1536134D02*
Y1524134D01*
G01X115826Y1536134D02*
X109826D01*
G01Y1524134D02*
X115826D01*
G01X101887Y1536068D02*
Y1524068D01*
G01X107887Y1536068D02*
X101887D01*
G01X107887Y1524068D02*
Y1536068D01*
G01X101887Y1524068D02*
X107887D01*
G01X109220Y1578806D02*
X115220D01*
G01X109220Y1590806D02*
Y1578806D01*
G01X115220Y1590806D02*
X109220D01*
G01X125059Y753366D02*
Y750166D01*
G01X131259Y753366D02*
X125059D01*
G01Y750166D02*
X131259D01*
G01X122725Y755505D02*
X134725D01*
G01X122725Y761505D02*
Y755505D01*
G01X134725Y761505D02*
X122725D01*
G01X121166Y755505D02*
Y761505D01*
G01X115160Y762166D02*
Y765366D01*
G01Y766166D02*
Y769366D01*
G01X115991Y962566D02*
Y959366D01*
G01X122191Y962566D02*
X115991D01*
G01X122191Y959366D02*
Y962566D01*
G01X115991Y959366D02*
X122191D01*
G01X114000Y1301383D02*
X117100D01*
Y1302303D01*
X116945Y1302610D01*
X116583Y1302840D01*
X116170Y1302917D01*
X115757Y1302840D01*
X115447Y1302648D01*
X115292Y1302303D01*
Y1301383D01*
G01X116842Y1306093D02*
X116997Y1305863D01*
X117100Y1305595D01*
Y1305288D01*
X116945Y1304943D01*
X116687Y1304675D01*
X116377Y1304483D01*
X115860Y1304330D01*
X115395Y1304292D01*
X114930Y1304368D01*
X114620Y1304483D01*
X114310Y1304713D01*
X114103Y1304982D01*
X114000Y1305250D01*
Y1305518D01*
X114103Y1305787D01*
X114258Y1306017D01*
X114465Y1306208D01*
G01X114000Y1308810D02*
X117100D01*
X114878Y1307392D01*
Y1309308D01*
G01X114465Y1310607D02*
X114207Y1310837D01*
X114052Y1311105D01*
X114000Y1311450D01*
X114103Y1311795D01*
X114310Y1312063D01*
X114672Y1312255D01*
X115085Y1312293D01*
X115498Y1312217D01*
X115757Y1312025D01*
X115963Y1311757D01*
X116015Y1311488D01*
X115963Y1311220D01*
X115757Y1310875D01*
X117100Y1310990D01*
Y1312025D01*
G01X114465Y1313707D02*
X114207Y1313937D01*
X114052Y1314205D01*
X114000Y1314550D01*
X114103Y1314895D01*
X114310Y1315163D01*
X114672Y1315355D01*
X115085Y1315393D01*
X115498Y1315317D01*
X115757Y1315125D01*
X115963Y1314857D01*
X116015Y1314588D01*
X115963Y1314320D01*
X115757Y1313975D01*
X117100Y1314090D01*
Y1315125D01*
G01X120652Y1320203D02*
Y1355899D01*
G01X122558Y1324668D02*
X128558D01*
G01X122558Y1336668D02*
Y1324668D01*
G01X128558Y1336668D02*
X122558D01*
G01X114017Y1371311D02*
Y1359311D01*
G01X120017Y1371311D02*
X114017D01*
G01X120017Y1359311D02*
Y1371311D01*
G01X114017Y1359311D02*
X120017D01*
G01X122395Y1371311D02*
Y1359311D01*
G01X128395Y1371311D02*
X122395D01*
G01Y1359311D02*
X128395D01*
G01X120017Y1374554D02*
Y1386554D01*
G01X114017Y1374554D02*
X120017D01*
G01X114017Y1386554D02*
Y1374554D01*
G01X120017Y1386554D02*
X114017D01*
G01X114690Y1393210D02*
Y1387210D01*
X126690D01*
Y1393210D01*
X114690D01*
G01X126100Y1420400D02*
Y1426600D01*
G01D02*
X122900D01*
G01Y1420400D02*
X126100D01*
G01X122900Y1426600D02*
Y1420400D01*
G01X131600Y1438100D02*
X125400D01*
G01Y1434900D02*
X131600D01*
G01X125400Y1438100D02*
Y1434900D01*
G01X115826Y1524134D02*
Y1536134D01*
G01X115220Y1578806D02*
Y1590806D01*
G01X131259Y750166D02*
Y753366D01*
G01X150867Y761505D02*
X138867D01*
G01Y755505D02*
X150867D01*
G01X138867Y761505D02*
Y755505D01*
G01X134725D02*
Y761505D01*
G01X138792Y762100D02*
X144992D01*
G01X138792Y765300D02*
Y762100D01*
G01X144992Y765300D02*
X138792D01*
G01Y769000D02*
Y765800D01*
G01X144992Y769000D02*
X138792D01*
G01Y765800D02*
X144992D01*
G01X128661Y762166D02*
X134861D01*
G01X128661Y765366D02*
Y762166D01*
G01X134861Y765366D02*
X128661D01*
G01X134861Y762166D02*
Y765366D01*
G01X128661Y768866D02*
Y765666D01*
G01X134861Y768866D02*
X128661D01*
G01Y765666D02*
X134861D01*
G01D02*
Y768866D01*
G01X138792Y769600D02*
X144992D01*
Y772800D01*
X138792D01*
Y769600D01*
G01X142358Y1301440D02*
X145458D01*
Y1302360D01*
X145303Y1302667D01*
X144941Y1302897D01*
X144528Y1302974D01*
X144115Y1302897D01*
X143805Y1302705D01*
X143650Y1302360D01*
Y1301440D01*
G01X145200Y1306150D02*
X145355Y1305920D01*
X145458Y1305652D01*
Y1305345D01*
X145303Y1305000D01*
X145045Y1304732D01*
X144735Y1304540D01*
X144218Y1304387D01*
X143753Y1304349D01*
X143288Y1304425D01*
X142978Y1304540D01*
X142668Y1304770D01*
X142461Y1305039D01*
X142358Y1305307D01*
Y1305575D01*
X142461Y1305844D01*
X142616Y1306074D01*
X142823Y1306265D01*
G01X142358Y1308867D02*
X145458D01*
X143236Y1307449D01*
Y1309365D01*
G01X142823Y1310664D02*
X142565Y1310894D01*
X142410Y1311162D01*
X142358Y1311507D01*
X142461Y1311852D01*
X142668Y1312120D01*
X143030Y1312312D01*
X143443Y1312350D01*
X143856Y1312274D01*
X144115Y1312082D01*
X144321Y1311814D01*
X144373Y1311545D01*
X144321Y1311277D01*
X144115Y1310932D01*
X145458Y1311047D01*
Y1312082D01*
G01X144941Y1313879D02*
X145251Y1314109D01*
X145406Y1314377D01*
X145458Y1314684D01*
X145355Y1315067D01*
X145096Y1315335D01*
X144786Y1315412D01*
X144476Y1315374D01*
X144218Y1315220D01*
X143701Y1314454D01*
X143340Y1314109D01*
X142823Y1313879D01*
X142358Y1313802D01*
Y1315412D01*
G01X139036Y1320403D02*
X156752D01*
G01X139036Y1356099D02*
Y1320403D01*
G01X136994Y1324751D02*
Y1336751D01*
G01X130994Y1324751D02*
X136994D01*
G01X130994Y1336751D02*
Y1324751D01*
G01X128558Y1324668D02*
Y1336668D01*
G01X136994Y1336751D02*
X130994D01*
G01X156752Y1356099D02*
X139036D01*
G01X129186Y1372437D02*
X132386D01*
G01X129186Y1378637D02*
Y1372437D01*
G01X132386D02*
Y1378637D01*
G01X134503Y1366114D02*
X137703D01*
G01X134503Y1372314D02*
Y1366114D01*
G01X137703Y1372314D02*
X134503D01*
G01X137703Y1366114D02*
Y1372314D01*
G01X128395Y1359311D02*
Y1371311D01*
G01X132386Y1378637D02*
X129186D01*
G01X131600Y1426600D02*
X128400D01*
G01D02*
Y1420400D01*
G01X131600D02*
Y1426600D01*
G01X128400Y1420400D02*
X131600D01*
G01X142100Y1426600D02*
X135900D01*
G01D02*
Y1423400D01*
G01D02*
X142100D01*
G01X139100Y1430600D02*
X132900D01*
G01Y1427400D02*
X139100D01*
G01D02*
Y1430600D01*
G01X132900D02*
Y1427400D01*
G01X131600Y1434900D02*
Y1438100D01*
G01X132185Y1675333D02*
Y1669333D01*
G01D02*
X144185D01*
G01X128575Y1678913D02*
X134775D01*
G01D02*
Y1682113D01*
G01D02*
X128575D01*
G01D02*
Y1678913D01*
G01X144185Y1675333D02*
X132185D01*
G01X154559Y753366D02*
Y750166D01*
G01X160759Y753366D02*
X154559D01*
G01Y750166D02*
X160759D01*
G01X150867Y755505D02*
Y761505D01*
G01X152426Y755505D02*
X164426D01*
G01X152426Y761505D02*
Y755505D01*
G01X164426Y761505D02*
X152426D01*
G01X144992Y762100D02*
Y765300D01*
G01Y765800D02*
Y769000D01*
G01X145691Y962566D02*
Y959366D01*
G01X151891Y962566D02*
X145691D01*
G01X151891Y959366D02*
Y962566D01*
G01X145691Y959366D02*
X151891D01*
G01X146571Y1314235D02*
X148811D01*
G01X147598Y1312610D02*
Y1315860D01*
G01X154287Y1356678D02*
Y1359104D01*
G01X154995Y1371311D02*
Y1359311D01*
G01X160995Y1371311D02*
X154995D01*
G01Y1359311D02*
X160995D01*
G01X146617Y1371311D02*
Y1359311D01*
G01X152617Y1371311D02*
X146617D01*
G01X152617Y1359311D02*
Y1371311D01*
G01X146617Y1359311D02*
X152617D01*
G01Y1374554D02*
Y1386554D01*
G01X146617Y1374554D02*
X152617D01*
G01X146617Y1386554D02*
Y1374554D01*
G01X152617Y1386554D02*
X146617D01*
G01X142100Y1423400D02*
Y1426600D01*
G01X144185Y1669333D02*
Y1675333D01*
G01X160759Y750166D02*
Y753366D01*
G01X180568Y761505D02*
X168568D01*
G01Y755505D02*
X180568D01*
G01X168568Y761505D02*
Y755505D01*
G01X164426D02*
Y761505D01*
G01X168462Y762066D02*
X174662D01*
G01X168462Y765266D02*
Y762066D01*
G01X174662Y765266D02*
X168462D01*
G01Y769266D02*
Y766066D01*
G01X174662Y769266D02*
X168462D01*
G01Y766066D02*
X174662D01*
G01X158300Y762166D02*
X164500D01*
G01X158300Y765366D02*
Y762166D01*
G01X164500Y765366D02*
X158300D01*
G01X164500Y762166D02*
Y765366D01*
G01X158300Y768866D02*
Y765666D01*
G01X164500Y768866D02*
X158300D01*
G01Y765666D02*
X164500D01*
G01D02*
Y768866D01*
G01X168462Y769666D02*
X174662D01*
Y772866D01*
X168462D01*
Y769666D01*
G01X156752Y1320403D02*
Y1356099D01*
G01X167266Y1324668D02*
X173266D01*
G01X167266Y1336668D02*
Y1324668D01*
G01X165058D02*
Y1336668D01*
G01X159058Y1324668D02*
X165058D01*
G01X159058Y1336668D02*
Y1324668D01*
G01X173266Y1336668D02*
X167266D01*
G01X165058D02*
X159058D01*
G01X161886Y1372437D02*
X165086D01*
G01X161886Y1378637D02*
Y1372437D01*
G01X165086D02*
Y1378637D01*
G01X167203Y1366114D02*
X170403D01*
G01X167203Y1372314D02*
Y1366114D01*
G01X170403Y1372314D02*
X167203D01*
G01X170403Y1366114D02*
Y1372314D01*
G01X160995Y1359311D02*
Y1371311D01*
G01X165086Y1378637D02*
X161886D01*
G01X184059Y753366D02*
Y750166D01*
G01X190259Y753366D02*
X184059D01*
G01Y750166D02*
X190259D01*
G01X182126Y755505D02*
X194126D01*
G01X182126Y761505D02*
Y755505D01*
G01X194126Y761505D02*
X182126D01*
G01X180568Y755505D02*
Y761505D01*
G01X174662Y762066D02*
Y765266D01*
G01Y766066D02*
Y769266D01*
G01X175392Y962566D02*
Y959366D01*
G01X181592Y962566D02*
X175392D01*
G01X181592Y959366D02*
Y962566D01*
G01X175392Y959366D02*
X181592D01*
G01X183682Y1324668D02*
X189682D01*
G01X183682Y1336668D02*
Y1324668D01*
G01X181474D02*
Y1336668D01*
G01X175474Y1324668D02*
X181474D01*
G01X175474Y1336668D02*
Y1324668D01*
G01X173266D02*
Y1336668D01*
G01X189682D02*
X183682D01*
G01X181474D02*
X175474D01*
G01X179317Y1371311D02*
Y1359311D01*
G01X185317Y1371311D02*
X179317D01*
G01X185317Y1359311D02*
Y1371311D01*
G01X179317Y1359311D02*
X185317D01*
G01Y1374554D02*
Y1386554D01*
G01X179317Y1374554D02*
X185317D01*
G01X179317Y1386554D02*
Y1374554D01*
G01X185317Y1386554D02*
X179317D01*
G01X174822Y1505450D02*
Y1499450D01*
X186822D01*
Y1505450D01*
X174822D01*
G01X184979Y1534538D02*
X188179D01*
G01X184979Y1540738D02*
Y1534538D01*
G01X188179Y1540738D02*
X184979D01*
G01X181421Y1543812D02*
Y1537612D01*
G01X184621Y1543812D02*
X181421D01*
G01X184621Y1537612D02*
Y1543812D01*
G01X181421Y1537612D02*
X184621D01*
G01X181213Y1667396D02*
X184413D01*
G01X181213Y1673596D02*
Y1667396D01*
G01X184413D02*
Y1673596D01*
G01Y1666596D02*
X181213D01*
G01X184413Y1660396D02*
Y1666596D01*
G01X181213D02*
Y1660396D01*
G01D02*
X184413D01*
G01X193023Y1664882D02*
X193330Y1664934D01*
X193598Y1665140D01*
X193828Y1665450D01*
X193981Y1665812D01*
X194058Y1666225D01*
Y1666639D01*
X193981Y1667052D01*
X193828Y1667414D01*
X193598Y1667724D01*
X193330Y1667930D01*
X193023Y1667982D01*
X192716Y1667930D01*
X192448Y1667724D01*
X192218Y1667414D01*
X192065Y1667052D01*
X191988Y1666639D01*
Y1666225D01*
X192065Y1665812D01*
X192218Y1665450D01*
X192448Y1665140D01*
X192716Y1664934D01*
X193023Y1664882D01*
G01X192716Y1665709D02*
X192256Y1664882D01*
G01X190575Y1665244D02*
X190306Y1664985D01*
X190000Y1664882D01*
X189693Y1664985D01*
X189425Y1665295D01*
X189233Y1665760D01*
X189156Y1666225D01*
Y1666794D01*
X189233Y1667259D01*
X189425Y1667672D01*
X189655Y1667879D01*
X189923Y1667982D01*
X190230Y1667879D01*
X190460Y1667672D01*
X190613Y1667362D01*
X190690Y1666949D01*
X190613Y1666587D01*
X190421Y1666225D01*
X190191Y1666019D01*
X189923Y1665967D01*
X189616Y1666070D01*
X189386Y1666329D01*
X189156Y1666794D01*
G01X187551Y1666174D02*
X187283Y1666535D01*
X187053Y1666742D01*
X186746Y1666845D01*
X186478Y1666742D01*
X186286Y1666535D01*
X186133Y1666225D01*
X186095Y1665864D01*
X186133Y1665554D01*
X186286Y1665244D01*
X186516Y1664985D01*
X186785Y1664882D01*
X187091Y1664985D01*
X187360Y1665295D01*
X187513Y1665760D01*
X187551Y1666277D01*
X187475Y1666949D01*
X187360Y1667310D01*
X187168Y1667672D01*
X186900Y1667930D01*
X186631Y1667982D01*
X186363Y1667879D01*
X186171Y1667620D01*
G01X184413Y1673596D02*
X181213D01*
G01X191515Y1680264D02*
X191822Y1680316D01*
X192090Y1680522D01*
X192320Y1680832D01*
X192473Y1681194D01*
X192550Y1681607D01*
Y1682021D01*
X192473Y1682434D01*
X192320Y1682796D01*
X192090Y1683106D01*
X191822Y1683312D01*
X191515Y1683364D01*
X191208Y1683312D01*
X190940Y1683106D01*
X190710Y1682796D01*
X190557Y1682434D01*
X190480Y1682021D01*
Y1681607D01*
X190557Y1681194D01*
X190710Y1680832D01*
X190940Y1680522D01*
X191208Y1680316D01*
X191515Y1680264D01*
G01X191208Y1681091D02*
X190748Y1680264D01*
G01X188492D02*
X188415Y1680936D01*
X188300Y1681504D01*
X188147Y1682021D01*
X187955Y1682589D01*
X187648Y1683364D01*
X189182D01*
G01X186043Y1682847D02*
X185813Y1683157D01*
X185545Y1683312D01*
X185238Y1683364D01*
X184855Y1683261D01*
X184587Y1683002D01*
X184510Y1682692D01*
X184548Y1682382D01*
X184702Y1682124D01*
X185468Y1681607D01*
X185813Y1681246D01*
X186043Y1680729D01*
X186120Y1680264D01*
X184510D01*
G01X180917Y1697631D02*
X184117D01*
G01X180917Y1703831D02*
Y1697631D01*
G01X184117D02*
Y1703831D01*
G01Y1696663D02*
X180917D01*
G01X184117Y1690463D02*
Y1696663D01*
G01X180917Y1690463D02*
X184117D01*
G01X180917Y1696663D02*
Y1690463D01*
G01X194893Y1696309D02*
X195200Y1696361D01*
X195468Y1696567D01*
X195698Y1696877D01*
X195851Y1697239D01*
X195928Y1697652D01*
Y1698066D01*
X195851Y1698479D01*
X195698Y1698841D01*
X195468Y1699151D01*
X195200Y1699357D01*
X194893Y1699409D01*
X194586Y1699357D01*
X194318Y1699151D01*
X194088Y1698841D01*
X193935Y1698479D01*
X193858Y1698066D01*
Y1697652D01*
X193935Y1697239D01*
X194088Y1696877D01*
X194318Y1696567D01*
X194586Y1696361D01*
X194893Y1696309D01*
G01X194586Y1697136D02*
X194126Y1696309D01*
G01X191793D02*
Y1699409D01*
X192253Y1698789D01*
G01Y1696309D02*
X191333D01*
G01X188693Y1699409D02*
X189000Y1699306D01*
X189230Y1699047D01*
X189383Y1698737D01*
X189498Y1698324D01*
X189536Y1697859D01*
X189498Y1697394D01*
X189383Y1696981D01*
X189230Y1696671D01*
X189000Y1696412D01*
X188693Y1696309D01*
X188386Y1696412D01*
X188156Y1696671D01*
X188003Y1696981D01*
X187888Y1697394D01*
X187850Y1697859D01*
X187888Y1698324D01*
X188003Y1698737D01*
X188156Y1699047D01*
X188386Y1699306D01*
X188693Y1699409D01*
G01X185670Y1696309D02*
X185593Y1696981D01*
X185478Y1697549D01*
X185325Y1698066D01*
X185133Y1698634D01*
X184826Y1699409D01*
X186360D01*
G01X184117Y1703831D02*
X180917D01*
G01X185973Y1710301D02*
X186280Y1710353D01*
X186548Y1710559D01*
X186778Y1710869D01*
X186931Y1711231D01*
X187008Y1711644D01*
Y1712058D01*
X186931Y1712471D01*
X186778Y1712833D01*
X186548Y1713143D01*
X186280Y1713349D01*
X185973Y1713401D01*
X185666Y1713349D01*
X185398Y1713143D01*
X185168Y1712833D01*
X185015Y1712471D01*
X184938Y1712058D01*
Y1711644D01*
X185015Y1711231D01*
X185168Y1710869D01*
X185398Y1710559D01*
X185666Y1710353D01*
X185973Y1710301D01*
G01X185666Y1711128D02*
X185206Y1710301D01*
G01X182873D02*
Y1713401D01*
X183333Y1712781D01*
G01Y1710301D02*
X182413D01*
G01X179773Y1713401D02*
X180080Y1713298D01*
X180310Y1713039D01*
X180463Y1712729D01*
X180578Y1712316D01*
X180616Y1711851D01*
X180578Y1711386D01*
X180463Y1710973D01*
X180310Y1710663D01*
X180080Y1710404D01*
X179773Y1710301D01*
X179466Y1710404D01*
X179236Y1710663D01*
X179083Y1710973D01*
X178968Y1711386D01*
X178930Y1711851D01*
X178968Y1712316D01*
X179083Y1712729D01*
X179236Y1713039D01*
X179466Y1713298D01*
X179773Y1713401D01*
G01X176673Y1710301D02*
Y1713401D01*
X177133Y1712781D01*
G01Y1710301D02*
X176213D01*
G01X196059Y752866D02*
Y749666D01*
G01X202259Y752866D02*
X196059D01*
G01Y749666D02*
X202259D01*
G01X190259Y750166D02*
Y753366D01*
G01X210268Y761505D02*
X198268D01*
G01Y755505D02*
X210268D01*
G01X198268Y761505D02*
Y755505D01*
G01X194126D02*
Y761505D01*
G01X198162Y762166D02*
X204362D01*
G01X198162Y765366D02*
Y762166D01*
G01X204362Y765366D02*
X198162D01*
G01X198193Y769000D02*
Y765800D01*
G01X204393Y769000D02*
X198193D01*
G01Y765800D02*
X204393D01*
G01X188062Y762166D02*
X194262D01*
G01X188062Y765366D02*
Y762166D01*
G01X194262Y765366D02*
X188062D01*
G01X194262Y762166D02*
Y765366D01*
G01X188062Y768866D02*
Y765666D01*
G01X194262Y768866D02*
X188062D01*
G01Y765666D02*
X194262D01*
G01D02*
Y768866D01*
G01X198162Y769766D02*
X204362D01*
Y772966D01*
X198162D01*
Y769766D01*
G01X200136Y1320303D02*
X217852D01*
G01X200136Y1355999D02*
Y1320303D01*
G01X197494Y1324651D02*
Y1336651D01*
G01X191494Y1324651D02*
X197494D01*
G01X191494Y1336651D02*
Y1324651D01*
G01X189682Y1324668D02*
Y1336668D01*
G01X197494Y1336651D02*
X191494D01*
G01X200614Y1357624D02*
Y1360050D01*
G01X217852Y1355999D02*
X200136D01*
G01X194786Y1372437D02*
X197986D01*
G01X194786Y1378637D02*
Y1372437D01*
G01X197986D02*
Y1378637D01*
G01X200103Y1366114D02*
X203303D01*
G01X200103Y1372314D02*
Y1366114D01*
G01X203303Y1372314D02*
X200103D01*
G01X187695Y1371311D02*
Y1359311D01*
G01X193695Y1371311D02*
X187695D01*
G01X193695Y1359311D02*
Y1371311D01*
G01X187695Y1359311D02*
X193695D01*
G01X197986Y1378637D02*
X194786D01*
G01X191347Y1489363D02*
X193587D01*
G01X192374Y1487738D02*
Y1490988D01*
G01X210765Y1489204D02*
X210995Y1489359D01*
X211263Y1489462D01*
X211570D01*
X211915Y1489307D01*
X212183Y1489049D01*
X212375Y1488739D01*
X212528Y1488222D01*
X212566Y1487757D01*
X212490Y1487292D01*
X212375Y1486982D01*
X212145Y1486672D01*
X211876Y1486465D01*
X211608Y1486362D01*
X211340D01*
X211071Y1486465D01*
X210841Y1486620D01*
X210650Y1486827D01*
G01X208585Y1486362D02*
X208508Y1487034D01*
X208393Y1487602D01*
X208240Y1488119D01*
X208048Y1488687D01*
X207741Y1489462D01*
X209275D01*
G01X205408D02*
X205715Y1489359D01*
X205945Y1489100D01*
X206098Y1488790D01*
X206213Y1488377D01*
X206251Y1487912D01*
X206213Y1487447D01*
X206098Y1487034D01*
X205945Y1486724D01*
X205715Y1486465D01*
X205408Y1486362D01*
X205101Y1486465D01*
X204871Y1486724D01*
X204718Y1487034D01*
X204603Y1487447D01*
X204565Y1487912D01*
X204603Y1488377D01*
X204718Y1488790D01*
X204871Y1489100D01*
X205101Y1489359D01*
X205408Y1489462D01*
G01X203036Y1488945D02*
X202806Y1489255D01*
X202538Y1489410D01*
X202231Y1489462D01*
X201848Y1489359D01*
X201580Y1489100D01*
X201503Y1488790D01*
X201541Y1488480D01*
X201695Y1488222D01*
X202461Y1487705D01*
X202806Y1487344D01*
X203036Y1486827D01*
X203113Y1486362D01*
X201503D01*
G01X199208D02*
Y1489462D01*
X199668Y1488842D01*
G01Y1486362D02*
X198748D01*
G01X188812Y1491980D02*
X224552D01*
Y1508910D01*
X188812D01*
Y1491980D01*
G01X187612Y1491978D02*
X188812D01*
G01X187612D02*
X187618Y1508961D01*
G01X188212Y1491978D02*
X188208Y1508953D01*
G01X188812Y1491978D02*
X188809Y1508918D01*
G01X187662Y1508911D02*
X189171Y1508907D01*
G01X188179Y1534538D02*
Y1540738D01*
G01X197629Y1534538D02*
Y1540738D01*
G01X194429Y1534538D02*
X197629D01*
G01X194429Y1540738D02*
Y1534538D01*
G01X199153Y1540738D02*
Y1534538D01*
X202353D01*
Y1540738D01*
X199153D01*
G01X189704D02*
Y1534538D01*
X192904D01*
Y1540738D01*
X189704D01*
G01X197629D02*
X194429D01*
G01X196581Y1654054D02*
Y1650854D01*
G01X202781Y1654054D02*
X196581D01*
G01Y1650854D02*
X202781D01*
G01X196581Y1650054D02*
Y1646854D01*
G01X202781Y1650054D02*
X196581D01*
G01Y1646854D02*
X202781D01*
G01X196660Y1654963D02*
Y1663625D01*
G01X186166Y1654963D02*
X196660D01*
G01X186166Y1663625D02*
Y1654963D01*
G01X199323Y1656570D02*
X205523D01*
G01X199323Y1659770D02*
Y1656570D01*
G01X205523Y1659770D02*
X199323D01*
G01X198981Y1666079D02*
Y1662879D01*
G01D02*
X205181D01*
G01Y1666079D02*
X198981D01*
G01X196660Y1669981D02*
Y1678643D01*
G01X186166Y1669981D02*
X196660D01*
G01X186166Y1678643D02*
Y1669981D01*
G01X193313Y1663625D02*
X191413Y1661425D01*
G01X196660Y1663625D02*
X193313D01*
G01X189513D02*
X186166D01*
G01X191413Y1661425D02*
X189513Y1663625D01*
G01X193313Y1678643D02*
X191413Y1676443D01*
G01X196660Y1678643D02*
X193313D01*
G01X189513D02*
X186166D01*
G01X191413Y1676443D02*
X189513Y1678643D01*
G01X196807Y1685098D02*
Y1693760D01*
G01X186313Y1685098D02*
X196807D01*
G01X186313Y1693760D02*
Y1685098D01*
G01X196807Y1700216D02*
Y1708878D01*
G01X186313Y1700216D02*
X196807D01*
G01X186313Y1708878D02*
Y1700216D01*
G01X196807Y1693760D02*
X193460D01*
G01X189660D02*
X186313D01*
G01X191560Y1691560D02*
X189660Y1693760D01*
G01X193460D02*
X191560Y1691560D01*
G01X196807Y1708878D02*
X193460D01*
G01X189660D02*
X186313D01*
G01X191560Y1706678D02*
X189660Y1708878D01*
G01X193460D02*
X191560Y1706678D01*
G01X213400Y-601572D02*
X214200Y-602238D01*
X215100Y-602638D01*
X215900D01*
X216700Y-602238D01*
X217300Y-601572D01*
X217600Y-600638D01*
X217400Y-599705D01*
X216900Y-598905D01*
X216000Y-598371D01*
X214800Y-598105D01*
X214100Y-597571D01*
X213800Y-596638D01*
X214000Y-595705D01*
X214500Y-595038D01*
X215200Y-594638D01*
X215900D01*
X216600Y-594905D01*
X217200Y-595571D01*
G01X222300Y-594638D02*
X224700D01*
G01X223500D02*
Y-602638D01*
G01X222300D02*
X224700D01*
G01X229500Y-594638D02*
Y-602638D01*
X233500D01*
G01X237300D02*
Y-594638D01*
G01X241100D02*
X237300Y-599572D01*
G01X241700Y-602638D02*
X239000Y-597305D01*
G01X246200Y-599971D02*
X248800D01*
G01X256300Y-598371D02*
X256700Y-597971D01*
X257000Y-597305D01*
X257200Y-596371D01*
X257000Y-595571D01*
X256600Y-595038D01*
X255900Y-594638D01*
X253200D01*
Y-602638D01*
X256500D01*
X257200Y-602105D01*
X257600Y-601305D01*
X257800Y-600371D01*
X257600Y-599438D01*
X257000Y-598638D01*
X256300Y-598371D01*
X253200D01*
G01X263500Y-602638D02*
X262700Y-602505D01*
X262000Y-601971D01*
X261400Y-601171D01*
X261000Y-600238D01*
X260800Y-599171D01*
Y-598105D01*
X261000Y-597038D01*
X261400Y-596105D01*
X262000Y-595305D01*
X262700Y-594771D01*
X263500Y-594638D01*
X264300Y-594771D01*
X265000Y-595305D01*
X265600Y-596105D01*
X266000Y-597038D01*
X266200Y-598105D01*
Y-599171D01*
X266000Y-600238D01*
X265600Y-601171D01*
X265000Y-601971D01*
X264300Y-602505D01*
X263500Y-602638D01*
G01X271500Y-594638D02*
Y-602638D01*
G01X269200Y-594638D02*
X273800D01*
G01X202000Y-569638D02*
Y-577638D01*
X206000D01*
G01X213800D02*
Y-572305D01*
G01Y-573238D02*
X213400Y-572705D01*
X212800Y-572438D01*
X212100Y-572305D01*
X211400Y-572571D01*
X210800Y-573105D01*
X210400Y-573905D01*
X210200Y-574971D01*
X210400Y-576038D01*
X210800Y-576838D01*
X211400Y-577371D01*
X212100Y-577638D01*
X212800Y-577505D01*
X213400Y-577105D01*
X213800Y-576572D01*
G01X217900Y-580038D02*
X218500Y-580305D01*
X219300Y-580038D01*
X219800Y-579505D01*
X220200Y-578838D01*
X220800Y-576705D01*
X222100Y-572305D01*
G01X218900D02*
X220800Y-576705D01*
G01X226500Y-574038D02*
X229700D01*
X229400Y-573105D01*
X228900Y-572571D01*
X228200Y-572305D01*
X227500Y-572438D01*
X226900Y-572838D01*
X226500Y-573771D01*
X226300Y-574572D01*
Y-575371D01*
X226500Y-576171D01*
X227000Y-576971D01*
X227600Y-577505D01*
X228300Y-577638D01*
X229000Y-577371D01*
X229700Y-576572D01*
G01X234600Y-577638D02*
Y-572305D01*
G01Y-573371D02*
X235100Y-572838D01*
X235600Y-572438D01*
X236300Y-572305D01*
X236800Y-572438D01*
X237400Y-572838D01*
G01X202259Y749666D02*
Y752866D01*
G01X209259Y749666D02*
Y752866D01*
G01X203059Y749666D02*
X209259D01*
G01X203059Y752866D02*
Y749666D01*
G01X209259Y752866D02*
X203059D01*
G01X210268Y755505D02*
Y761505D01*
G01X211827Y755505D02*
X223827D01*
G01X211827Y761505D02*
Y755505D01*
G01X223827Y761505D02*
X211827D01*
G01X204362Y762166D02*
Y765366D01*
G01X204393Y765800D02*
Y769000D01*
G01X205093Y962566D02*
Y959366D01*
G01X211293Y962566D02*
X205093D01*
G01X211293Y959366D02*
Y962566D01*
G01X205093Y959366D02*
X211293D01*
G01X211358Y1300500D02*
X214458D01*
Y1301420D01*
X214303Y1301727D01*
X213941Y1301957D01*
X213528Y1302034D01*
X213115Y1301957D01*
X212805Y1301765D01*
X212650Y1301420D01*
Y1300500D01*
G01X214200Y1305210D02*
X214355Y1304980D01*
X214458Y1304712D01*
Y1304405D01*
X214303Y1304060D01*
X214045Y1303792D01*
X213735Y1303600D01*
X213218Y1303447D01*
X212753Y1303409D01*
X212288Y1303485D01*
X211978Y1303600D01*
X211668Y1303830D01*
X211461Y1304099D01*
X211358Y1304367D01*
Y1304635D01*
X211461Y1304904D01*
X211616Y1305134D01*
X211823Y1305325D01*
G01X211358Y1307927D02*
X214458D01*
X212236Y1306509D01*
Y1308425D01*
G01X211823Y1309724D02*
X211565Y1309954D01*
X211410Y1310222D01*
X211358Y1310567D01*
X211461Y1310912D01*
X211668Y1311180D01*
X212030Y1311372D01*
X212443Y1311410D01*
X212856Y1311334D01*
X213115Y1311142D01*
X213321Y1310874D01*
X213373Y1310605D01*
X213321Y1310337D01*
X213115Y1309992D01*
X214458Y1310107D01*
Y1311142D01*
G01Y1313667D02*
X214355Y1313360D01*
X214096Y1313130D01*
X213786Y1312977D01*
X213373Y1312862D01*
X212908Y1312824D01*
X212443Y1312862D01*
X212030Y1312977D01*
X211720Y1313130D01*
X211461Y1313360D01*
X211358Y1313667D01*
X211461Y1313974D01*
X211720Y1314204D01*
X212030Y1314357D01*
X212443Y1314472D01*
X212908Y1314510D01*
X213373Y1314472D01*
X213786Y1314357D01*
X214096Y1314204D01*
X214355Y1313974D01*
X214458Y1313667D01*
G01X207773Y1313500D02*
X210013D01*
G01X208800Y1311875D02*
Y1315125D01*
G01X203303Y1366114D02*
Y1372314D01*
G01X212217Y1371311D02*
Y1359311D01*
G01X218217Y1371311D02*
X212217D01*
G01Y1359311D02*
X218217D01*
G01X212217Y1374554D02*
X218217D01*
G01X212217Y1386554D02*
Y1374554D01*
G01X218217Y1386554D02*
X212217D01*
G01X211802Y1534538D02*
Y1540738D01*
G01X208602Y1534538D02*
X211802D01*
G01X208602Y1540738D02*
Y1534538D01*
G01X213326D02*
X216526D01*
G01X213326Y1540738D02*
Y1534538D01*
G01X203878Y1540738D02*
Y1534538D01*
X207078D01*
Y1540738D01*
X203878D01*
G01X211802D02*
X208602D01*
G01X216526D02*
X213326D01*
G01X214173Y1617677D02*
X304330D01*
G01X214173Y1630800D02*
Y1622300D01*
G01Y1710853D02*
Y1638700D01*
G01X202781Y1650854D02*
Y1654054D01*
G01Y1646854D02*
Y1650054D01*
G01X205260Y1667078D02*
Y1673278D01*
G01X202060Y1667078D02*
X205260D01*
G01X202060Y1673278D02*
Y1667078D01*
G01X205523Y1656570D02*
Y1659770D01*
G01X206060Y1667078D02*
X209260D01*
G01X206060Y1673278D02*
Y1667078D01*
G01X209260D02*
Y1673278D01*
G01X212358Y1656592D02*
Y1659792D01*
G01X206158Y1656592D02*
X212358D01*
G01X206158Y1659792D02*
Y1656592D01*
G01X212358Y1659792D02*
X206158D01*
G01X212130Y1662879D02*
Y1666079D01*
G01X205930Y1662879D02*
X212130D01*
G01X205930Y1666079D02*
Y1662879D01*
G01X212130Y1666079D02*
X205930D01*
G01X205181Y1662879D02*
Y1666079D01*
G01X223200Y1735367D02*
X215700D01*
Y1733127D01*
X216075Y1732380D01*
X216950Y1731820D01*
X217950Y1731633D01*
X218950Y1731820D01*
X219700Y1732287D01*
X220075Y1733127D01*
Y1735367D01*
G01X223200Y1727867D02*
X215700D01*
Y1725533D01*
X216075Y1724787D01*
X216575Y1724320D01*
X217575Y1724133D01*
X218575Y1724320D01*
X219200Y1724880D01*
X219575Y1725533D01*
Y1727867D01*
G01Y1725533D02*
X223200Y1724133D01*
G01Y1716633D02*
Y1720367D01*
X215700D01*
Y1716633D01*
G01X219325Y1718127D02*
Y1720367D01*
G01X222200Y1712960D02*
X222825Y1712213D01*
X223200Y1711373D01*
Y1710627D01*
X222825Y1709880D01*
X222200Y1709320D01*
X221325Y1709040D01*
X220450Y1709227D01*
X219700Y1709693D01*
X219200Y1710533D01*
X218950Y1711653D01*
X218450Y1712307D01*
X217575Y1712587D01*
X216700Y1712400D01*
X216075Y1711933D01*
X215700Y1711280D01*
Y1710627D01*
X215950Y1709973D01*
X216575Y1709413D01*
G01X222200Y1705460D02*
X222825Y1704713D01*
X223200Y1703873D01*
Y1703127D01*
X222825Y1702380D01*
X222200Y1701820D01*
X221325Y1701540D01*
X220450Y1701727D01*
X219700Y1702193D01*
X219200Y1703033D01*
X218950Y1704153D01*
X218450Y1704807D01*
X217575Y1705087D01*
X216700Y1704900D01*
X216075Y1704433D01*
X215700Y1703780D01*
Y1703127D01*
X215950Y1702473D01*
X216575Y1701913D01*
G01X220700Y1697213D02*
Y1694787D01*
G01X223200Y1690273D02*
X215700D01*
Y1686727D01*
G01X219325Y1688033D02*
Y1690273D01*
G01X215700Y1682120D02*
Y1679880D01*
G01Y1681000D02*
X223200D01*
G01Y1682120D02*
Y1679880D01*
G01X215700Y1673500D02*
X223200D01*
G01X215700Y1675647D02*
Y1671353D01*
G01X205260Y1673278D02*
X202060D01*
G01X202207Y1688395D02*
Y1682195D01*
G01D02*
X205407D01*
G01D02*
Y1688395D01*
G01X209260Y1673278D02*
X206060D01*
G01X209260Y1680278D02*
X206060D01*
G01X209260Y1674078D02*
Y1680278D01*
G01X206060Y1674078D02*
X209260D01*
G01X206060Y1680278D02*
Y1674078D01*
G01X205260Y1680278D02*
X202060D01*
G01Y1674078D02*
X205260D01*
G01X202060Y1680278D02*
Y1674078D01*
G01X205260D02*
Y1680278D01*
G01X209407Y1682195D02*
Y1688395D01*
G01X206207D02*
Y1682195D01*
G01D02*
X209407D01*
G01X205407Y1697313D02*
Y1703513D01*
G01X202207Y1697313D02*
X205407D01*
G01X202207Y1703513D02*
Y1697313D01*
G01X205407Y1688395D02*
X202207D01*
G01X206207Y1697313D02*
X209407D01*
G01X206207Y1703513D02*
Y1697313D01*
G01X209407D02*
Y1703513D01*
G01X205407Y1695395D02*
X202207D01*
G01X205407Y1689195D02*
Y1695395D01*
G01X202207Y1689195D02*
X205407D01*
G01X202207Y1695395D02*
Y1689195D01*
G01X209407Y1695395D02*
X206207D01*
G01X209407Y1689195D02*
Y1695395D01*
G01X206207Y1689195D02*
X209407D01*
G01X206207Y1695395D02*
Y1689195D01*
G01X209407Y1688395D02*
X206207D01*
G01X205407Y1703513D02*
X202207D01*
G01X209407D02*
X206207D01*
G01X205407Y1710513D02*
X202207D01*
G01X205407Y1704313D02*
Y1710513D01*
G01X202207Y1704313D02*
X205407D01*
G01X202207Y1710513D02*
Y1704313D01*
G01X209407Y1710513D02*
X206207D01*
G01Y1704313D02*
X209407D01*
G01X206207Y1710513D02*
Y1704313D01*
G01X209407D02*
Y1710513D01*
G01X214173Y1781456D02*
Y1715392D01*
G01X304330Y1781456D02*
X214173D01*
G01X226000Y-626038D02*
X226500Y-626838D01*
X227100Y-627371D01*
X227800Y-627638D01*
X228600Y-627371D01*
X229200Y-626838D01*
X229800Y-626038D01*
X230000Y-624971D01*
Y-619638D01*
G01X237800Y-627638D02*
Y-622305D01*
G01Y-623238D02*
X237400Y-622705D01*
X236800Y-622438D01*
X236100Y-622305D01*
X235400Y-622571D01*
X234800Y-623105D01*
X234400Y-623905D01*
X234200Y-624971D01*
X234400Y-626038D01*
X234800Y-626838D01*
X235400Y-627371D01*
X236100Y-627638D01*
X236800Y-627505D01*
X237400Y-627105D01*
X237800Y-626572D01*
G01X245600Y-622971D02*
X244900Y-622438D01*
X244300Y-622305D01*
X243500Y-622571D01*
X242900Y-623105D01*
X242500Y-624038D01*
X242400Y-624971D01*
X242500Y-625905D01*
X242900Y-626705D01*
X243500Y-627371D01*
X244300Y-627638D01*
X245000Y-627371D01*
X245600Y-626838D01*
G01X250300Y-627638D02*
Y-619638D01*
G01X253500Y-622305D02*
X250300Y-625371D01*
G01X251600Y-624171D02*
X253700Y-627638D01*
G01X227533Y582348D02*
X233733D01*
G01X227533Y585548D02*
Y582348D01*
G01X233733Y585548D02*
X227533D01*
G01X224915Y600556D02*
Y594556D01*
G01D02*
X236915D01*
G01Y592456D02*
X224915D01*
G01D02*
Y586456D01*
G01D02*
X236915D01*
G01Y600556D02*
X224915D01*
G01X236933Y608598D02*
X224933D01*
G01D02*
Y602598D01*
G01D02*
X236933D01*
G01X239969Y761505D02*
X227969D01*
G01Y755505D02*
X239969D01*
G01X227969Y761505D02*
Y755505D01*
G01X223827D02*
Y761505D01*
G01X230763Y762166D02*
X236963D01*
G01X230763Y765366D02*
Y762166D01*
G01X236963Y765366D02*
X230763D01*
G01Y769366D02*
Y766166D01*
G01X236963Y769366D02*
X230763D01*
G01Y766166D02*
X236963D01*
G01X217663Y762166D02*
X223863D01*
G01X217663Y765366D02*
Y762166D01*
G01X223863Y765366D02*
X217663D01*
G01X223863Y762166D02*
Y765366D01*
G01X217663Y768866D02*
Y765666D01*
G01X223863Y768866D02*
X217663D01*
G01Y765666D02*
X223863D01*
G01D02*
Y768866D01*
G01X230763Y769766D02*
X236963D01*
Y772966D01*
X230763D01*
Y769766D01*
G01X226015Y959366D02*
X232215D01*
G01X226015Y962566D02*
Y959366D01*
G01X232215Y962566D02*
X226015D01*
G01X217852Y1320303D02*
Y1355999D01*
G01X226994Y1325051D02*
X232994D01*
G01X226994Y1337051D02*
Y1325051D01*
G01X232994Y1337051D02*
X226994D01*
G01X227586Y1372437D02*
X230786D01*
G01X227586Y1378637D02*
Y1372437D01*
G01X230786D02*
Y1378637D01*
G01X218217Y1359311D02*
Y1371311D01*
G01X220595D02*
Y1359311D01*
G01X226595Y1371311D02*
X220595D01*
G01X226595Y1359311D02*
Y1371311D01*
G01X220595Y1359311D02*
X226595D01*
G01X230786Y1378637D02*
X227586D01*
G01X218217Y1374554D02*
Y1386554D01*
G01X222400Y1490412D02*
X219974D01*
G01X261838Y1508910D02*
X226098D01*
Y1491980D01*
X261838D01*
Y1508910D01*
G01X230240Y1490418D02*
X232666D01*
G01X221251Y1534538D02*
Y1540738D01*
G01X218051Y1534538D02*
X221251D01*
G01X218051Y1540738D02*
Y1534538D01*
G01X225975D02*
Y1540738D01*
G01X222775Y1534538D02*
X225975D01*
G01X222775Y1540738D02*
Y1534538D01*
G01X216526D02*
Y1540738D01*
G01X227500D02*
Y1534538D01*
X230700D01*
Y1540738D01*
X227500D01*
G01X221251D02*
X218051D01*
G01X225975D02*
X222775D01*
G01X231005Y1637825D02*
Y1640925D01*
X231465Y1640305D01*
G01Y1637825D02*
X230545D01*
G01X226435Y1645958D02*
Y1642858D01*
G01X227317Y1645958D02*
X225553D01*
G01X226435Y1657031D02*
X226742Y1657083D01*
X227010Y1657289D01*
X227240Y1657599D01*
X227393Y1657961D01*
X227470Y1658374D01*
Y1658788D01*
X227393Y1659201D01*
X227240Y1659563D01*
X227010Y1659873D01*
X226742Y1660079D01*
X226435Y1660131D01*
X226128Y1660079D01*
X225860Y1659873D01*
X225630Y1659563D01*
X225477Y1659201D01*
X225400Y1658788D01*
Y1658374D01*
X225477Y1657961D01*
X225630Y1657599D01*
X225860Y1657289D01*
X226128Y1657083D01*
X226435Y1657031D01*
G01X226128Y1657858D02*
X225668Y1657031D01*
G01X227202Y1652307D02*
Y1655407D01*
X226243D01*
X225937Y1655252D01*
X225745Y1655045D01*
X225668Y1654632D01*
X225745Y1654219D01*
X225975Y1653960D01*
X226243Y1653805D01*
X227202D01*
G01X226243D02*
X225668Y1652307D01*
G01X227240Y1647995D02*
X226933Y1647737D01*
X226588Y1647582D01*
X226282D01*
X225975Y1647737D01*
X225745Y1647995D01*
X225630Y1648357D01*
X225707Y1648719D01*
X225898Y1649029D01*
X226243Y1649235D01*
X226703Y1649339D01*
X226972Y1649545D01*
X227087Y1649907D01*
X227010Y1650269D01*
X226818Y1650527D01*
X226550Y1650682D01*
X226282D01*
X226013Y1650579D01*
X225783Y1650320D01*
G01X227317Y1671204D02*
Y1674304D01*
X225553Y1671204D01*
Y1674304D01*
G01X226435Y1666480D02*
X226742Y1666532D01*
X227010Y1666738D01*
X227240Y1667048D01*
X227393Y1667410D01*
X227470Y1667823D01*
Y1668237D01*
X227393Y1668650D01*
X227240Y1669012D01*
X227010Y1669322D01*
X226742Y1669528D01*
X226435Y1669580D01*
X226128Y1669528D01*
X225860Y1669322D01*
X225630Y1669012D01*
X225477Y1668650D01*
X225400Y1668237D01*
Y1667823D01*
X225477Y1667410D01*
X225630Y1667048D01*
X225860Y1666738D01*
X226128Y1666532D01*
X226435Y1666480D01*
G01X227202Y1661756D02*
Y1664856D01*
X226282D01*
X225975Y1664701D01*
X225745Y1664339D01*
X225668Y1663926D01*
X225745Y1663513D01*
X225937Y1663203D01*
X226282Y1663048D01*
X227202D01*
G01X227278Y1685378D02*
Y1688478D01*
G01X225822D02*
X227278Y1686566D01*
G01X225592Y1685378D02*
X226627Y1687445D01*
G01X227202Y1683753D02*
Y1680653D01*
X225668D01*
G01X227432Y1675929D02*
Y1679029D01*
X226435Y1676446D01*
X225438Y1679029D01*
Y1675929D01*
G01X227240Y1699551D02*
Y1702651D01*
G01X225630D02*
Y1699551D01*
G01Y1701101D02*
X227240D01*
G01X226895Y1697926D02*
X225975D01*
G01X226435D02*
Y1694826D01*
G01X226895D02*
X225975D01*
G01X227202Y1690722D02*
X227010Y1690412D01*
X226780Y1690205D01*
X226512Y1690102D01*
X226205Y1690205D01*
X225975Y1690412D01*
X225745Y1690722D01*
X225668Y1691135D01*
Y1693202D01*
G01X226205Y1705825D02*
X225438D01*
Y1704895D01*
X225668Y1704585D01*
X225937Y1704378D01*
X226320Y1704275D01*
X226703Y1704378D01*
X226972Y1704585D01*
X227202Y1704895D01*
X227355Y1705257D01*
X227432Y1705670D01*
Y1706032D01*
X227355Y1706342D01*
X227202Y1706703D01*
X226972Y1707013D01*
X226742Y1707220D01*
X226435Y1707375D01*
X226167D01*
X225860Y1707272D01*
X225630Y1707065D01*
G01X225668Y1713724D02*
X227202D01*
Y1716824D01*
X225668D01*
G01X226282Y1715326D02*
X227202D01*
G01X227163Y1709000D02*
Y1712100D01*
X225707D01*
G01X226243Y1710602D02*
X227163D01*
G01X227278Y1718448D02*
Y1721548D01*
X226512D01*
X226205Y1721393D01*
X225975Y1721186D01*
X225783Y1720876D01*
X225630Y1720515D01*
X225592Y1719998D01*
X225630Y1719481D01*
X225783Y1719120D01*
X225975Y1718810D01*
X226205Y1718603D01*
X226512Y1718448D01*
X227278D01*
G01X225592Y1726015D02*
X225822Y1726170D01*
X226090Y1726273D01*
X226397D01*
X226742Y1726118D01*
X227010Y1725860D01*
X227202Y1725550D01*
X227355Y1725033D01*
X227393Y1724568D01*
X227317Y1724103D01*
X227202Y1723793D01*
X226972Y1723483D01*
X226703Y1723276D01*
X226435Y1723173D01*
X226167D01*
X225898Y1723276D01*
X225668Y1723431D01*
X225477Y1723638D01*
G01X226128Y1729550D02*
X225975Y1729705D01*
X225860Y1729964D01*
X225783Y1730325D01*
X225860Y1730635D01*
X226013Y1730842D01*
X226282Y1730997D01*
X227317D01*
Y1727897D01*
X226052D01*
X225783Y1728104D01*
X225630Y1728414D01*
X225553Y1728775D01*
X225630Y1729137D01*
X225860Y1729447D01*
X226128Y1729550D01*
X227317D01*
G01X227393Y1732622D02*
X226435Y1735722D01*
X225477Y1732622D01*
G01X225822Y1733707D02*
X227048D01*
G01X239663Y29653D02*
Y35853D01*
G01X236463D02*
Y29653D01*
G01D02*
X239663D01*
G01X240620Y38462D02*
Y32262D01*
G01D02*
X243820D01*
G01D02*
Y38462D01*
G01D02*
X240620D01*
G01X244620D02*
Y32262D01*
G01D02*
X247820D01*
G01Y38462D02*
X244620D01*
G01X239663Y35853D02*
X236463D01*
G01X245205Y58240D02*
X248405D01*
G01X245205Y64440D02*
Y58240D01*
G01X243387D02*
Y64440D01*
G01X240187Y58240D02*
X243387D01*
G01X240187Y64440D02*
Y58240D01*
G01X248405Y64440D02*
X245205D01*
G01X243387D02*
X240187D01*
G01X245697Y110143D02*
X251897D01*
G01X245697Y113343D02*
Y110143D01*
G01X251897Y113343D02*
X245697D01*
G01X233733Y582348D02*
Y585548D01*
G01X236915Y594556D02*
Y600556D01*
G01Y586456D02*
Y592456D01*
G01X236933Y602598D02*
Y608598D01*
G01X249312Y670830D02*
X243312D01*
G01D02*
Y658830D01*
G01D02*
X249312D01*
G01X233227Y701173D02*
Y694973D01*
G01D02*
X236427D01*
G01D02*
Y701173D01*
G01D02*
X233227D01*
G01X237711Y692348D02*
X243711D01*
G01D02*
Y704348D01*
G01X237711D02*
Y692348D01*
G01X243711Y704348D02*
X237711D01*
G01X231603Y747480D02*
X234803D01*
G01X231603Y753680D02*
Y747480D01*
G01X234803Y753680D02*
X231603D01*
G01X234803Y747480D02*
Y753680D01*
G01X239969Y755505D02*
Y761505D01*
G01X236963Y762166D02*
Y765366D01*
G01Y766166D02*
Y769366D01*
G01X232215Y959366D02*
Y962566D01*
G01X244598Y997560D02*
X256803Y985749D01*
G01X244598Y1040868D02*
Y997560D01*
G01X256803Y1052679D02*
X244598Y1040868D01*
G01X241894Y1325051D02*
Y1337051D01*
G01X235894Y1325051D02*
X241894D01*
G01X235894Y1337051D02*
Y1325051D01*
G01X244058Y1325068D02*
X250058D01*
G01X244058Y1337068D02*
Y1325068D01*
G01X232994Y1325051D02*
Y1337051D01*
G01X241894D02*
X235894D01*
G01X250058Y1337068D02*
X244058D01*
G01X232903Y1366114D02*
X236103D01*
G01X232903Y1372314D02*
Y1366114D01*
G01X236103Y1372314D02*
X232903D01*
G01X236103Y1366114D02*
Y1372314D01*
G01X245017Y1371311D02*
Y1359311D01*
G01X251017Y1371311D02*
X245017D01*
G01Y1359311D02*
X251017D01*
G01X245017Y1374554D02*
X251017D01*
G01X245017Y1386554D02*
Y1374554D01*
G01X251017Y1386554D02*
X245017D01*
G01X249955Y1488824D02*
X250185Y1488979D01*
X250453Y1489082D01*
X250760D01*
X251105Y1488927D01*
X251373Y1488669D01*
X251565Y1488359D01*
X251718Y1487842D01*
X251756Y1487377D01*
X251680Y1486912D01*
X251565Y1486602D01*
X251335Y1486292D01*
X251066Y1486085D01*
X250798Y1485982D01*
X250530D01*
X250261Y1486085D01*
X250031Y1486240D01*
X249840Y1486447D01*
G01X247775Y1485982D02*
X247698Y1486654D01*
X247583Y1487222D01*
X247430Y1487739D01*
X247238Y1488307D01*
X246931Y1489082D01*
X248465D01*
G01X244598D02*
X244905Y1488979D01*
X245135Y1488720D01*
X245288Y1488410D01*
X245403Y1487997D01*
X245441Y1487532D01*
X245403Y1487067D01*
X245288Y1486654D01*
X245135Y1486344D01*
X244905Y1486085D01*
X244598Y1485982D01*
X244291Y1486085D01*
X244061Y1486344D01*
X243908Y1486654D01*
X243793Y1487067D01*
X243755Y1487532D01*
X243793Y1487997D01*
X243908Y1488410D01*
X244061Y1488720D01*
X244291Y1488979D01*
X244598Y1489082D01*
G01X242226Y1488565D02*
X241996Y1488875D01*
X241728Y1489030D01*
X241421Y1489082D01*
X241038Y1488979D01*
X240770Y1488720D01*
X240693Y1488410D01*
X240731Y1488100D01*
X240885Y1487842D01*
X241651Y1487325D01*
X241996Y1486964D01*
X242226Y1486447D01*
X242303Y1485982D01*
X240693D01*
G01X238398Y1489082D02*
X238705Y1488979D01*
X238935Y1488720D01*
X239088Y1488410D01*
X239203Y1487997D01*
X239241Y1487532D01*
X239203Y1487067D01*
X239088Y1486654D01*
X238935Y1486344D01*
X238705Y1486085D01*
X238398Y1485982D01*
X238091Y1486085D01*
X237861Y1486344D01*
X237708Y1486654D01*
X237593Y1487067D01*
X237555Y1487532D01*
X237593Y1487997D01*
X237708Y1488410D01*
X237861Y1488720D01*
X238091Y1488979D01*
X238398Y1489082D01*
G01X240148Y1534538D02*
Y1540738D01*
G01X236948Y1534538D02*
X240148D01*
G01X236948Y1540738D02*
Y1534538D01*
G01X244873D02*
Y1540738D01*
G01X241673Y1534538D02*
X244873D01*
G01X241673Y1540738D02*
Y1534538D01*
G01X240148Y1540738D02*
X236948D01*
G01X244873D02*
X241673D01*
G01X239607Y1640341D02*
X239377Y1640651D01*
X239109Y1640806D01*
X238802Y1640858D01*
X238419Y1640755D01*
X238151Y1640496D01*
X238074Y1640186D01*
X238112Y1639876D01*
X238266Y1639618D01*
X239032Y1639101D01*
X239377Y1638740D01*
X239607Y1638223D01*
X239684Y1637758D01*
X238074D01*
G01X247596Y1638445D02*
X247366Y1638083D01*
X247060Y1637877D01*
X246715Y1637825D01*
X246408Y1637877D01*
X246101Y1638135D01*
X245910Y1638445D01*
X245871Y1638755D01*
X245948Y1639117D01*
X246216Y1639375D01*
X246485Y1639478D01*
X246830D01*
G01X246485D02*
X246255Y1639633D01*
X246063Y1639892D01*
X245986Y1640202D01*
X246063Y1640512D01*
X246255Y1640770D01*
X246600Y1640925D01*
X246945Y1640873D01*
X247290Y1640667D01*
G01X252522Y38470D02*
Y32270D01*
G01D02*
X255722D01*
G01D02*
Y38470D01*
G01D02*
X252522D01*
G01X247820Y32262D02*
Y38462D01*
G01X248620D02*
Y32262D01*
G01D02*
X251820D01*
G01D02*
Y38462D01*
G01D02*
X248620D01*
G01X254300Y60800D02*
X260500D01*
G01X254300Y64000D02*
Y60800D01*
G01X260500D02*
Y64000D01*
G01X254300Y56800D02*
X260500D01*
G01X254300Y60000D02*
Y56800D01*
G01X260500Y60000D02*
X254300D01*
G01X260500Y56800D02*
Y60000D01*
G01X248405Y58240D02*
Y64440D01*
G01X260500Y64000D02*
X254300D01*
G01X249469Y75930D02*
X261469D01*
G01X249469Y81930D02*
Y75930D01*
G01X262666Y70826D02*
X250666D01*
G01Y64826D02*
X262666D01*
G01X250666Y70826D02*
Y64826D01*
G01X261469Y81930D02*
X249469D01*
G01X251897Y110143D02*
Y113343D01*
G01X250551Y644078D02*
X256551D01*
G01D02*
Y656078D01*
G01D02*
X250551D01*
G01D02*
Y644078D01*
G01X249312Y658830D02*
Y670830D01*
G01X257312D02*
X251312D01*
G01D02*
Y658830D01*
G01D02*
X257312D01*
G01D02*
Y670830D01*
G01X256157Y692228D02*
X262157D01*
G01X256157Y704228D02*
Y692228D01*
G01X246551D02*
X252551D01*
G01D02*
Y704228D01*
G01X246551D02*
Y692228D01*
G01X262157Y704228D02*
X256157D01*
G01X252551D02*
X246551D01*
G01X247371Y773988D02*
Y770788D01*
G01X253571Y773988D02*
X247371D01*
G01X253571Y770788D02*
Y773988D01*
G01X247371Y770788D02*
X253571D01*
G01X247371Y777988D02*
Y774788D01*
G01X253571D02*
Y777988D01*
G01X247371Y774788D02*
X253571D01*
G01Y777988D02*
X247371D01*
G01X256803Y820395D02*
G03X266645Y810553I9842J0D01*
G01X256803Y985749D02*
Y820395D01*
G01Y1218033D02*
Y1052679D01*
G01X266645Y1227875D02*
G03X256803Y1218033I0J-9842D01*
G01X250058Y1325068D02*
Y1337068D01*
G01X258558Y1325051D02*
Y1337051D01*
G01X252558Y1325051D02*
X258558D01*
G01X252558Y1337051D02*
Y1325051D01*
G01X258558Y1337051D02*
X252558D01*
G01X253395Y1371311D02*
Y1359311D01*
G01X259395Y1371311D02*
X253395D01*
G01X259395Y1359311D02*
Y1371311D01*
G01X253395Y1359311D02*
X259395D01*
G01X251017D02*
Y1371311D01*
G01Y1374554D02*
Y1386554D01*
G01X259133Y1489547D02*
X256893D01*
G01X258106Y1491172D02*
Y1487922D01*
G01X251122Y1540738D02*
Y1534538D01*
X254322D01*
Y1540738D01*
X251122D01*
G01X255846D02*
Y1534538D01*
X259046D01*
Y1540738D01*
X255846D01*
G01X246397D02*
Y1534538D01*
X249597D01*
Y1540738D01*
X246397D01*
G01X254167Y1637758D02*
Y1640858D01*
X255585Y1638636D01*
X253669D01*
G01X261469Y75930D02*
Y81930D01*
G01X262666Y64826D02*
Y70826D01*
G01X269953Y201603D02*
Y204703D01*
G01X268343D02*
Y201603D01*
G01Y203153D02*
X269953D01*
G01X266891Y202223D02*
X266661Y201861D01*
X266355Y201655D01*
X266010Y201603D01*
X265703Y201655D01*
X265396Y201913D01*
X265205Y202223D01*
X265166Y202533D01*
X265243Y202895D01*
X265511Y203153D01*
X265780Y203256D01*
X266125D01*
G01X265780D02*
X265550Y203411D01*
X265358Y203670D01*
X265281Y203980D01*
X265358Y204290D01*
X265550Y204548D01*
X265895Y204703D01*
X266240Y204651D01*
X266585Y204445D01*
G01X262948Y201603D02*
Y204703D01*
X263408Y204083D01*
G01Y201603D02*
X262488D01*
G01X271270Y657680D02*
Y651480D01*
G01D02*
X274470D01*
G01D02*
Y657680D01*
G01D02*
X271270D01*
G01X265953Y664003D02*
Y657803D01*
G01D02*
X269153D01*
G01D02*
Y664003D01*
G01D02*
X265953D01*
G01X262157Y692228D02*
Y704228D01*
G01X265281Y692228D02*
X271281D01*
G01D02*
Y704228D01*
G01X265281D02*
Y692228D01*
G01X271281Y704228D02*
X265281D01*
G01X271621Y735908D02*
Y723908D01*
G01D02*
X277621D01*
G01Y735908D02*
X271621D01*
G01X267671Y773810D02*
Y777010D01*
G01X261471Y773810D02*
X267671D01*
G01X261471Y777010D02*
Y773810D01*
G01X271471Y790388D02*
Y796588D01*
G01X268271Y790388D02*
X271471D01*
G01X268271Y796588D02*
Y790388D01*
G01X267671Y783188D02*
Y786388D01*
G01X261471Y783188D02*
X267671D01*
G01X261471Y786388D02*
Y783188D01*
G01X267671Y786388D02*
X261471D01*
G01X267671Y778988D02*
Y782188D01*
G01X261471Y778988D02*
X267671D01*
G01X261471Y782188D02*
Y778988D01*
G01X267671Y782188D02*
X261471D01*
G01X267671Y777010D02*
X261471D01*
G01X271471Y796588D02*
X268271D01*
G01X273171Y792388D02*
X279371D01*
G01X273171Y795588D02*
Y792388D01*
G01X279371Y795588D02*
X273171D01*
G01Y803488D02*
Y800288D01*
G01X279371Y803488D02*
X273171D01*
G01Y800288D02*
X279371D01*
G01X267371Y798088D02*
X270571D01*
G01X267371Y804288D02*
Y798088D01*
G01X270571Y804288D02*
X267371D01*
G01X270571Y798088D02*
Y804288D01*
G01X273171Y796388D02*
X279371D01*
G01X273171Y799588D02*
Y796388D01*
G01X279371Y799588D02*
X273171D01*
G01X336496Y810553D02*
X266645D01*
G01X336496Y1227875D02*
X266645D01*
G01X276238Y1268289D02*
X278478D01*
G01X277265Y1266664D02*
Y1269914D01*
G01X268703Y1274457D02*
X286419D01*
G01X268703Y1310153D02*
Y1274457D01*
G01X266932Y1311566D02*
Y1313992D01*
G01X286419Y1310153D02*
X268703D01*
G01X266503Y1319968D02*
X269703D01*
G01X266503Y1326168D02*
Y1319968D01*
G01X269703Y1326168D02*
X266503D01*
G01X269703Y1319968D02*
Y1326168D01*
G01X261186Y1326291D02*
X264386D01*
G01X261186Y1332491D02*
Y1326291D01*
G01X264386D02*
Y1332491D01*
G01D02*
X261186D01*
G01X262988Y1491979D02*
X261479Y1491983D01*
G01X263038Y1508912D02*
X263032Y1491929D01*
G01X262438Y1508912D02*
X262442Y1491937D01*
G01X261838Y1508912D02*
X261841Y1491972D01*
G01X275132Y1517953D02*
X281132D01*
G01X275132Y1529953D02*
Y1517953D01*
G01X274324D02*
Y1529953D01*
G01X268324Y1517953D02*
X274324D01*
G01X268324Y1529953D02*
Y1517953D01*
G01X270144Y1517277D02*
Y1510877D01*
G01D02*
X283024D01*
G01Y1517277D02*
X270144D01*
G01X263038Y1508912D02*
X261838D01*
G01X269046Y1532721D02*
X281046D01*
G01X269046Y1538721D02*
Y1532721D01*
G01X281132Y1529953D02*
X275132D01*
G01X274324D02*
X268324D01*
G01X261177Y1540738D02*
Y1534538D01*
X264377D01*
Y1540738D01*
X261177D01*
G01X269046Y1539575D02*
X281046D01*
G01X269046Y1545575D02*
Y1539575D01*
G01X281046Y1545575D02*
X269046D01*
G01X281046Y1538721D02*
X269046D01*
G01X271103Y1639050D02*
X270835Y1639411D01*
X270605Y1639618D01*
X270298Y1639721D01*
X270030Y1639618D01*
X269838Y1639411D01*
X269685Y1639101D01*
X269647Y1638740D01*
X269685Y1638430D01*
X269838Y1638120D01*
X270068Y1637861D01*
X270337Y1637758D01*
X270643Y1637861D01*
X270912Y1638171D01*
X271065Y1638636D01*
X271103Y1639153D01*
X271027Y1639825D01*
X270912Y1640186D01*
X270720Y1640548D01*
X270452Y1640806D01*
X270183Y1640858D01*
X269915Y1640755D01*
X269723Y1640496D01*
G01X263344Y1638290D02*
X263114Y1638032D01*
X262846Y1637877D01*
X262501Y1637825D01*
X262156Y1637928D01*
X261888Y1638135D01*
X261696Y1638497D01*
X261658Y1638910D01*
X261734Y1639323D01*
X261926Y1639582D01*
X262194Y1639788D01*
X262463Y1639840D01*
X262731Y1639788D01*
X263076Y1639582D01*
X262961Y1640925D01*
X261926D01*
G01X293241Y39020D02*
X287041D01*
G01D02*
Y35820D01*
G01D02*
X293241D01*
G01X289116Y47465D02*
Y41265D01*
G01D02*
X292316D01*
G01X284316D02*
Y47465D01*
G01X281116D02*
Y41265D01*
G01D02*
X284316D01*
G01X285116Y47465D02*
Y41265D01*
G01D02*
X288316D01*
G01D02*
Y47465D01*
G01X292316D02*
X289116D01*
G01X284316D02*
X281116D01*
G01X288316D02*
X285116D01*
G01X283181Y678528D02*
X289181D01*
G01D02*
Y690528D01*
G01X283181D02*
Y678528D01*
G01X293180Y705120D02*
Y702694D01*
G01X289181Y690528D02*
X283181D01*
G01X276042Y704871D02*
Y692871D01*
G01D02*
X282042D01*
G01D02*
Y704871D01*
G01X284042D02*
Y692871D01*
G01D02*
X290042D01*
G01D02*
Y704871D01*
G01X279523Y743610D02*
Y707914D01*
G01D02*
X297239D01*
G01X282042Y704871D02*
X276042D01*
G01X290042D02*
X284042D01*
G01X277621Y723908D02*
Y735908D01*
G01X289704Y749778D02*
X287464D01*
G01X288677Y751403D02*
Y748153D01*
G01X297239Y743610D02*
X279523D01*
G01X290340Y749023D02*
X293440D01*
Y749943D01*
X293285Y750250D01*
X292923Y750480D01*
X292510Y750557D01*
X292097Y750480D01*
X291787Y750288D01*
X291632Y749943D01*
Y749023D01*
G01X293182Y753733D02*
X293337Y753503D01*
X293440Y753235D01*
Y752928D01*
X293285Y752583D01*
X293027Y752315D01*
X292717Y752123D01*
X292200Y751970D01*
X291735Y751932D01*
X291270Y752008D01*
X290960Y752123D01*
X290650Y752353D01*
X290443Y752622D01*
X290340Y752890D01*
Y753158D01*
X290443Y753427D01*
X290598Y753657D01*
X290805Y753848D01*
G01X292923Y755262D02*
X293233Y755492D01*
X293388Y755760D01*
X293440Y756067D01*
X293337Y756450D01*
X293078Y756718D01*
X292768Y756795D01*
X292458Y756757D01*
X292200Y756603D01*
X291683Y755837D01*
X291322Y755492D01*
X290805Y755262D01*
X290340Y755185D01*
Y756795D01*
G01Y759013D02*
X291012Y759090D01*
X291580Y759205D01*
X292097Y759358D01*
X292665Y759550D01*
X293440Y759857D01*
Y758323D01*
G01X290702Y761538D02*
X290443Y761807D01*
X290340Y762113D01*
X290443Y762420D01*
X290753Y762688D01*
X291218Y762880D01*
X291683Y762957D01*
X292252D01*
X292717Y762880D01*
X293130Y762688D01*
X293337Y762458D01*
X293440Y762190D01*
X293337Y761883D01*
X293130Y761653D01*
X292820Y761500D01*
X292407Y761423D01*
X292045Y761500D01*
X291683Y761692D01*
X291477Y761922D01*
X291425Y762190D01*
X291528Y762497D01*
X291787Y762727D01*
X292252Y762957D01*
G01X279371Y792388D02*
Y795588D01*
G01Y800288D02*
Y803488D01*
G01Y796388D02*
Y799588D01*
G01X280651Y805648D02*
Y802448D01*
G01X286851Y805648D02*
X280651D01*
G01X286851Y802448D02*
Y805648D01*
G01X280651Y802448D02*
X286851D01*
G01X277395Y1252304D02*
X280495D01*
Y1253224D01*
X280340Y1253531D01*
X279978Y1253761D01*
X279565Y1253838D01*
X279152Y1253761D01*
X278842Y1253569D01*
X278687Y1253224D01*
Y1252304D01*
G01X280237Y1257014D02*
X280392Y1256784D01*
X280495Y1256516D01*
Y1256209D01*
X280340Y1255864D01*
X280082Y1255596D01*
X279772Y1255404D01*
X279255Y1255251D01*
X278790Y1255213D01*
X278325Y1255289D01*
X278015Y1255404D01*
X277705Y1255634D01*
X277498Y1255903D01*
X277395Y1256171D01*
Y1256439D01*
X277498Y1256708D01*
X277653Y1256938D01*
X277860Y1257129D01*
G01X278015Y1258428D02*
X277653Y1258658D01*
X277447Y1258964D01*
X277395Y1259309D01*
X277447Y1259616D01*
X277705Y1259923D01*
X278015Y1260114D01*
X278325Y1260153D01*
X278687Y1260076D01*
X278945Y1259808D01*
X279048Y1259539D01*
Y1259194D01*
G01Y1259539D02*
X279203Y1259769D01*
X279462Y1259961D01*
X279772Y1260038D01*
X280082Y1259961D01*
X280340Y1259769D01*
X280495Y1259424D01*
X280443Y1259079D01*
X280237Y1258734D01*
G01X277395Y1262371D02*
X277447Y1262639D01*
X277602Y1262946D01*
X277860Y1263138D01*
X278222Y1263214D01*
X278583Y1263138D01*
X278893Y1262908D01*
X279048Y1262563D01*
Y1262179D01*
X279152Y1261949D01*
X279410Y1261758D01*
X279772Y1261681D01*
X280133Y1261796D01*
X280392Y1262064D01*
X280495Y1262371D01*
X280392Y1262678D01*
X280133Y1262946D01*
X279772Y1263061D01*
X279410Y1262984D01*
X279152Y1262793D01*
X279048Y1262563D01*
Y1262179D01*
X278893Y1261834D01*
X278583Y1261604D01*
X278222Y1261528D01*
X277860Y1261604D01*
X277602Y1261796D01*
X277447Y1262103D01*
X277395Y1262371D01*
G01Y1265394D02*
X278067Y1265471D01*
X278635Y1265586D01*
X279152Y1265739D01*
X279720Y1265931D01*
X280495Y1266238D01*
Y1264704D01*
G01X286419Y1274457D02*
Y1310153D01*
G01X290221Y1278378D02*
X296221D01*
G01X290221Y1290378D02*
Y1278378D01*
G01X296221Y1290378D02*
X290221D01*
G01X278617Y1325165D02*
Y1313165D01*
G01X284617D02*
Y1325165D01*
G01X278617Y1313165D02*
X284617D01*
G01X286995Y1325165D02*
Y1313165D01*
G01D02*
X292995D01*
G01X284617Y1325165D02*
X278617D01*
G01X292995D02*
X286995D01*
G01X284617Y1328408D02*
Y1340408D01*
G01X278617Y1328408D02*
X284617D01*
G01X278617Y1340408D02*
Y1328408D01*
G01X284617Y1340408D02*
X278617D01*
G01X286071Y1519522D02*
X289271D01*
G01X286071Y1525722D02*
Y1519522D01*
G01X289271D02*
Y1525722D01*
G01X282071Y1519522D02*
X285271D01*
G01X282071Y1525722D02*
Y1519522D01*
G01X285271D02*
Y1525722D01*
G01X281132Y1517953D02*
Y1529953D01*
G01X283024Y1517277D02*
Y1510877D01*
G01X289271Y1525722D02*
X286071D01*
G01X285271D02*
X282071D01*
G01X281046Y1532721D02*
Y1538721D01*
G01X289068Y1534746D02*
X301068D01*
G01X289068Y1540746D02*
Y1534746D01*
G01X301042Y1533892D02*
X289042D01*
G01Y1527892D02*
X301042D01*
G01X289042Y1533892D02*
Y1527892D01*
G01X282286Y1540146D02*
Y1528146D01*
G01X288286D02*
Y1540146D01*
G01X282286Y1528146D02*
X288286D01*
G01X280004Y1550499D02*
Y1545899D01*
G01X290204Y1550499D02*
X280004D01*
G01X290204Y1545899D02*
Y1550499D01*
G01X280004Y1545899D02*
X290204D01*
G01X285804Y1550499D02*
Y1545899D01*
G01X296004Y1550499D02*
X285804D01*
G01Y1545899D02*
X296004D01*
G01X281046Y1539575D02*
Y1545575D01*
G01X301068Y1540746D02*
X289068D01*
G01X288286Y1540146D02*
X282286D01*
G01X278326Y1637825D02*
X278249Y1638497D01*
X278134Y1639065D01*
X277981Y1639582D01*
X277789Y1640150D01*
X277482Y1640925D01*
X279016D01*
G01X284000Y1638100D02*
X283732Y1638152D01*
X283425Y1638307D01*
X283233Y1638565D01*
X283157Y1638927D01*
X283233Y1639288D01*
X283463Y1639598D01*
X283808Y1639753D01*
X284192D01*
X284422Y1639857D01*
X284613Y1640115D01*
X284690Y1640477D01*
X284575Y1640838D01*
X284307Y1641097D01*
X284000Y1641200D01*
X283693Y1641097D01*
X283425Y1640838D01*
X283310Y1640477D01*
X283387Y1640115D01*
X283578Y1639857D01*
X283808Y1639753D01*
X284192D01*
X284537Y1639598D01*
X284767Y1639288D01*
X284843Y1638927D01*
X284767Y1638565D01*
X284575Y1638307D01*
X284268Y1638152D01*
X284000Y1638100D01*
G01X281103Y1646023D02*
Y1666000D01*
G01X287300Y1646023D02*
X281103D01*
G01Y1737400D02*
Y1781456D01*
G01D02*
X371260D01*
G01X291920Y19837D02*
Y13637D01*
G01D02*
X295120D01*
G01D02*
Y19837D01*
G01X299120Y13637D02*
Y19837D01*
G01X295920D02*
Y13637D01*
G01D02*
X299120D01*
G01X295120Y19837D02*
X291920D01*
G01X299120D02*
X295920D01*
G01X302120Y47462D02*
Y41262D01*
G01D02*
X305320D01*
G01D02*
Y47462D01*
G01X294041Y35820D02*
X300241D01*
G01D02*
Y39020D01*
G01D02*
X294041D01*
G01D02*
Y35820D01*
G01X293241D02*
Y39020D01*
G01X292316Y41265D02*
Y47465D01*
G01X298420Y47462D02*
Y41262D01*
G01D02*
X301620D01*
G01D02*
Y47462D01*
G01X305320D02*
X302120D01*
G01X301620D02*
X298420D01*
G01X298915Y581354D02*
Y587554D01*
G01X295715D02*
Y581354D01*
G01D02*
X298915D01*
G01Y587554D02*
X295715D01*
G01X304000Y691921D02*
Y685721D01*
G01D02*
X307200D01*
G01Y691921D02*
X304000D01*
G01X298683Y698244D02*
Y692044D01*
G01D02*
X301883D01*
G01D02*
Y698244D01*
G01D02*
X298683D01*
G01X297239Y707914D02*
Y743610D01*
G01X299181Y739528D02*
Y727528D01*
G01X305181D02*
Y739528D01*
G01X299181Y727528D02*
X305181D01*
G01Y739528D02*
X299181D01*
G01X298125Y1274457D02*
X315841D01*
G01X298125Y1310153D02*
Y1274457D01*
G01X296221Y1278378D02*
Y1290378D01*
G01X300292Y1312445D02*
Y1314871D01*
G01X315841Y1310153D02*
X298125D01*
G01X292995Y1313165D02*
Y1325165D01*
G01X294082Y1326263D02*
X297282D01*
G01X294082Y1332463D02*
Y1326263D01*
G01X297282D02*
Y1332463D01*
G01X299399Y1319940D02*
X302599D01*
G01X299399Y1326140D02*
Y1319940D01*
G01X302599Y1326140D02*
X299399D01*
G01X302599Y1319940D02*
Y1326140D01*
G01X297282Y1332463D02*
X294082D01*
G01X301372Y1503938D02*
Y1497938D01*
X313372D01*
Y1503938D01*
X301372D01*
G01X301068Y1534746D02*
Y1540746D01*
G01X301042Y1527892D02*
Y1533892D01*
G01X296004Y1545899D02*
Y1550499D01*
G01X304330Y1617677D02*
Y1638000D01*
G01X304759Y1668940D02*
X304449Y1668710D01*
X304294Y1668442D01*
X304242Y1668135D01*
X304345Y1667752D01*
X304604Y1667484D01*
X304914Y1667407D01*
X305224Y1667445D01*
X305482Y1667599D01*
X305999Y1668365D01*
X306360Y1668710D01*
X306877Y1668940D01*
X307342Y1669017D01*
Y1667407D01*
G01X299468Y1668212D02*
X296368D01*
X296988Y1668672D01*
G01X299468D02*
Y1667752D01*
G01X294715Y1673177D02*
X291615D01*
X294715Y1671413D01*
X291615D01*
G01X294715Y1678016D02*
X291615D01*
X294198Y1677019D01*
X291615Y1676022D01*
X294715D01*
G01X291615Y1682510D02*
X294715D01*
Y1680976D01*
G01Y1687311D02*
X291615D01*
G01Y1685855D02*
X293527Y1687311D01*
G01X294715Y1685625D02*
X292648Y1686660D01*
G01X294709Y1701017D02*
X291609D01*
G01Y1699407D02*
X294709D01*
G01X293159D02*
Y1701017D01*
G01X294095Y1691959D02*
X294405Y1691767D01*
X294612Y1691537D01*
X294715Y1691269D01*
X294612Y1690962D01*
X294405Y1690732D01*
X294095Y1690502D01*
X293682Y1690425D01*
X291615D01*
G01Y1696377D02*
Y1695457D01*
G01Y1695917D02*
X294715D01*
G01Y1696377D02*
Y1695457D01*
G01X293059Y1704782D02*
Y1704015D01*
X293989D01*
X294299Y1704245D01*
X294506Y1704514D01*
X294609Y1704897D01*
X294506Y1705280D01*
X294299Y1705549D01*
X293989Y1705779D01*
X293627Y1705932D01*
X293214Y1706009D01*
X292852D01*
X292542Y1705932D01*
X292181Y1705779D01*
X291871Y1705549D01*
X291664Y1705319D01*
X291509Y1705012D01*
Y1704744D01*
X291612Y1704437D01*
X291819Y1704207D01*
G01X294715Y1710818D02*
X291615D01*
Y1709362D01*
G01X293113Y1709898D02*
Y1710818D01*
G01X294715Y1714047D02*
Y1715581D01*
X291615D01*
Y1714047D01*
G01X293113Y1714661D02*
Y1715581D01*
G01X294715Y1720382D02*
X291615D01*
Y1719616D01*
X291770Y1719309D01*
X291977Y1719079D01*
X292287Y1718887D01*
X292648Y1718734D01*
X293165Y1718696D01*
X293682Y1718734D01*
X294043Y1718887D01*
X294353Y1719079D01*
X294560Y1719309D01*
X294715Y1719616D01*
Y1720382D01*
G01X291873Y1723420D02*
X291718Y1723650D01*
X291615Y1723918D01*
Y1724225D01*
X291770Y1724570D01*
X292028Y1724838D01*
X292338Y1725030D01*
X292855Y1725183D01*
X293320Y1725221D01*
X293785Y1725145D01*
X294095Y1725030D01*
X294405Y1724800D01*
X294612Y1724531D01*
X294715Y1724263D01*
Y1723995D01*
X294612Y1723726D01*
X294457Y1723496D01*
X294250Y1723305D01*
G01X293062Y1728681D02*
X292907Y1728528D01*
X292648Y1728413D01*
X292287Y1728336D01*
X291977Y1728413D01*
X291770Y1728566D01*
X291615Y1728835D01*
Y1729870D01*
X294715D01*
Y1728605D01*
X294508Y1728336D01*
X294198Y1728183D01*
X293837Y1728106D01*
X293475Y1728183D01*
X293165Y1728413D01*
X293062Y1728681D01*
Y1729870D01*
G01X294509Y1735170D02*
X291409Y1734212D01*
X294509Y1733254D01*
G01X293424Y1733599D02*
Y1734825D01*
G01X304330Y1737400D02*
Y1781456D01*
G01X313316Y41265D02*
Y47465D01*
G01X310116D02*
Y41265D01*
G01D02*
X313316D01*
G01X309316D02*
Y47465D01*
G01X306116D02*
Y41265D01*
G01D02*
X309316D01*
G01X313316Y47465D02*
X310116D01*
G01X309316D02*
X306116D01*
G01X307200Y685721D02*
Y691921D01*
G01X315651Y698578D02*
X321651D01*
G01X315651Y710578D02*
Y698578D01*
G01X308912Y725121D02*
Y713121D01*
G01D02*
X314912D01*
G01D02*
Y725121D01*
G01X316912D02*
Y713121D01*
G01D02*
X322912D01*
G01X321651Y710578D02*
X315651D01*
G01X318093Y728064D02*
X335809D01*
G01X318093Y763760D02*
Y728064D01*
G01X314912Y725121D02*
X308912D01*
G01X322912D02*
X316912D01*
G01X309051Y759378D02*
Y747378D01*
G01X315051Y759378D02*
X309051D01*
G01X315051Y747378D02*
Y759378D01*
G01X309051Y747378D02*
X315051D01*
G01X321227Y769029D02*
X324327D01*
Y769949D01*
X324172Y770256D01*
X323810Y770486D01*
X323397Y770563D01*
X322984Y770486D01*
X322674Y770294D01*
X322519Y769949D01*
Y769029D01*
G01X324069Y773739D02*
X324224Y773509D01*
X324327Y773241D01*
Y772934D01*
X324172Y772589D01*
X323914Y772321D01*
X323604Y772129D01*
X323087Y771976D01*
X322622Y771938D01*
X322157Y772014D01*
X321847Y772129D01*
X321537Y772359D01*
X321330Y772628D01*
X321227Y772896D01*
Y773164D01*
X321330Y773433D01*
X321485Y773663D01*
X321692Y773854D01*
G01X323810Y775268D02*
X324120Y775498D01*
X324275Y775766D01*
X324327Y776073D01*
X324224Y776456D01*
X323965Y776724D01*
X323655Y776801D01*
X323345Y776763D01*
X323087Y776609D01*
X322570Y775843D01*
X322209Y775498D01*
X321692Y775268D01*
X321227Y775191D01*
Y776801D01*
G01Y779019D02*
X321899Y779096D01*
X322467Y779211D01*
X322984Y779364D01*
X323552Y779556D01*
X324327Y779863D01*
Y778329D01*
G01X321227Y782119D02*
X321899Y782196D01*
X322467Y782311D01*
X322984Y782464D01*
X323552Y782656D01*
X324327Y782963D01*
Y781429D01*
G01X335809Y763760D02*
X318093D01*
G01X311000Y1253383D02*
X314100D01*
Y1254303D01*
X313945Y1254610D01*
X313583Y1254840D01*
X313170Y1254917D01*
X312757Y1254840D01*
X312447Y1254648D01*
X312292Y1254303D01*
Y1253383D01*
G01X313842Y1258093D02*
X313997Y1257863D01*
X314100Y1257595D01*
Y1257288D01*
X313945Y1256943D01*
X313687Y1256675D01*
X313377Y1256483D01*
X312860Y1256330D01*
X312395Y1256292D01*
X311930Y1256368D01*
X311620Y1256483D01*
X311310Y1256713D01*
X311103Y1256982D01*
X311000Y1257250D01*
Y1257518D01*
X311103Y1257787D01*
X311258Y1258017D01*
X311465Y1258208D01*
G01X311620Y1259507D02*
X311258Y1259737D01*
X311052Y1260043D01*
X311000Y1260388D01*
X311052Y1260695D01*
X311310Y1261002D01*
X311620Y1261193D01*
X311930Y1261232D01*
X312292Y1261155D01*
X312550Y1260887D01*
X312653Y1260618D01*
Y1260273D01*
G01Y1260618D02*
X312808Y1260848D01*
X313067Y1261040D01*
X313377Y1261117D01*
X313687Y1261040D01*
X313945Y1260848D01*
X314100Y1260503D01*
X314048Y1260158D01*
X313842Y1259813D01*
G01X311000Y1263450D02*
X311052Y1263718D01*
X311207Y1264025D01*
X311465Y1264217D01*
X311827Y1264293D01*
X312188Y1264217D01*
X312498Y1263987D01*
X312653Y1263642D01*
Y1263258D01*
X312757Y1263028D01*
X313015Y1262837D01*
X313377Y1262760D01*
X313738Y1262875D01*
X313997Y1263143D01*
X314100Y1263450D01*
X313997Y1263757D01*
X313738Y1264025D01*
X313377Y1264140D01*
X313015Y1264063D01*
X312757Y1263872D01*
X312653Y1263642D01*
Y1263258D01*
X312498Y1262913D01*
X312188Y1262683D01*
X311827Y1262607D01*
X311465Y1262683D01*
X311207Y1262875D01*
X311052Y1263182D01*
X311000Y1263450D01*
G01Y1266550D02*
X311052Y1266818D01*
X311207Y1267125D01*
X311465Y1267317D01*
X311827Y1267393D01*
X312188Y1267317D01*
X312498Y1267087D01*
X312653Y1266742D01*
Y1266358D01*
X312757Y1266128D01*
X313015Y1265937D01*
X313377Y1265860D01*
X313738Y1265975D01*
X313997Y1266243D01*
X314100Y1266550D01*
X313997Y1266857D01*
X313738Y1267125D01*
X313377Y1267240D01*
X313015Y1267163D01*
X312757Y1266972D01*
X312653Y1266742D01*
Y1266358D01*
X312498Y1266013D01*
X312188Y1265783D01*
X311827Y1265707D01*
X311465Y1265783D01*
X311207Y1265975D01*
X311052Y1266282D01*
X311000Y1266550D01*
G01X308551Y1268513D02*
X310791D01*
G01X309578Y1266888D02*
Y1270138D01*
G01X315841Y1274457D02*
Y1310153D01*
G01X317954Y1278694D02*
X323954D01*
G01X317954Y1290694D02*
Y1278694D01*
G01X323954Y1290694D02*
X317954D01*
G01X311513Y1325137D02*
Y1313137D01*
G01X317513D02*
Y1325137D01*
G01X311513Y1313137D02*
X317513D01*
G01X319891Y1325137D02*
Y1313137D01*
G01D02*
X325891D01*
G01X317513Y1325137D02*
X311513D01*
G01X325891D02*
X319891D01*
G01X317513Y1328380D02*
Y1340380D01*
G01X311513Y1328380D02*
X317513D01*
G01X311513Y1340380D02*
Y1328380D01*
G01X317513Y1340380D02*
X311513D01*
G01X319759Y1489123D02*
X321999D01*
G01X320786Y1487498D02*
Y1490748D01*
G01X316874Y1491980D02*
X352614D01*
Y1508910D01*
X316874D01*
Y1491980D01*
G01X315674Y1491978D02*
X316874D01*
G01X315674D02*
X315680Y1508961D01*
G01X316274Y1491978D02*
X316270Y1508953D01*
G01X316874Y1491978D02*
X316871Y1508918D01*
G01X315724Y1508911D02*
X317233Y1508907D01*
G01X316241Y1534538D02*
Y1540738D01*
G01X313041Y1534538D02*
X316241D01*
G01X313041Y1540738D02*
Y1534538D01*
G01X317766Y1540738D02*
Y1534538D01*
X320966D01*
Y1540738D01*
X317766D01*
G01X309483Y1543812D02*
Y1537612D01*
G01X312683Y1543812D02*
X309483D01*
G01X312683Y1537612D02*
Y1543812D01*
G01X309483Y1537612D02*
X312683D01*
G01X316241Y1540738D02*
X313041D01*
G01X371260Y1646023D02*
X310200D01*
G01X323090Y1667752D02*
X319990D01*
X322212Y1669170D01*
Y1667254D01*
G01X314596Y1669055D02*
X314958Y1668825D01*
X315164Y1668519D01*
X315216Y1668174D01*
X315164Y1667867D01*
X314906Y1667560D01*
X314596Y1667369D01*
X314286Y1667330D01*
X313924Y1667407D01*
X313666Y1667675D01*
X313563Y1667944D01*
Y1668289D01*
G01Y1667944D02*
X313408Y1667714D01*
X313149Y1667522D01*
X312839Y1667445D01*
X312529Y1667522D01*
X312271Y1667714D01*
X312116Y1668059D01*
X312168Y1668404D01*
X312374Y1668749D01*
G01X328600Y-620971D02*
X329200Y-620171D01*
X329900Y-619771D01*
X330700Y-619638D01*
X331700Y-619905D01*
X332400Y-620571D01*
X332600Y-621371D01*
X332500Y-622172D01*
X332100Y-622838D01*
X330100Y-624171D01*
X329200Y-625105D01*
X328600Y-626438D01*
X328400Y-627638D01*
X332600D01*
G01X338500Y-619638D02*
X337700Y-619905D01*
X337100Y-620571D01*
X336700Y-621371D01*
X336400Y-622438D01*
X336300Y-623638D01*
X336400Y-624838D01*
X336700Y-625905D01*
X337100Y-626705D01*
X337700Y-627371D01*
X338500Y-627638D01*
X339300Y-627371D01*
X339900Y-626705D01*
X340300Y-625905D01*
X340600Y-624838D01*
X340700Y-623638D01*
X340600Y-622438D01*
X340300Y-621371D01*
X339900Y-620571D01*
X339300Y-619905D01*
X338500Y-619638D01*
G01X344600Y-620971D02*
X345200Y-620171D01*
X345900Y-619771D01*
X346700Y-619638D01*
X347700Y-619905D01*
X348400Y-620571D01*
X348600Y-621371D01*
X348500Y-622172D01*
X348100Y-622838D01*
X346100Y-624171D01*
X345200Y-625105D01*
X344600Y-626438D01*
X344400Y-627638D01*
X348600D01*
G01X352300Y-626038D02*
X352900Y-626971D01*
X353700Y-627505D01*
X354600Y-627638D01*
X355400Y-627505D01*
X356200Y-626838D01*
X356700Y-626038D01*
X356800Y-625238D01*
X356600Y-624305D01*
X355900Y-623638D01*
X355200Y-623371D01*
X354300D01*
G01X355200D02*
X355800Y-622971D01*
X356300Y-622305D01*
X356500Y-621505D01*
X356300Y-620705D01*
X355800Y-620038D01*
X354900Y-619638D01*
X354000Y-619771D01*
X353100Y-620305D01*
G01X360700Y-627905D02*
X364300Y-619638D01*
G01X370500D02*
X369700Y-619905D01*
X369100Y-620571D01*
X368700Y-621371D01*
X368400Y-622438D01*
X368300Y-623638D01*
X368400Y-624838D01*
X368700Y-625905D01*
X369100Y-626705D01*
X369700Y-627371D01*
X370500Y-627638D01*
X371300Y-627371D01*
X371900Y-626705D01*
X372300Y-625905D01*
X372600Y-624838D01*
X372700Y-623638D01*
X372600Y-622438D01*
X372300Y-621371D01*
X371900Y-620571D01*
X371300Y-619905D01*
X370500Y-619638D01*
G01X379700Y-627638D02*
Y-619638D01*
X376000Y-625371D01*
X381000D01*
G01X384700Y-627905D02*
X388300Y-619638D01*
G01X394500Y-627638D02*
Y-619638D01*
X393300Y-621238D01*
G01Y-627638D02*
X395700D01*
G01X402300D02*
X402500Y-625905D01*
X402800Y-624438D01*
X403200Y-623105D01*
X403700Y-621638D01*
X404500Y-619638D01*
X400500D01*
G01X328300Y-602638D02*
Y-594638D01*
X330300D01*
X331100Y-595038D01*
X331700Y-595571D01*
X332200Y-596371D01*
X332600Y-597305D01*
X332700Y-598638D01*
X332600Y-599971D01*
X332200Y-600905D01*
X331700Y-601705D01*
X331100Y-602238D01*
X330300Y-602638D01*
X328300D01*
G01X336000D02*
X338500Y-594638D01*
X341000Y-602638D01*
G01X340100Y-599838D02*
X336900D01*
G01X344600Y-602638D02*
Y-594638D01*
X348400D01*
G01X347000Y-598505D02*
X344600D01*
G01X354500Y-594638D02*
X353700Y-594905D01*
X353100Y-595571D01*
X352700Y-596371D01*
X352400Y-597438D01*
X352300Y-598638D01*
X352400Y-599838D01*
X352700Y-600905D01*
X353100Y-601705D01*
X353700Y-602371D01*
X354500Y-602638D01*
X355300Y-602371D01*
X355900Y-601705D01*
X356300Y-600905D01*
X356600Y-599838D01*
X356700Y-598638D01*
X356600Y-597438D01*
X356300Y-596371D01*
X355900Y-595571D01*
X355300Y-594905D01*
X354500Y-594638D01*
G01X362500D02*
Y-602638D01*
G01X360200Y-594638D02*
X364800D01*
G01X367900Y-602638D02*
Y-594638D01*
X370500Y-601305D01*
X373100Y-594638D01*
Y-602638D01*
G01X379300Y-598371D02*
X379700Y-597971D01*
X380000Y-597305D01*
X380200Y-596371D01*
X380000Y-595571D01*
X379600Y-595038D01*
X378900Y-594638D01*
X376200D01*
Y-602638D01*
X379500D01*
X380200Y-602105D01*
X380600Y-601305D01*
X380800Y-600371D01*
X380600Y-599438D01*
X380000Y-598638D01*
X379300Y-598371D01*
X376200D01*
G01X384300Y-601038D02*
X384900Y-601971D01*
X385700Y-602505D01*
X386600Y-602638D01*
X387400Y-602505D01*
X388200Y-601838D01*
X388700Y-601038D01*
X388800Y-600238D01*
X388600Y-599305D01*
X387900Y-598638D01*
X387200Y-598371D01*
X386300D01*
G01X387200D02*
X387800Y-597971D01*
X388300Y-597305D01*
X388500Y-596505D01*
X388300Y-595705D01*
X387800Y-595038D01*
X386900Y-594638D01*
X386000Y-594771D01*
X385100Y-595305D01*
G01X393300Y-594638D02*
X395700D01*
G01X394500D02*
Y-602638D01*
G01X393300D02*
X395700D01*
G01X404700Y-595305D02*
X404100Y-594905D01*
X403400Y-594638D01*
X402600D01*
X401700Y-595038D01*
X401000Y-595705D01*
X400500Y-596505D01*
X400100Y-597838D01*
X400000Y-599038D01*
X400200Y-600238D01*
X400500Y-601038D01*
X401100Y-601838D01*
X401800Y-602371D01*
X402500Y-602638D01*
X403200D01*
X403900Y-602371D01*
X404500Y-601971D01*
X405000Y-601438D01*
G01X410500Y-594638D02*
X409700Y-594905D01*
X409100Y-595571D01*
X408700Y-596371D01*
X408400Y-597438D01*
X408300Y-598638D01*
X408400Y-599838D01*
X408700Y-600905D01*
X409100Y-601705D01*
X409700Y-602371D01*
X410500Y-602638D01*
X411300Y-602371D01*
X411900Y-601705D01*
X412300Y-600905D01*
X412600Y-599838D01*
X412700Y-598638D01*
X412600Y-597438D01*
X412300Y-596371D01*
X411900Y-595571D01*
X411300Y-594905D01*
X410500Y-594638D01*
G01X334900Y584100D02*
Y580900D01*
G01D02*
X341100D01*
G01X334900Y580100D02*
Y576900D01*
G01X341100Y580100D02*
X334900D01*
G01Y576900D02*
X341100D01*
G01Y584100D02*
X334900D01*
G01X321651Y698578D02*
Y710578D01*
G01X331453Y718394D02*
Y712194D01*
G01D02*
X334653D01*
G01D02*
Y718394D01*
G01X322912Y713121D02*
Y725121D01*
G01X327251Y725225D02*
Y722799D01*
G01X334653Y718394D02*
X331453D01*
G01X328274Y769928D02*
X326034D01*
G01X327247Y771553D02*
Y768303D01*
G01X332718Y1274372D02*
X350434D01*
G01X332718Y1310068D02*
Y1274372D01*
G01X330831Y1278708D02*
Y1290708D01*
G01X324831Y1278708D02*
X330831D01*
G01X324831Y1290708D02*
Y1278708D01*
G01X323954Y1278694D02*
Y1290694D01*
G01X330831Y1290708D02*
X324831D01*
G01X332843Y1311769D02*
Y1314195D01*
G01X350434Y1310068D02*
X332718D01*
G01X325891Y1313137D02*
Y1325137D01*
G01X326986Y1326206D02*
X330186D01*
G01X326986Y1332406D02*
Y1326206D01*
G01X330186D02*
Y1332406D01*
G01X332303Y1319883D02*
X335503D01*
G01X332303Y1326083D02*
Y1319883D01*
G01X335503Y1326083D02*
X332303D01*
G01X330186Y1332406D02*
X326986D01*
G01X339733Y1490124D02*
X339963Y1490279D01*
X340231Y1490382D01*
X340538D01*
X340883Y1490227D01*
X341151Y1489969D01*
X341343Y1489659D01*
X341496Y1489142D01*
X341534Y1488677D01*
X341458Y1488212D01*
X341343Y1487902D01*
X341113Y1487592D01*
X340844Y1487385D01*
X340576Y1487282D01*
X340308D01*
X340039Y1487385D01*
X339809Y1487540D01*
X339618Y1487747D01*
G01X337553Y1487282D02*
X337476Y1487954D01*
X337361Y1488522D01*
X337208Y1489039D01*
X337016Y1489607D01*
X336709Y1490382D01*
X338243D01*
G01X334376D02*
X334683Y1490279D01*
X334913Y1490020D01*
X335066Y1489710D01*
X335181Y1489297D01*
X335219Y1488832D01*
X335181Y1488367D01*
X335066Y1487954D01*
X334913Y1487644D01*
X334683Y1487385D01*
X334376Y1487282D01*
X334069Y1487385D01*
X333839Y1487644D01*
X333686Y1487954D01*
X333571Y1488367D01*
X333533Y1488832D01*
X333571Y1489297D01*
X333686Y1489710D01*
X333839Y1490020D01*
X334069Y1490279D01*
X334376Y1490382D01*
G01X332004Y1489865D02*
X331774Y1490175D01*
X331506Y1490330D01*
X331199Y1490382D01*
X330816Y1490279D01*
X330548Y1490020D01*
X330471Y1489710D01*
X330509Y1489400D01*
X330663Y1489142D01*
X331429Y1488625D01*
X331774Y1488264D01*
X332004Y1487747D01*
X332081Y1487282D01*
X330471D01*
G01X327716D02*
Y1490382D01*
X329134Y1488160D01*
X327218D01*
G01X325691Y1534538D02*
Y1540738D01*
G01X322491Y1534538D02*
X325691D01*
G01X322491Y1540738D02*
Y1534538D01*
G01X330415D02*
Y1540738D01*
G01X327215Y1534538D02*
X330415D01*
G01X327215Y1540738D02*
Y1534538D01*
G01X331940Y1540738D02*
Y1534538D01*
X335140D01*
Y1540738D01*
X331940D01*
G01X325691D02*
X322491D01*
G01X330415D02*
X327215D01*
G01X330499Y1669055D02*
X330757Y1668825D01*
X330912Y1668557D01*
X330964Y1668212D01*
X330861Y1667867D01*
X330654Y1667599D01*
X330292Y1667407D01*
X329879Y1667369D01*
X329466Y1667445D01*
X329207Y1667637D01*
X329001Y1667905D01*
X328949Y1668174D01*
X329001Y1668442D01*
X329207Y1668787D01*
X327864Y1668672D01*
Y1667637D01*
G01X346100Y-577638D02*
Y-569638D01*
X349900D01*
G01X348500Y-573505D02*
X346100D01*
G01X356000Y-569638D02*
X355200Y-569905D01*
X354600Y-570571D01*
X354200Y-571371D01*
X353900Y-572438D01*
X353800Y-573638D01*
X353900Y-574838D01*
X354200Y-575905D01*
X354600Y-576705D01*
X355200Y-577371D01*
X356000Y-577638D01*
X356800Y-577371D01*
X357400Y-576705D01*
X357800Y-575905D01*
X358100Y-574838D01*
X358200Y-573638D01*
X358100Y-572438D01*
X357800Y-571371D01*
X357400Y-570571D01*
X356800Y-569905D01*
X356000Y-569638D01*
G01X364000D02*
Y-577638D01*
G01X361700Y-569638D02*
X366300D01*
G01X372600Y-573638D02*
X374600D01*
Y-576038D01*
X374000Y-576838D01*
X373300Y-577371D01*
X372300Y-577638D01*
X371300Y-577371D01*
X370600Y-576838D01*
X370000Y-576038D01*
X369600Y-575105D01*
X369400Y-574038D01*
Y-573105D01*
X369600Y-572305D01*
X370000Y-571371D01*
X370600Y-570571D01*
X371200Y-570038D01*
X372000Y-569638D01*
X372700D01*
X373500Y-569905D01*
X374100Y-570438D01*
G01X377000Y-580305D02*
X383000D01*
G01X385400Y-577638D02*
Y-569638D01*
X388000Y-576305D01*
X390600Y-569638D01*
Y-577638D01*
G01X396800Y-573371D02*
X397200Y-572971D01*
X397500Y-572305D01*
X397700Y-571371D01*
X397500Y-570571D01*
X397100Y-570038D01*
X396400Y-569638D01*
X393700D01*
Y-577638D01*
X397000D01*
X397700Y-577105D01*
X398100Y-576305D01*
X398300Y-575371D01*
X398100Y-574438D01*
X397500Y-573638D01*
X396800Y-573371D01*
X393700D01*
G01X341100Y580900D02*
Y584100D01*
G01Y576900D02*
Y580100D01*
G01X343900D02*
Y576900D01*
G01X350100Y580100D02*
X343900D01*
G01Y576900D02*
X350100D01*
G01X343900Y584100D02*
Y580900D01*
G01D02*
X350100D01*
G01X350257Y592935D02*
X344057D01*
G01D02*
Y589735D01*
G01D02*
X350257D01*
G01Y588015D02*
X344057D01*
G01D02*
Y584815D01*
G01D02*
X350257D01*
G01X350100Y584100D02*
X343900D01*
G01X349599Y697686D02*
X355599D01*
G01X349599Y709686D02*
Y697686D01*
G01X336770Y712071D02*
Y705871D01*
G01D02*
X339970D01*
G01D02*
Y712071D01*
G01D02*
X336770D01*
G01X341221Y724929D02*
Y712929D01*
G01D02*
X347221D01*
G01D02*
Y724929D01*
G01X355599Y709686D02*
X349599D01*
G01Y724929D02*
Y712929D01*
G01D02*
X355599D01*
G01X335809Y728064D02*
Y763760D01*
G01X347799Y728064D02*
X365515D01*
G01X347799Y763760D02*
Y728064D01*
G01X347221Y724929D02*
X341221D01*
G01X355599D02*
X349599D01*
G01X338151Y759378D02*
Y747378D01*
G01X344151Y759378D02*
X338151D01*
G01X344151Y747378D02*
Y759378D01*
G01X338151Y747378D02*
X344151D01*
G01X365515Y763760D02*
X347799D01*
G01X336496Y810553D02*
G03X346244Y819025I1J9843D01*
G01X350500Y849324D02*
X346244Y819025D01*
G01X350500Y1189104D02*
X346244Y1219403D01*
G01D02*
G03X336496Y1227875I-9747J-1371D01*
G01X343770Y1255069D02*
X346870D01*
Y1255989D01*
X346715Y1256296D01*
X346353Y1256526D01*
X345940Y1256603D01*
X345527Y1256526D01*
X345217Y1256334D01*
X345062Y1255989D01*
Y1255069D01*
G01X346612Y1259779D02*
X346767Y1259549D01*
X346870Y1259281D01*
Y1258974D01*
X346715Y1258629D01*
X346457Y1258361D01*
X346147Y1258169D01*
X345630Y1258016D01*
X345165Y1257978D01*
X344700Y1258054D01*
X344390Y1258169D01*
X344080Y1258399D01*
X343873Y1258668D01*
X343770Y1258936D01*
Y1259204D01*
X343873Y1259473D01*
X344028Y1259703D01*
X344235Y1259894D01*
G01X344390Y1261193D02*
X344028Y1261423D01*
X343822Y1261729D01*
X343770Y1262074D01*
X343822Y1262381D01*
X344080Y1262688D01*
X344390Y1262879D01*
X344700Y1262918D01*
X345062Y1262841D01*
X345320Y1262573D01*
X345423Y1262304D01*
Y1261959D01*
G01Y1262304D02*
X345578Y1262534D01*
X345837Y1262726D01*
X346147Y1262803D01*
X346457Y1262726D01*
X346715Y1262534D01*
X346870Y1262189D01*
X346818Y1261844D01*
X346612Y1261499D01*
G01X344132Y1264484D02*
X343873Y1264753D01*
X343770Y1265059D01*
X343873Y1265366D01*
X344183Y1265634D01*
X344648Y1265826D01*
X345113Y1265903D01*
X345682D01*
X346147Y1265826D01*
X346560Y1265634D01*
X346767Y1265404D01*
X346870Y1265136D01*
X346767Y1264829D01*
X346560Y1264599D01*
X346250Y1264446D01*
X345837Y1264369D01*
X345475Y1264446D01*
X345113Y1264638D01*
X344907Y1264868D01*
X344855Y1265136D01*
X344958Y1265443D01*
X345217Y1265673D01*
X345682Y1265903D01*
G01X343770Y1268236D02*
X346870D01*
X346250Y1267776D01*
G01X343770D02*
Y1268696D01*
G01X340253Y1268204D02*
X342493D01*
G01X341280Y1266579D02*
Y1269829D01*
G01X344417Y1325080D02*
Y1313080D01*
G01D02*
X350417D01*
G01X335503Y1319883D02*
Y1326083D01*
G01X350417Y1325080D02*
X344417D01*
G01Y1328323D02*
X350417D01*
G01X344417Y1340323D02*
Y1328323D01*
G01X350417Y1340323D02*
X344417D01*
G01X347932Y1489898D02*
X350358D01*
G01X344588Y1534538D02*
Y1540738D01*
G01X341388Y1534538D02*
X344588D01*
G01X341388Y1540738D02*
Y1534538D01*
G01X339864D02*
Y1540738D01*
G01X336664Y1534538D02*
X339864D01*
G01X336664Y1540738D02*
Y1534538D01*
G01X349313D02*
Y1540738D01*
G01X346113Y1534538D02*
X349313D01*
G01X346113Y1540738D02*
Y1534538D01*
G01X344588Y1540738D02*
X341388D01*
G01X339864D02*
X336664D01*
G01X349313D02*
X346113D01*
G01X346712Y1668289D02*
X346040Y1668212D01*
X345472Y1668097D01*
X344955Y1667944D01*
X344387Y1667752D01*
X343612Y1667445D01*
Y1668979D01*
G01X337546Y1668940D02*
X337185Y1668672D01*
X336978Y1668442D01*
X336875Y1668135D01*
X336978Y1667867D01*
X337185Y1667675D01*
X337495Y1667522D01*
X337856Y1667484D01*
X338166Y1667522D01*
X338476Y1667675D01*
X338735Y1667905D01*
X338838Y1668174D01*
X338735Y1668480D01*
X338425Y1668749D01*
X337960Y1668902D01*
X337443Y1668940D01*
X336771Y1668864D01*
X336410Y1668749D01*
X336048Y1668557D01*
X335790Y1668289D01*
X335738Y1668020D01*
X335841Y1667752D01*
X336100Y1667560D01*
G01X365596Y-20644D02*
X365286Y-20452D01*
X365079Y-20222D01*
X364976Y-19954D01*
X365079Y-19647D01*
X365286Y-19417D01*
X365596Y-19187D01*
X366009Y-19110D01*
X368076D01*
G01X364976Y-16777D02*
X368076D01*
X367456Y-17237D01*
G01X364976D02*
Y-16317D01*
G01Y-13677D02*
X368076D01*
X367456Y-14137D01*
G01X364976D02*
Y-13217D01*
G01Y-10577D02*
X365028Y-10309D01*
X365183Y-10002D01*
X365441Y-9810D01*
X365803Y-9734D01*
X366164Y-9810D01*
X366474Y-10040D01*
X366629Y-10385D01*
Y-10769D01*
X366733Y-10999D01*
X366991Y-11190D01*
X367353Y-11267D01*
X367714Y-11152D01*
X367973Y-10884D01*
X368076Y-10577D01*
X367973Y-10270D01*
X367714Y-10002D01*
X367353Y-9887D01*
X366991Y-9964D01*
X366733Y-10155D01*
X366629Y-10385D01*
Y-10769D01*
X366474Y-11114D01*
X366164Y-11344D01*
X365803Y-11420D01*
X365441Y-11344D01*
X365183Y-11152D01*
X365028Y-10845D01*
X364976Y-10577D01*
G01X352057Y548815D02*
X358257D01*
G01D02*
Y552015D01*
G01D02*
X352057D01*
G01D02*
Y548815D01*
G01X363757Y541815D02*
Y548015D01*
G01D02*
X360557D01*
G01D02*
Y541815D01*
G01D02*
X363757D01*
G01X370900Y545600D02*
X364700D01*
G01D02*
Y542400D01*
G01D02*
X370900D01*
G01X363757Y548815D02*
Y555015D01*
G01X360557D02*
Y548815D01*
G01D02*
X363757D01*
G01X352057Y552815D02*
X358257D01*
G01D02*
Y556015D01*
G01X352057D02*
Y552815D01*
G01X364700Y546400D02*
X370900D01*
G01X364700Y549600D02*
Y546400D01*
G01X370900Y549600D02*
X364700D01*
G01X358257Y560015D02*
X352057D01*
G01D02*
Y556815D01*
G01D02*
X358257D01*
G01D02*
Y560015D01*
G01Y564015D02*
X352057D01*
G01D02*
Y560815D01*
G01D02*
X358257D01*
G01D02*
Y564015D01*
G01X363757Y555015D02*
X360557D01*
G01X358257Y556015D02*
X352057D01*
G01Y564815D02*
X358257D01*
G01D02*
Y568015D01*
G01X352057D02*
Y564815D01*
G01X364748Y560354D02*
Y558006D01*
G01D02*
X367096D01*
G01X358257Y572015D02*
X352057D01*
G01D02*
Y568815D01*
G01D02*
X358257D01*
G01D02*
Y572015D01*
G01Y576015D02*
X352057D01*
G01D02*
Y572815D01*
G01D02*
X358257D01*
G01D02*
Y576015D01*
G01Y568015D02*
X352057D01*
G01X350100Y576900D02*
Y580100D01*
G01Y580900D02*
Y584100D01*
G01X367096Y581824D02*
X364748D01*
G01D02*
Y579476D01*
G01X360483Y588879D02*
X366683D01*
G01Y592079D02*
X360483D01*
G01D02*
Y588879D01*
G01X352057Y588815D02*
X358257D01*
G01D02*
Y592015D01*
G01D02*
X352057D01*
G01D02*
Y588815D01*
G01X360473Y599071D02*
Y592871D01*
G01D02*
X363673D01*
G01D02*
Y599071D01*
G01X350257Y589735D02*
Y592935D01*
G01X352057Y584815D02*
X358257D01*
G01D02*
Y588015D01*
G01D02*
X352057D01*
G01D02*
Y584815D01*
G01X350257D02*
Y588015D01*
G01X363673Y599071D02*
X360473D01*
G01X355599Y697686D02*
Y709686D01*
G01X364513Y718126D02*
Y711926D01*
G01D02*
X367713D01*
G01X355599Y712929D02*
Y724929D01*
G01X356957Y725225D02*
Y722799D01*
G01X367713Y718126D02*
X364513D01*
G01X352703Y772309D02*
X355803D01*
Y773229D01*
X355648Y773536D01*
X355286Y773766D01*
X354873Y773843D01*
X354460Y773766D01*
X354150Y773574D01*
X353995Y773229D01*
Y772309D01*
G01X355545Y777019D02*
X355700Y776789D01*
X355803Y776521D01*
Y776214D01*
X355648Y775869D01*
X355390Y775601D01*
X355080Y775409D01*
X354563Y775256D01*
X354098Y775218D01*
X353633Y775294D01*
X353323Y775409D01*
X353013Y775639D01*
X352806Y775908D01*
X352703Y776176D01*
Y776444D01*
X352806Y776713D01*
X352961Y776943D01*
X353168Y777134D01*
G01X355286Y778548D02*
X355596Y778778D01*
X355751Y779046D01*
X355803Y779353D01*
X355700Y779736D01*
X355441Y780004D01*
X355131Y780081D01*
X354821Y780043D01*
X354563Y779889D01*
X354046Y779123D01*
X353685Y778778D01*
X353168Y778548D01*
X352703Y778471D01*
Y780081D01*
G01Y782299D02*
X353375Y782376D01*
X353943Y782491D01*
X354460Y782644D01*
X355028Y782836D01*
X355803Y783143D01*
Y781609D01*
G01X353995Y784748D02*
X354356Y785016D01*
X354563Y785246D01*
X354666Y785553D01*
X354563Y785821D01*
X354356Y786013D01*
X354046Y786166D01*
X353685Y786204D01*
X353375Y786166D01*
X353065Y786013D01*
X352806Y785783D01*
X352703Y785514D01*
X352806Y785208D01*
X353116Y784939D01*
X353581Y784786D01*
X354098Y784748D01*
X354770Y784824D01*
X355131Y784939D01*
X355493Y785131D01*
X355751Y785399D01*
X355803Y785668D01*
X355700Y785936D01*
X355441Y786128D01*
G01X357980Y769928D02*
X355740D01*
G01X356953Y771553D02*
Y768303D01*
G01X364913Y804575D02*
Y810775D01*
G01X361713Y804575D02*
X364913D01*
G01X361713Y810775D02*
Y804575D01*
G01X361413D02*
Y810775D01*
G01X358213Y804575D02*
X361413D01*
G01X358213Y810775D02*
Y804575D01*
G01X357913D02*
Y810775D01*
G01X354713Y804575D02*
X357913D01*
G01X354713Y810775D02*
Y804575D01*
G01X354413D02*
Y810775D01*
G01X351213Y804575D02*
X354413D01*
G01X351213Y810775D02*
Y804575D01*
G01X364913Y810775D02*
X361713D01*
G01X361413D02*
X358213D01*
G01X357913D02*
X354713D01*
G01X364913Y819575D02*
X361713D01*
G01X364913Y813375D02*
Y819575D01*
G01X361713Y813375D02*
X364913D01*
G01X361713Y819575D02*
Y813375D01*
G01X361413Y819675D02*
X358213D01*
G01X361413Y813475D02*
Y819675D01*
G01X358213Y813475D02*
X361413D01*
G01X358213Y819675D02*
Y813475D01*
G01X357913Y819675D02*
X354713D01*
G01X357913Y813475D02*
Y819675D01*
G01X354713Y813475D02*
X357913D01*
G01X354713Y819675D02*
Y813475D01*
G01X354413Y810775D02*
X351213D01*
G01X354413Y819675D02*
X351213D01*
G01X354413Y813475D02*
Y819675D01*
G01X351213Y813475D02*
X354413D01*
G01X351213Y819675D02*
Y813475D01*
G01X360248Y857797D02*
G03X350500Y849324I-1J-9843D01*
G01X360248Y857797D02*
X411900D01*
G01X357111Y1195518D02*
Y1192318D01*
G01X363311D02*
Y1195518D01*
G01X357111Y1192318D02*
X363311D01*
G01X357111Y1189462D02*
Y1186262D01*
G01X363311Y1189462D02*
X357111D01*
G01X363311Y1186262D02*
Y1189462D01*
G01X357111Y1186262D02*
X363311D01*
G01X350500Y1189104D02*
G03X360248Y1180631I9747J1370D01*
G01D02*
X521074D01*
G01X362438Y1196531D02*
X356238D01*
G01D02*
Y1199731D01*
G01D02*
X362438D01*
G01X363311Y1195518D02*
X357111D01*
G01X357171Y1203988D02*
Y1200788D01*
G01X363371Y1203988D02*
X357171D01*
G01X363371Y1200788D02*
Y1203988D01*
G01X357171Y1200788D02*
X363371D01*
G01X362438Y1196531D02*
Y1199731D01*
G01X356238Y1196531D02*
X362438D01*
G01X356238Y1199731D02*
Y1196531D01*
G01X362438Y1199731D02*
X356238D01*
G01X362871Y1218088D02*
X359671D01*
G01X362871Y1211888D02*
Y1218088D01*
G01X359671Y1211888D02*
X362871D01*
G01X359671Y1218088D02*
Y1211888D01*
G01X358871Y1218088D02*
X355671D01*
G01X358871Y1211888D02*
Y1218088D01*
G01X355671Y1211888D02*
X358871D01*
G01X355671Y1218088D02*
Y1211888D01*
G01X350434Y1274372D02*
Y1310068D01*
G01X358314Y1278827D02*
Y1290827D01*
G01X352314Y1278827D02*
X358314D01*
G01X352314Y1290827D02*
Y1278827D01*
G01X359201Y1278913D02*
X365201D01*
G01X359201Y1290913D02*
Y1278913D01*
G01X358314Y1290827D02*
X352314D01*
G01X365201Y1290913D02*
X359201D01*
G01X365663Y1311905D02*
Y1314331D01*
G01X352795Y1325080D02*
Y1313080D01*
G01X358795D02*
Y1325080D01*
G01X352795Y1313080D02*
X358795D01*
G01X350417D02*
Y1325080D01*
G01X359786Y1326406D02*
X362986D01*
G01X359786Y1332606D02*
Y1326406D01*
G01X362986D02*
Y1332606D01*
G01X358795Y1325080D02*
X352795D01*
G01X362986Y1332606D02*
X359786D01*
G01X350417Y1328323D02*
Y1340323D01*
G01X359312Y1489442D02*
X356886D01*
G01X389900Y1508910D02*
X354160D01*
Y1491980D01*
X389900D01*
Y1508910D01*
G01X354037Y1534538D02*
Y1540738D01*
G01X350837Y1534538D02*
X354037D01*
G01X350837Y1540738D02*
Y1534538D01*
G01X355562Y1540738D02*
Y1534538D01*
X358762D01*
Y1540738D01*
X355562D01*
G01X354037D02*
X350837D01*
G01X354586Y1668212D02*
X354534Y1667944D01*
X354379Y1667637D01*
X354121Y1667445D01*
X353759Y1667369D01*
X353398Y1667445D01*
X353088Y1667675D01*
X352933Y1668020D01*
Y1668404D01*
X352829Y1668634D01*
X352571Y1668825D01*
X352209Y1668902D01*
X351848Y1668787D01*
X351589Y1668519D01*
X351486Y1668212D01*
X351589Y1667905D01*
X351848Y1667637D01*
X352209Y1667522D01*
X352571Y1667599D01*
X352829Y1667790D01*
X352933Y1668020D01*
Y1668404D01*
X353088Y1668749D01*
X353398Y1668979D01*
X353759Y1669055D01*
X354121Y1668979D01*
X354379Y1668787D01*
X354534Y1668480D01*
X354586Y1668212D01*
G01X369075Y1733579D02*
X361575D01*
Y1731339D01*
X361950Y1730592D01*
X362825Y1730032D01*
X363825Y1729845D01*
X364825Y1730032D01*
X365575Y1730499D01*
X365950Y1731339D01*
Y1733579D01*
G01X369075Y1726079D02*
X361575D01*
Y1723745D01*
X361950Y1722999D01*
X362450Y1722532D01*
X363450Y1722345D01*
X364450Y1722532D01*
X365075Y1723092D01*
X365450Y1723745D01*
Y1726079D01*
G01Y1723745D02*
X369075Y1722345D01*
G01Y1714845D02*
Y1718579D01*
X361575D01*
Y1714845D01*
G01X365200Y1716339D02*
Y1718579D01*
G01X368075Y1711172D02*
X368700Y1710425D01*
X369075Y1709585D01*
Y1708839D01*
X368700Y1708092D01*
X368075Y1707532D01*
X367200Y1707252D01*
X366325Y1707439D01*
X365575Y1707905D01*
X365075Y1708745D01*
X364825Y1709865D01*
X364325Y1710519D01*
X363450Y1710799D01*
X362575Y1710612D01*
X361950Y1710145D01*
X361575Y1709492D01*
Y1708839D01*
X361825Y1708185D01*
X362450Y1707625D01*
G01X368075Y1703672D02*
X368700Y1702925D01*
X369075Y1702085D01*
Y1701339D01*
X368700Y1700592D01*
X368075Y1700032D01*
X367200Y1699752D01*
X366325Y1699939D01*
X365575Y1700405D01*
X365075Y1701245D01*
X364825Y1702365D01*
X364325Y1703019D01*
X363450Y1703299D01*
X362575Y1703112D01*
X361950Y1702645D01*
X361575Y1701992D01*
Y1701339D01*
X361825Y1700685D01*
X362450Y1700125D01*
G01X366575Y1695425D02*
Y1692999D01*
G01X369075Y1688485D02*
X361575D01*
Y1684939D01*
G01X365200Y1686245D02*
Y1688485D01*
G01X361575Y1680332D02*
Y1678092D01*
G01Y1679212D02*
X369075D01*
G01Y1680332D02*
Y1678092D01*
G01X361575Y1671712D02*
X369075D01*
G01X361575Y1673859D02*
Y1669565D01*
G01X368693Y241052D02*
Y237852D01*
G01D02*
X374893D01*
G01D02*
Y241052D01*
G01D02*
X368693D01*
G01X370900Y542400D02*
Y545600D01*
G01Y546400D02*
Y549600D01*
G01X366683Y588879D02*
Y592079D01*
G01X383043Y596403D02*
X379843D01*
G01D02*
Y590203D01*
G01D02*
X383043D01*
G01X369830Y711803D02*
Y705603D01*
G01D02*
X373030D01*
G01D02*
Y711803D01*
G01D02*
X369830D01*
G01X367713Y711926D02*
Y718126D01*
G01X374812Y724721D02*
Y712721D01*
G01D02*
X380812D01*
G01X365515Y728064D02*
Y763760D01*
G01X378293Y728030D02*
X396009D01*
G01X378293Y763726D02*
Y728030D01*
G01X380812Y724721D02*
X374812D01*
G01X368551Y759378D02*
Y747378D01*
G01X374551Y759378D02*
X368551D01*
G01X374551Y747378D02*
Y759378D01*
G01X368551Y747378D02*
X374551D01*
G01X396009Y763726D02*
X378293D01*
G01X368413Y804575D02*
Y810775D01*
G01X365213Y804575D02*
X368413D01*
G01X365213Y810775D02*
Y804575D01*
G01X378913D02*
Y810775D01*
G01X375713Y804575D02*
X378913D01*
G01X375713Y810775D02*
Y804575D01*
G01X375413D02*
Y810775D01*
G01X372213Y804575D02*
X375413D01*
G01X372213Y810775D02*
Y804575D01*
G01X371913D02*
Y810775D01*
G01X368713Y804575D02*
X371913D01*
G01X368713Y810775D02*
Y804575D01*
G01X368413Y810775D02*
X365213D01*
G01X378913D02*
X375713D01*
G01X375413D02*
X372213D01*
G01X371913D02*
X368713D01*
G01X375031Y1190548D02*
X368831D01*
G01D02*
Y1193748D01*
G01X375100Y1186262D02*
X368900D01*
G01D02*
Y1189462D01*
G01D02*
X375100D01*
G01X375031Y1190548D02*
Y1193748D01*
G01X368831Y1190548D02*
X375031D01*
G01X368831Y1193748D02*
Y1190548D01*
G01X375031Y1193748D02*
X368831D01*
G01X375100Y1186262D02*
Y1189462D01*
G01X368900Y1186262D02*
X375100D01*
G01X368900Y1189462D02*
Y1186262D01*
G01X375100Y1189462D02*
X368900D01*
G01X378171Y1205888D02*
Y1209088D01*
G01X375100Y1194262D02*
Y1197462D01*
G01X368900Y1194262D02*
X375100D01*
G01X368900Y1197462D02*
Y1194262D01*
G01X375100Y1197462D02*
X368900D01*
G01X374991Y1205938D02*
Y1209138D01*
G01X368791Y1205938D02*
X374991D01*
G01X368791Y1209138D02*
Y1205938D01*
G01X378171Y1209088D02*
Y1205888D01*
G01D02*
X384371D01*
G01X368831Y1201248D02*
Y1198048D01*
G01X375031Y1201248D02*
X368831D01*
G01X375031Y1198048D02*
Y1201248D01*
G01X368831Y1198048D02*
X375031D01*
G01X378171Y1209088D02*
X384371D01*
G01X374991Y1209138D02*
X368791D01*
G01Y1213138D02*
Y1209938D01*
G01X374991Y1213138D02*
X368791D01*
G01X374991Y1209938D02*
Y1213138D01*
G01X368791Y1209938D02*
X374991D01*
G01X384371Y1209088D02*
X378171D01*
G01X374653Y1268179D02*
X376893D01*
G01X375680Y1266554D02*
Y1269804D01*
G01X367118Y1274347D02*
X384834D01*
G01X367118Y1310043D02*
Y1274347D01*
G01X365201Y1278913D02*
Y1290913D01*
G01X384834Y1310043D02*
X367118D01*
G01X377217Y1325280D02*
Y1313280D01*
G01D02*
X383217D01*
G01X365103Y1320083D02*
X368303D01*
G01X365103Y1326283D02*
Y1320083D01*
G01X368303Y1326283D02*
X365103D01*
G01X368303Y1320083D02*
Y1326283D01*
G01X383217Y1325280D02*
X377217D01*
G01Y1328523D02*
X383217D01*
G01X377217Y1340523D02*
Y1328523D01*
G01X383217Y1340523D02*
X377217D01*
G01X380437Y1490124D02*
X380667Y1490279D01*
X380935Y1490382D01*
X381242D01*
X381587Y1490227D01*
X381855Y1489969D01*
X382047Y1489659D01*
X382200Y1489142D01*
X382238Y1488677D01*
X382162Y1488212D01*
X382047Y1487902D01*
X381817Y1487592D01*
X381548Y1487385D01*
X381280Y1487282D01*
X381012D01*
X380743Y1487385D01*
X380513Y1487540D01*
X380322Y1487747D01*
G01X378257Y1487282D02*
X378180Y1487954D01*
X378065Y1488522D01*
X377912Y1489039D01*
X377720Y1489607D01*
X377413Y1490382D01*
X378947D01*
G01X375080D02*
X375387Y1490279D01*
X375617Y1490020D01*
X375770Y1489710D01*
X375885Y1489297D01*
X375923Y1488832D01*
X375885Y1488367D01*
X375770Y1487954D01*
X375617Y1487644D01*
X375387Y1487385D01*
X375080Y1487282D01*
X374773Y1487385D01*
X374543Y1487644D01*
X374390Y1487954D01*
X374275Y1488367D01*
X374237Y1488832D01*
X374275Y1489297D01*
X374390Y1489710D01*
X374543Y1490020D01*
X374773Y1490279D01*
X375080Y1490382D01*
G01X372708Y1489865D02*
X372478Y1490175D01*
X372210Y1490330D01*
X371903Y1490382D01*
X371520Y1490279D01*
X371252Y1490020D01*
X371175Y1489710D01*
X371213Y1489400D01*
X371367Y1489142D01*
X372133Y1488625D01*
X372478Y1488264D01*
X372708Y1487747D01*
X372785Y1487282D01*
X371175D01*
G01X369723Y1487902D02*
X369493Y1487540D01*
X369187Y1487334D01*
X368842Y1487282D01*
X368535Y1487334D01*
X368228Y1487592D01*
X368037Y1487902D01*
X367998Y1488212D01*
X368075Y1488574D01*
X368343Y1488832D01*
X368612Y1488935D01*
X368957D01*
G01X368612D02*
X368382Y1489090D01*
X368190Y1489349D01*
X368113Y1489659D01*
X368190Y1489969D01*
X368382Y1490227D01*
X368727Y1490382D01*
X369072Y1490330D01*
X369417Y1490124D01*
G01X379184Y1540738D02*
Y1534538D01*
X382384D01*
Y1540738D01*
X379184D01*
G01X365010D02*
Y1534538D01*
X368210D01*
Y1540738D01*
X365010D01*
G01X369735D02*
Y1534538D01*
X372935D01*
Y1540738D01*
X369735D01*
G01X374459D02*
Y1534538D01*
X377659D01*
Y1540738D01*
X374459D01*
G01X371260Y1667500D02*
Y1646023D01*
G01Y1781456D02*
Y1672460D01*
G01X389823Y-22011D02*
Y-5731D01*
X380223D01*
Y-22011D01*
X389823D01*
G01X388063Y201603D02*
Y204703D01*
G01X386453D02*
Y201603D01*
G01Y203153D02*
X388063D01*
G01X385001Y202223D02*
X384771Y201861D01*
X384465Y201655D01*
X384120Y201603D01*
X383813Y201655D01*
X383506Y201913D01*
X383315Y202223D01*
X383276Y202533D01*
X383353Y202895D01*
X383621Y203153D01*
X383890Y203256D01*
X384235D01*
G01X383890D02*
X383660Y203411D01*
X383468Y203670D01*
X383391Y203980D01*
X383468Y204290D01*
X383660Y204548D01*
X384005Y204703D01*
X384350Y204651D01*
X384695Y204445D01*
G01X381786Y204186D02*
X381556Y204496D01*
X381288Y204651D01*
X380981Y204703D01*
X380598Y204600D01*
X380330Y204341D01*
X380253Y204031D01*
X380291Y203721D01*
X380445Y203463D01*
X381211Y202946D01*
X381556Y202585D01*
X381786Y202068D01*
X381863Y201603D01*
X380253D01*
G01X394057Y554015D02*
Y547815D01*
G01D02*
X397257D01*
G01X386057Y554015D02*
Y547815D01*
G01D02*
X389257D01*
G01D02*
Y554015D01*
G01X390057D02*
Y547815D01*
G01D02*
X393257D01*
G01D02*
Y554015D01*
G01X397257D02*
X394057D01*
G01X389257D02*
X386057D01*
G01X393257D02*
X390057D01*
G01X386218Y558006D02*
X388566D01*
G01D02*
Y560354D01*
G01Y581824D02*
X386218D01*
G01X388566Y579476D02*
Y581824D01*
G01X387043Y590203D02*
Y596403D01*
G01D02*
X383843D01*
G01D02*
Y590203D01*
G01D02*
X387043D01*
G01X391043D02*
Y596403D01*
G01D02*
X387843D01*
G01D02*
Y590203D01*
G01D02*
X391043D01*
G01X383043D02*
Y596403D01*
G01X401065Y584106D02*
Y587206D01*
X400145D01*
X399838Y587051D01*
X399608Y586689D01*
X399531Y586276D01*
X399608Y585863D01*
X399800Y585553D01*
X400145Y585398D01*
X401065D01*
G01X398041Y587206D02*
Y584984D01*
X397888Y584519D01*
X397581Y584209D01*
X397198Y584106D01*
X396815Y584209D01*
X396508Y584519D01*
X396355Y584984D01*
Y587206D01*
G01X394826Y586689D02*
X394596Y586999D01*
X394328Y587154D01*
X394021Y587206D01*
X393638Y587103D01*
X393370Y586844D01*
X393293Y586534D01*
X393331Y586224D01*
X393485Y585966D01*
X394251Y585449D01*
X394596Y585088D01*
X394826Y584571D01*
X394903Y584106D01*
X393293D01*
G01X391841Y584571D02*
X391611Y584313D01*
X391343Y584158D01*
X390998Y584106D01*
X390653Y584209D01*
X390385Y584416D01*
X390193Y584778D01*
X390155Y585191D01*
X390231Y585604D01*
X390423Y585863D01*
X390691Y586069D01*
X390960Y586121D01*
X391228Y586069D01*
X391573Y585863D01*
X391458Y587206D01*
X390423D01*
G01X382251Y698278D02*
X388251D01*
G01D02*
Y710278D01*
G01X382251D02*
Y698278D01*
G01X380812Y712721D02*
Y724721D01*
G01X382812D02*
Y712721D01*
G01D02*
X388812D01*
G01D02*
Y724721D01*
G01X388251Y710278D02*
X382251D01*
G01X391798Y724189D02*
Y721763D01*
G01X388812Y724721D02*
X382812D01*
G01X389577Y769245D02*
X392677D01*
Y770165D01*
X392522Y770472D01*
X392160Y770702D01*
X391747Y770779D01*
X391334Y770702D01*
X391024Y770510D01*
X390869Y770165D01*
Y769245D01*
G01X392419Y773955D02*
X392574Y773725D01*
X392677Y773457D01*
Y773150D01*
X392522Y772805D01*
X392264Y772537D01*
X391954Y772345D01*
X391437Y772192D01*
X390972Y772154D01*
X390507Y772230D01*
X390197Y772345D01*
X389887Y772575D01*
X389680Y772844D01*
X389577Y773112D01*
Y773380D01*
X389680Y773649D01*
X389835Y773879D01*
X390042Y774070D01*
G01X392160Y775484D02*
X392470Y775714D01*
X392625Y775982D01*
X392677Y776289D01*
X392574Y776672D01*
X392315Y776940D01*
X392005Y777017D01*
X391695Y776979D01*
X391437Y776825D01*
X390920Y776059D01*
X390559Y775714D01*
X390042Y775484D01*
X389577Y775407D01*
Y777017D01*
G01Y779235D02*
X390249Y779312D01*
X390817Y779427D01*
X391334Y779580D01*
X391902Y779772D01*
X392677Y780079D01*
Y778545D01*
G01X390042Y781569D02*
X389784Y781799D01*
X389629Y782067D01*
X389577Y782412D01*
X389680Y782757D01*
X389887Y783025D01*
X390249Y783217D01*
X390662Y783255D01*
X391075Y783179D01*
X391334Y782987D01*
X391540Y782719D01*
X391592Y782450D01*
X391540Y782182D01*
X391334Y781837D01*
X392677Y781952D01*
Y782987D01*
G01X388474Y769894D02*
X386234D01*
G01X387447Y771519D02*
Y768269D01*
G01X383574Y973938D02*
G03X393417Y964096I9843J1D01*
G01X487905D02*
X393417D01*
G01X394971Y964888D02*
Y971088D01*
X391771D01*
Y964888D01*
X394971D01*
G01X383574Y973938D02*
Y1064490D01*
G01X386671Y980166D02*
X392871D01*
Y983366D01*
X386671D01*
Y980166D01*
G01X384735Y976666D02*
X390935D01*
Y979866D01*
X384735D01*
Y976666D01*
G01X394171Y980166D02*
X400371D01*
Y983366D01*
X394171D01*
Y980166D01*
G01X394671Y986166D02*
X400871D01*
Y989366D01*
X394671D01*
Y986166D01*
G01X387171Y998666D02*
X393371D01*
Y1001866D01*
X387171D01*
Y998666D01*
G01Y986166D02*
X393371D01*
Y989366D01*
X387171D01*
Y986166D01*
G01X394071Y992888D02*
X400271D01*
Y996088D01*
X394071D01*
Y992888D01*
G01X387071D02*
X393271D01*
Y996088D01*
X387071D01*
Y992888D01*
G01X394071Y998666D02*
X400271D01*
Y1001866D01*
X394071D01*
Y998666D01*
G01X391310Y1005366D02*
X385110D01*
Y1002166D01*
X391310D01*
Y1005366D01*
G01X392559Y1009166D02*
X398759D01*
Y1012366D01*
X392559D01*
Y1009166D01*
G01X387059Y1005666D02*
X393259D01*
Y1008866D01*
X387059D01*
Y1005666D01*
G01X385006Y1013874D02*
X391206D01*
Y1017074D01*
X385006D01*
Y1013874D01*
G01X392486D02*
X398686D01*
Y1017074D01*
X392486D01*
Y1013874D01*
G01X385059Y1009166D02*
X391259D01*
Y1012366D01*
X385059D01*
Y1009166D01*
G01X392486Y1017417D02*
X398686D01*
Y1020617D01*
X392486D01*
Y1017417D01*
G01X390871Y1032888D02*
X384671D01*
Y1029688D01*
X390871D01*
Y1032888D01*
G01X385006Y1017417D02*
X391206D01*
Y1020617D01*
X385006D01*
Y1017417D01*
G01Y1020960D02*
X391206D01*
Y1024160D01*
X385006D01*
Y1020960D01*
G01X397871Y1032888D02*
X391671D01*
Y1029688D01*
X397871D01*
Y1032888D01*
G01X392486Y1020960D02*
X398686D01*
Y1024160D01*
X392486D01*
Y1020960D01*
G01X390871Y1039088D02*
X384671D01*
Y1035888D01*
X390871D01*
Y1039088D01*
G01X397871Y1045088D02*
X391671D01*
Y1041888D01*
X397871D01*
Y1045088D01*
G01X390871D02*
X384671D01*
Y1041888D01*
X390871D01*
Y1045088D01*
G01X397871Y1039088D02*
X391671D01*
Y1035888D01*
X397871D01*
Y1039088D01*
G01X390716Y1048166D02*
Y1051366D01*
G01X384516Y1048166D02*
X390716D01*
G01X384516Y1051366D02*
Y1048166D01*
G01X390716Y1051366D02*
X384516D01*
G01X392716Y1051666D02*
Y1054866D01*
G01X386516Y1051666D02*
X392716D01*
G01X386516Y1054866D02*
Y1051666D01*
G01X392716Y1054866D02*
X386516D01*
G01X400259Y1048866D02*
X394059D01*
Y1045666D01*
X400259D01*
Y1048866D01*
G01X398259Y1058366D02*
X392059D01*
Y1055166D01*
X398259D01*
Y1058366D01*
G01X400259Y1054866D02*
X394059D01*
Y1051666D01*
X400259D01*
Y1054866D01*
G01X396259Y1061866D02*
X390059D01*
Y1058666D01*
X396259D01*
Y1061866D01*
G01X393417Y1074332D02*
G03X383574Y1064490I0J-9843D01*
G01X487905Y1074332D02*
X393417D01*
G01X392671Y1073588D02*
Y1067388D01*
X395871D01*
Y1073588D01*
X392671D01*
G01X384371Y1209088D02*
Y1205888D01*
G01D02*
Y1209088D01*
G01X388760Y1262784D02*
X391860D01*
Y1263704D01*
X391705Y1264011D01*
X391343Y1264241D01*
X390930Y1264318D01*
X390517Y1264241D01*
X390207Y1264049D01*
X390052Y1263704D01*
Y1262784D01*
G01X391602Y1267494D02*
X391757Y1267264D01*
X391860Y1266996D01*
Y1266689D01*
X391705Y1266344D01*
X391447Y1266076D01*
X391137Y1265884D01*
X390620Y1265731D01*
X390155Y1265693D01*
X389690Y1265769D01*
X389380Y1265884D01*
X389070Y1266114D01*
X388863Y1266383D01*
X388760Y1266651D01*
Y1266919D01*
X388863Y1267188D01*
X389018Y1267418D01*
X389225Y1267609D01*
G01X389380Y1268908D02*
X389018Y1269138D01*
X388812Y1269444D01*
X388760Y1269789D01*
X388812Y1270096D01*
X389070Y1270403D01*
X389380Y1270594D01*
X389690Y1270633D01*
X390052Y1270556D01*
X390310Y1270288D01*
X390413Y1270019D01*
Y1269674D01*
G01Y1270019D02*
X390568Y1270249D01*
X390827Y1270441D01*
X391137Y1270518D01*
X391447Y1270441D01*
X391705Y1270249D01*
X391860Y1269904D01*
X391808Y1269559D01*
X391602Y1269214D01*
G01X388760Y1272851D02*
X388812Y1273119D01*
X388967Y1273426D01*
X389225Y1273618D01*
X389587Y1273694D01*
X389948Y1273618D01*
X390258Y1273388D01*
X390413Y1273043D01*
Y1272659D01*
X390517Y1272429D01*
X390775Y1272238D01*
X391137Y1272161D01*
X391498Y1272276D01*
X391757Y1272544D01*
X391860Y1272851D01*
X391757Y1273158D01*
X391498Y1273426D01*
X391137Y1273541D01*
X390775Y1273464D01*
X390517Y1273273D01*
X390413Y1273043D01*
Y1272659D01*
X390258Y1272314D01*
X389948Y1272084D01*
X389587Y1272008D01*
X389225Y1272084D01*
X388967Y1272276D01*
X388812Y1272583D01*
X388760Y1272851D01*
G01X389122Y1275299D02*
X388863Y1275568D01*
X388760Y1275874D01*
X388863Y1276181D01*
X389173Y1276449D01*
X389638Y1276641D01*
X390103Y1276718D01*
X390672D01*
X391137Y1276641D01*
X391550Y1276449D01*
X391757Y1276219D01*
X391860Y1275951D01*
X391757Y1275644D01*
X391550Y1275414D01*
X391240Y1275261D01*
X390827Y1275184D01*
X390465Y1275261D01*
X390103Y1275453D01*
X389897Y1275683D01*
X389845Y1275951D01*
X389948Y1276258D01*
X390207Y1276488D01*
X390672Y1276718D01*
G01X384834Y1274347D02*
Y1310043D01*
G01X392701Y1280713D02*
Y1292713D01*
G01X386701Y1280713D02*
X392701D01*
G01X386701Y1292713D02*
Y1280713D01*
G01X392701Y1292713D02*
X386701D01*
G01X393176Y1298251D02*
X399176D01*
G01X393176Y1310251D02*
Y1298251D01*
G01X399176Y1310251D02*
X393176D01*
G01X385595Y1325280D02*
Y1313280D01*
G01X391595D02*
Y1325280D01*
G01X385595Y1313280D02*
X391595D01*
G01X383217D02*
Y1325280D01*
G01X391595D02*
X385595D01*
G01X398146Y1331421D02*
Y1333847D01*
G01X383217Y1328523D02*
Y1340523D01*
G01X392368Y1345737D02*
X395568D01*
G01X392368Y1351937D02*
Y1345737D01*
G01X395568Y1351937D02*
X392368D01*
G01X391050Y1491979D02*
X389541Y1491983D01*
G01X391100Y1508912D02*
X391094Y1491929D01*
G01X390500Y1508912D02*
X390504Y1491937D01*
G01X389900Y1508912D02*
X389903Y1491972D01*
G01X394725Y1500897D02*
X392485D01*
G01X393698Y1502522D02*
Y1499272D01*
G01X391100Y1508912D02*
X389900D01*
G01X387108Y1534538D02*
Y1540738D01*
G01X383908Y1534538D02*
X387108D01*
G01X383908Y1540738D02*
Y1534538D01*
G01X389239Y1540738D02*
Y1534538D01*
X392439D01*
Y1540738D01*
X389239D01*
G01X387108D02*
X383908D01*
G01X387317Y1668446D02*
Y1671646D01*
G01X381117Y1668446D02*
X387317D01*
G01X381117Y1671646D02*
Y1668446D01*
G01X402795Y1660773D02*
X403102Y1660825D01*
X403370Y1661031D01*
X403600Y1661341D01*
X403753Y1661703D01*
X403830Y1662116D01*
Y1662530D01*
X403753Y1662943D01*
X403600Y1663305D01*
X403370Y1663615D01*
X403102Y1663821D01*
X402795Y1663873D01*
X402488Y1663821D01*
X402220Y1663615D01*
X401990Y1663305D01*
X401837Y1662943D01*
X401760Y1662530D01*
Y1662116D01*
X401837Y1661703D01*
X401990Y1661341D01*
X402220Y1661031D01*
X402488Y1660825D01*
X402795Y1660773D01*
G01X402488Y1661600D02*
X402028Y1660773D01*
G01X399695D02*
X399427Y1660825D01*
X399120Y1660980D01*
X398928Y1661238D01*
X398852Y1661600D01*
X398928Y1661961D01*
X399158Y1662271D01*
X399503Y1662426D01*
X399887D01*
X400117Y1662530D01*
X400308Y1662788D01*
X400385Y1663150D01*
X400270Y1663511D01*
X400002Y1663770D01*
X399695Y1663873D01*
X399388Y1663770D01*
X399120Y1663511D01*
X399005Y1663150D01*
X399082Y1662788D01*
X399273Y1662530D01*
X399503Y1662426D01*
X399887D01*
X400232Y1662271D01*
X400462Y1661961D01*
X400538Y1661600D01*
X400462Y1661238D01*
X400270Y1660980D01*
X399963Y1660825D01*
X399695Y1660773D01*
G01X396595Y1663873D02*
X396902Y1663770D01*
X397132Y1663511D01*
X397285Y1663201D01*
X397400Y1662788D01*
X397438Y1662323D01*
X397400Y1661858D01*
X397285Y1661445D01*
X397132Y1661135D01*
X396902Y1660876D01*
X396595Y1660773D01*
X396288Y1660876D01*
X396058Y1661135D01*
X395905Y1661445D01*
X395790Y1661858D01*
X395752Y1662323D01*
X395790Y1662788D01*
X395905Y1663201D01*
X396058Y1663511D01*
X396288Y1663770D01*
X396595Y1663873D01*
G01X393495D02*
X393802Y1663770D01*
X394032Y1663511D01*
X394185Y1663201D01*
X394300Y1662788D01*
X394338Y1662323D01*
X394300Y1661858D01*
X394185Y1661445D01*
X394032Y1661135D01*
X393802Y1660876D01*
X393495Y1660773D01*
X393188Y1660876D01*
X392958Y1661135D01*
X392805Y1661445D01*
X392690Y1661858D01*
X392652Y1662323D01*
X392690Y1662788D01*
X392805Y1663201D01*
X392958Y1663511D01*
X393188Y1663770D01*
X393495Y1663873D01*
G01X390395D02*
X390702Y1663770D01*
X390932Y1663511D01*
X391085Y1663201D01*
X391200Y1662788D01*
X391238Y1662323D01*
X391200Y1661858D01*
X391085Y1661445D01*
X390932Y1661135D01*
X390702Y1660876D01*
X390395Y1660773D01*
X390088Y1660876D01*
X389858Y1661135D01*
X389705Y1661445D01*
X389590Y1661858D01*
X389552Y1662323D01*
X389590Y1662788D01*
X389705Y1663201D01*
X389858Y1663511D01*
X390088Y1663770D01*
X390395Y1663873D01*
G01X392679Y1677108D02*
Y1668446D01*
G01D02*
X396026D01*
G01X387317Y1672385D02*
Y1675585D01*
G01X381117Y1672385D02*
X387317D01*
G01X381117Y1675585D02*
Y1672385D01*
G01X387317Y1675585D02*
X381117D01*
G01Y1679474D02*
Y1676274D01*
G01X387317Y1679474D02*
X381117D01*
G01X387317Y1676274D02*
Y1679474D01*
G01X381117Y1676274D02*
X387317D01*
G01Y1671646D02*
X381117D01*
G01X403173Y1677108D02*
X392679D01*
G01X397257Y547815D02*
Y554015D01*
G01X398057D02*
Y547815D01*
G01D02*
X401257D01*
G01D02*
Y554015D01*
G01X402057D02*
Y547815D01*
G01D02*
X405257D01*
G01D02*
Y554015D01*
G01X396057Y555815D02*
X402257D01*
G01D02*
Y559015D01*
G01D02*
X396057D01*
G01D02*
Y555815D01*
G01Y559815D02*
X402257D01*
G01D02*
Y563015D01*
G01D02*
X396057D01*
G01D02*
Y559815D01*
G01Y563815D02*
X402257D01*
G01D02*
Y567015D01*
G01D02*
X396057D01*
G01D02*
Y563815D01*
G01Y567815D02*
X402257D01*
G01D02*
Y571015D01*
G01X396057D02*
Y567815D01*
G01X401257Y554015D02*
X398057D01*
G01X405257D02*
X402057D01*
G01X399257Y575815D02*
Y582015D01*
G01D02*
X396057D01*
G01D02*
Y575815D01*
G01D02*
X399257D01*
G01X402257Y571015D02*
X396057D01*
G01X402257Y575015D02*
X396057D01*
G01D02*
Y571815D01*
G01D02*
X402257D01*
G01D02*
Y575015D01*
G01X406257Y579015D02*
X400057D01*
G01D02*
Y575815D01*
G01D02*
X406257D01*
G01D02*
Y579015D01*
G01X407712Y707221D02*
Y695221D01*
G01D02*
X413712D01*
G01X402870Y711871D02*
Y705671D01*
G01D02*
X406070D01*
G01D02*
Y711871D01*
G01D02*
X402870D01*
G01X397553Y718194D02*
Y711994D01*
G01D02*
X400753D01*
G01D02*
Y718194D01*
G01X413712Y707221D02*
X407712D01*
G01X396009Y728030D02*
Y763726D01*
G01X400753Y718194D02*
X397553D01*
G01X406151Y741478D02*
Y729478D01*
G01D02*
X412151D01*
G01Y741478D02*
X406151D01*
G01X398280Y759063D02*
Y747063D01*
G01X404280Y759063D02*
X398280D01*
G01X404280Y747063D02*
Y759063D01*
G01X398280Y747063D02*
X404280D01*
G01X396171Y964888D02*
X402371D01*
Y968088D01*
X396171D01*
Y964888D01*
G01X401671Y980166D02*
X407871D01*
Y983366D01*
X401671D01*
Y980166D01*
G01X396035Y976666D02*
X402235D01*
Y979866D01*
X396035D01*
Y976666D01*
G01X409171Y980166D02*
X415371D01*
Y983366D01*
X409171D01*
Y980166D01*
G01X413759Y999366D02*
X407559D01*
Y996166D01*
X413759D01*
Y999366D01*
G01X405507Y1000103D02*
X402407Y1005473D01*
X399635Y1003873D01*
X402735Y998503D01*
X405507Y1000103D01*
G01X413759Y992866D02*
X407559D01*
Y989666D01*
X413759D01*
Y992866D01*
G01X402585Y996533D02*
X399485Y991163D01*
X402257Y989563D01*
X405357Y994933D01*
X402585Y996533D01*
G01X402171Y986166D02*
X408371D01*
Y989366D01*
X402171D01*
Y986166D01*
G01X409171D02*
X415371D01*
Y989366D01*
X409171D01*
Y986166D01*
G01X400059Y1009166D02*
X406259D01*
Y1012366D01*
X400059D01*
Y1009166D01*
G01X404259Y1008866D02*
X398059D01*
Y1005666D01*
X404259D01*
Y1008866D01*
G01X405559Y1005666D02*
X411759D01*
Y1008866D01*
X405559D01*
Y1005666D01*
G01X399966Y1013874D02*
X406166D01*
Y1017074D01*
X399966D01*
Y1013874D01*
G01Y1017417D02*
X406166D01*
Y1020617D01*
X399966D01*
Y1017417D01*
G01X405059Y1026666D02*
X411259D01*
Y1029866D01*
X405059D01*
Y1026666D01*
G01X404259Y1029866D02*
X398059D01*
Y1026666D01*
X404259D01*
Y1029866D01*
G01X399966Y1020960D02*
X406166D01*
Y1024160D01*
X399966D01*
Y1020960D01*
G01X407259Y1042366D02*
X401059D01*
Y1039166D01*
X407259D01*
Y1042366D01*
G01X414759D02*
X408559D01*
Y1039166D01*
X414759D01*
Y1042366D01*
G01X404259Y1035866D02*
X398059D01*
Y1032666D01*
X404259D01*
Y1035866D01*
G01X405059Y1032666D02*
X411259D01*
Y1035866D01*
X405059D01*
Y1032666D01*
G01X407259Y1054866D02*
X401059D01*
Y1051666D01*
X407259D01*
Y1054866D01*
G01X414759D02*
X408559D01*
Y1051666D01*
X414759D01*
Y1054866D01*
G01X407759Y1061866D02*
X401559D01*
Y1058666D01*
X407759D01*
Y1061866D01*
G01X405759Y1058366D02*
X399559D01*
Y1055166D01*
X405759D01*
Y1058366D01*
G01X413259D02*
X407059D01*
Y1055166D01*
X413259D01*
Y1058366D01*
G01X414759Y1048866D02*
X408559D01*
Y1045666D01*
X414759D01*
Y1048866D01*
G01X407759D02*
X401559D01*
Y1045666D01*
X407759D01*
Y1048866D01*
G01X397171Y1070388D02*
X403371D01*
Y1073588D01*
X397171D01*
Y1070388D01*
G01X409338Y1287503D02*
X411578D01*
G01X410365Y1285878D02*
Y1289128D01*
G01X401803Y1293671D02*
X419519D01*
G01X401803Y1329367D02*
Y1293671D01*
G01X399176Y1298251D02*
Y1310251D01*
G01X419519Y1329367D02*
X401803D01*
G01X397685Y1339414D02*
X400885D01*
G01X397685Y1345614D02*
Y1339414D01*
G01X400885D02*
Y1345614D01*
G01D02*
X397685D01*
G01X395568Y1345737D02*
Y1351937D01*
G01X402386Y1517953D02*
Y1529953D01*
G01X396386Y1517953D02*
X402386D01*
G01X396386Y1529953D02*
Y1517953D01*
G01X409194D02*
Y1529953D01*
G01X403194Y1517953D02*
X409194D01*
G01X403194Y1529953D02*
Y1517953D01*
G01X398206Y1517277D02*
Y1510877D01*
G01D02*
X411086D01*
G01Y1517277D02*
X398206D01*
G01X402386Y1529953D02*
X396386D01*
G01X409194D02*
X403194D01*
G01X397108Y1532721D02*
X409108D01*
G01X397108Y1538721D02*
Y1532721D01*
G01X409108D02*
Y1538721D01*
G01D02*
X397108D01*
G01Y1539575D02*
X409108D01*
G01X397108Y1545575D02*
Y1539575D01*
G01X409108Y1545575D02*
X397108D01*
G01X409108Y1539575D02*
Y1545575D01*
G01X408376Y1611761D02*
Y1608561D01*
G01D02*
X414576D01*
G01Y1611761D02*
X408376D01*
G01X408403Y1617000D02*
Y1613800D01*
G01X414603Y1617000D02*
X408403D01*
G01Y1613800D02*
X414603D01*
G01X397900Y1625200D02*
X404100D01*
Y1628400D01*
X397900D01*
Y1625200D01*
G01X406400Y1634400D02*
X409600D01*
G01X406400Y1640600D02*
Y1634400D01*
G01X409600Y1640600D02*
X406400D01*
G01X409600Y1634400D02*
Y1640600D01*
G01X402906Y1629619D02*
X409106D01*
Y1632819D01*
X402906D01*
Y1629619D01*
G01X410100Y1651100D02*
X406900D01*
G01Y1644900D02*
X410100D01*
G01X406900Y1651100D02*
Y1644900D01*
G01X408400Y1670900D02*
X414600D01*
G01X408400Y1674100D02*
Y1670900D01*
G01X403173Y1668446D02*
Y1677108D01*
G01X399826Y1668446D02*
X403173D01*
G01X397926Y1670646D02*
X399826Y1668446D01*
G01X396026D02*
X397926Y1670646D01*
G01X414600Y1674100D02*
X408400D01*
G01X417000Y-630638D02*
Y-622638D01*
X415800Y-624238D01*
G01Y-630638D02*
X418200D01*
G01X423100Y-627305D02*
X423800Y-626371D01*
X424400Y-625838D01*
X425200Y-625571D01*
X425900Y-625838D01*
X426400Y-626371D01*
X426800Y-627171D01*
X426900Y-628105D01*
X426800Y-628905D01*
X426400Y-629705D01*
X425800Y-630371D01*
X425100Y-630638D01*
X424300Y-630371D01*
X423600Y-629572D01*
X423200Y-628371D01*
X423100Y-627038D01*
X423300Y-625305D01*
X423600Y-624371D01*
X424100Y-623438D01*
X424800Y-622771D01*
X425500Y-622638D01*
X426200Y-622905D01*
X426700Y-623571D01*
G01X433000Y-630905D02*
X432800Y-630771D01*
Y-630505D01*
X433000Y-630371D01*
X433200Y-630505D01*
Y-630771D01*
X433000Y-630905D01*
G01X439100Y-627305D02*
X439800Y-626371D01*
X440400Y-625838D01*
X441200Y-625571D01*
X441900Y-625838D01*
X442400Y-626371D01*
X442800Y-627171D01*
X442900Y-628105D01*
X442800Y-628905D01*
X442400Y-629705D01*
X441800Y-630371D01*
X441100Y-630638D01*
X440300Y-630371D01*
X439600Y-629572D01*
X439200Y-628371D01*
X439100Y-627038D01*
X439300Y-625305D01*
X439600Y-624371D01*
X440100Y-623438D01*
X440800Y-622771D01*
X441500Y-622638D01*
X442200Y-622905D01*
X442700Y-623571D01*
G01X423274Y109212D02*
Y103012D01*
G01D02*
X426474D01*
G01X419274Y109212D02*
Y103012D01*
G01D02*
X422474D01*
G01D02*
Y109212D01*
G01X418374Y103012D02*
Y115892D01*
G01X411974D02*
Y103012D01*
G01X418374D02*
X411974D01*
G01X419148Y126460D02*
Y120260D01*
G01D02*
X422348D01*
G01D02*
Y126460D01*
G01X423648Y113260D02*
Y119460D01*
G01D02*
X420448D01*
G01D02*
Y113260D01*
G01D02*
X423648D01*
G01X427148Y119460D02*
X423948D01*
G01D02*
Y113260D01*
G01D02*
X427148D01*
G01X426474Y109212D02*
X423274D01*
G01X422474D02*
X419274D01*
G01X418374Y115892D02*
X411974D01*
G01X422348Y126460D02*
X419148D01*
G01X415051Y680378D02*
X421051D01*
G01D02*
Y692378D01*
G01X415051D02*
Y680378D01*
G01X415712Y707221D02*
Y695221D01*
G01D02*
X421712D01*
G01D02*
Y707221D01*
G01X413712Y695221D02*
Y707221D01*
G01X421051Y692378D02*
X415051D01*
G01X423251Y707291D02*
Y704865D01*
G01X414093Y745826D02*
Y710130D01*
G01D02*
X431809D01*
G01X421712Y707221D02*
X415712D01*
G01X412151Y729478D02*
Y741478D01*
G01X431809Y745826D02*
X414093D01*
G01X425547Y751945D02*
X428647D01*
Y752865D01*
X428492Y753172D01*
X428130Y753402D01*
X427717Y753479D01*
X427304Y753402D01*
X426994Y753210D01*
X426839Y752865D01*
Y751945D01*
G01X428389Y756655D02*
X428544Y756425D01*
X428647Y756157D01*
Y755850D01*
X428492Y755505D01*
X428234Y755237D01*
X427924Y755045D01*
X427407Y754892D01*
X426942Y754854D01*
X426477Y754930D01*
X426167Y755045D01*
X425857Y755275D01*
X425650Y755544D01*
X425547Y755812D01*
Y756080D01*
X425650Y756349D01*
X425805Y756579D01*
X426012Y756770D01*
G01X425547Y758912D02*
X428647D01*
X428027Y758452D01*
G01X425547D02*
Y759372D01*
G01X428647Y762012D02*
X428544Y761705D01*
X428285Y761475D01*
X427975Y761322D01*
X427562Y761207D01*
X427097Y761169D01*
X426632Y761207D01*
X426219Y761322D01*
X425909Y761475D01*
X425650Y761705D01*
X425547Y762012D01*
X425650Y762319D01*
X425909Y762549D01*
X426219Y762702D01*
X426632Y762817D01*
X427097Y762855D01*
X427562Y762817D01*
X427975Y762702D01*
X428285Y762549D01*
X428544Y762319D01*
X428647Y762012D01*
G01X426012Y764269D02*
X425754Y764499D01*
X425599Y764767D01*
X425547Y765112D01*
X425650Y765457D01*
X425857Y765725D01*
X426219Y765917D01*
X426632Y765955D01*
X427045Y765879D01*
X427304Y765687D01*
X427510Y765419D01*
X427562Y765150D01*
X427510Y764882D01*
X427304Y764537D01*
X428647Y764652D01*
Y765687D01*
G01X424274Y751994D02*
X422034D01*
G01X423247Y753619D02*
Y750369D01*
G01X417371Y968088D02*
X411171D01*
Y964888D01*
X417371D01*
Y968088D01*
G01X418671Y964888D02*
X424871D01*
Y968088D01*
X418671D01*
Y964888D01*
G01X430271Y971688D02*
X424071D01*
Y968488D01*
X430271D01*
Y971688D01*
G01X417259Y979866D02*
X411059D01*
Y976666D01*
X417259D01*
Y979866D01*
G01X418559Y976666D02*
X424759D01*
Y979866D01*
X418559D01*
Y976666D01*
G01X428871Y986866D02*
X422671D01*
Y983666D01*
X428871D01*
Y986866D01*
G01X424171Y980166D02*
X430371D01*
Y983366D01*
X424171D01*
Y980166D01*
G01X416671D02*
X422871D01*
Y983366D01*
X416671D01*
Y980166D01*
G01X421259Y992866D02*
X415059D01*
Y989666D01*
X421259D01*
Y992866D01*
G01X428759D02*
X422559D01*
Y989666D01*
X428759D01*
Y992866D01*
G01X421259Y999366D02*
X415059D01*
Y996166D01*
X421259D01*
Y999366D01*
G01X416145Y986161D02*
X422345D01*
Y989361D01*
X416145D01*
Y986161D01*
G01X428759Y999366D02*
X422559D01*
Y996166D01*
X428759D01*
Y999366D01*
G01X414066Y1004523D02*
X420266D01*
Y1007723D01*
X414066D01*
Y1004523D01*
G01X423516Y1013166D02*
X429716D01*
Y1016366D01*
X423516D01*
Y1013166D01*
G01X414066Y1008264D02*
X420266D01*
Y1011464D01*
X414066D01*
Y1008264D01*
G01X425521Y1004823D02*
Y1011023D01*
X422321D01*
Y1004823D01*
X425521D01*
G01X414066Y1012004D02*
X420266D01*
Y1015204D01*
X414066D01*
Y1012004D01*
G01X422326Y1033604D02*
Y1027404D01*
X425526D01*
Y1033604D01*
X422326D01*
G01X414066Y1019484D02*
X420266D01*
Y1022684D01*
X414066D01*
Y1019484D01*
G01Y1026964D02*
X420266D01*
Y1030164D01*
X414066D01*
Y1026964D01*
G01Y1015744D02*
X420266D01*
Y1018944D01*
X414066D01*
Y1015744D01*
G01X423498Y1021413D02*
X429698D01*
Y1024613D01*
X423498D01*
Y1021413D01*
G01X414066Y1023224D02*
X420266D01*
Y1026424D01*
X414066D01*
Y1023224D01*
G01X423498Y1017279D02*
X429698D01*
Y1020479D01*
X423498D01*
Y1017279D01*
G01X422259Y1042366D02*
X416059D01*
Y1039166D01*
X422259D01*
Y1042366D01*
G01X429759D02*
X423559D01*
Y1039166D01*
X429759D01*
Y1042366D01*
G01X420266Y1033904D02*
X414066D01*
Y1030704D01*
X420266D01*
Y1033904D01*
G01X422259Y1054866D02*
X416059D01*
Y1051666D01*
X422259D01*
Y1054866D01*
G01X419559Y1058666D02*
X425759D01*
Y1061866D01*
X419559D01*
Y1058666D01*
G01X420759Y1058366D02*
X414559D01*
Y1055166D01*
X420759D01*
Y1058366D01*
G01X429759Y1054866D02*
X423559D01*
Y1051666D01*
X429759D01*
Y1054866D01*
G01X427759Y1058366D02*
X421559D01*
Y1055166D01*
X427759D01*
Y1058366D01*
G01X418759Y1061866D02*
X412559D01*
Y1058666D01*
X418759D01*
Y1061866D01*
G01X429759Y1048866D02*
X423559D01*
Y1045666D01*
X429759D01*
Y1048866D01*
G01X422259D02*
X416059D01*
Y1045666D01*
X422259D01*
Y1048866D01*
G01X418871Y1073588D02*
X412671D01*
Y1070388D01*
X418871D01*
Y1073588D01*
G01X419671Y1070388D02*
X425871D01*
Y1073588D01*
X419671D01*
Y1070388D01*
G01X422105Y1282608D02*
X425205D01*
Y1283528D01*
X425050Y1283835D01*
X424688Y1284065D01*
X424275Y1284142D01*
X423862Y1284065D01*
X423552Y1283873D01*
X423397Y1283528D01*
Y1282608D01*
G01X424947Y1287318D02*
X425102Y1287088D01*
X425205Y1286820D01*
Y1286513D01*
X425050Y1286168D01*
X424792Y1285900D01*
X424482Y1285708D01*
X423965Y1285555D01*
X423500Y1285517D01*
X423035Y1285593D01*
X422725Y1285708D01*
X422415Y1285938D01*
X422208Y1286207D01*
X422105Y1286475D01*
Y1286743D01*
X422208Y1287012D01*
X422363Y1287242D01*
X422570Y1287433D01*
G01X422105Y1289575D02*
X425205D01*
X424585Y1289115D01*
G01X422105D02*
Y1290035D01*
G01X425205Y1292675D02*
X425102Y1292368D01*
X424843Y1292138D01*
X424533Y1291985D01*
X424120Y1291870D01*
X423655Y1291832D01*
X423190Y1291870D01*
X422777Y1291985D01*
X422467Y1292138D01*
X422208Y1292368D01*
X422105Y1292675D01*
X422208Y1292982D01*
X422467Y1293212D01*
X422777Y1293365D01*
X423190Y1293480D01*
X423655Y1293518D01*
X424120Y1293480D01*
X424533Y1293365D01*
X424843Y1293212D01*
X425102Y1292982D01*
X425205Y1292675D01*
G01X423397Y1295047D02*
X423758Y1295315D01*
X423965Y1295545D01*
X424068Y1295852D01*
X423965Y1296120D01*
X423758Y1296312D01*
X423448Y1296465D01*
X423087Y1296503D01*
X422777Y1296465D01*
X422467Y1296312D01*
X422208Y1296082D01*
X422105Y1295813D01*
X422208Y1295507D01*
X422518Y1295238D01*
X422983Y1295085D01*
X423500Y1295047D01*
X424172Y1295123D01*
X424533Y1295238D01*
X424895Y1295430D01*
X425153Y1295698D01*
X425205Y1295967D01*
X425102Y1296235D01*
X424843Y1296427D01*
G01X419519Y1293671D02*
Y1329367D01*
G01X421373Y1298368D02*
X427373D01*
G01X421373Y1310368D02*
Y1298368D01*
G01X427373Y1310368D02*
X421373D01*
G01X418177Y1344611D02*
Y1332611D01*
G01X424177D02*
Y1344611D01*
G01X418177Y1332611D02*
X424177D01*
G01X409799Y1344611D02*
Y1332611D01*
G01X415799D02*
Y1344611D01*
G01X409799Y1332611D02*
X415799D01*
G01X424177Y1344611D02*
X418177D01*
G01X415799D02*
X409799D01*
G01X415799Y1347854D02*
Y1359854D01*
G01X409799Y1347854D02*
X415799D01*
G01X409799Y1359854D02*
Y1347854D01*
G01X415799Y1359854D02*
X409799D01*
G01X414133Y1519522D02*
X417333D01*
G01X414133Y1525722D02*
Y1519522D01*
G01X417333D02*
Y1525722D01*
G01X410133Y1519522D02*
X413333D01*
G01X410133Y1525722D02*
Y1519522D01*
G01X413333D02*
Y1525722D01*
G01X411086Y1517277D02*
Y1510877D01*
G01X417333Y1525722D02*
X414133D01*
G01X413333D02*
X410133D01*
G01X418397Y1540146D02*
Y1528146D01*
G01X424397D02*
Y1540146D01*
G01X418397Y1528146D02*
X424397D01*
G01X421915Y1550499D02*
Y1545899D01*
G01X432115Y1550499D02*
X421915D01*
G01Y1545899D02*
X432115D01*
G01X416115Y1550499D02*
Y1545899D01*
G01X426315Y1550499D02*
X416115D01*
G01Y1545899D02*
X426315D01*
G01X424397Y1540146D02*
X418397D01*
G01X414576Y1608561D02*
Y1611761D01*
G01X419231Y1619059D02*
X422431D01*
G01X419231Y1625259D02*
Y1619059D01*
G01X422431D02*
Y1625259D01*
G01D02*
X419231D01*
G01X422720Y1613568D02*
X428920D01*
G01X422720Y1616768D02*
Y1613568D01*
G01X428920Y1616768D02*
X422720D01*
G01X414603Y1613800D02*
Y1617000D01*
G01X414523Y1619080D02*
X417723D01*
G01Y1625280D02*
X414523D01*
G01X417723Y1619080D02*
Y1625280D01*
G01X414523D02*
Y1619080D01*
G01X413236Y1622224D02*
Y1628424D01*
G01X410036Y1622224D02*
X413236D01*
G01X410036Y1628424D02*
Y1622224D01*
G01X413236Y1628424D02*
X410036D01*
G01X413600Y1640600D02*
X410400D01*
G01X413600Y1634400D02*
Y1640600D01*
G01X410400Y1634400D02*
X413600D01*
G01X410400Y1640600D02*
Y1634400D01*
G01X417500Y1629650D02*
X417552Y1629343D01*
X417758Y1629075D01*
X418068Y1628845D01*
X418430Y1628692D01*
X418843Y1628615D01*
X419257D01*
X419670Y1628692D01*
X420032Y1628845D01*
X420342Y1629075D01*
X420548Y1629343D01*
X420600Y1629650D01*
X420548Y1629957D01*
X420342Y1630225D01*
X420032Y1630455D01*
X419670Y1630608D01*
X419257Y1630685D01*
X418843D01*
X418430Y1630608D01*
X418068Y1630455D01*
X417758Y1630225D01*
X417552Y1629957D01*
X417500Y1629650D01*
G01X418327Y1629957D02*
X417500Y1630417D01*
G01Y1632673D02*
X418172Y1632750D01*
X418740Y1632865D01*
X419257Y1633018D01*
X419825Y1633210D01*
X420600Y1633517D01*
Y1631983D01*
G01X417500Y1636310D02*
X420600D01*
X418378Y1634892D01*
Y1636808D01*
G01X417869Y1643000D02*
X415669Y1641100D01*
G01D02*
Y1637753D01*
G01D02*
X424331D01*
G01D02*
Y1648247D01*
G01X418600Y1655100D02*
X412400D01*
G01D02*
Y1651900D01*
G01D02*
X418600D01*
G01D02*
Y1655100D01*
G01X412400Y1659100D02*
Y1655900D01*
G01X418600D02*
Y1659100D01*
G01X412400Y1655900D02*
X418600D01*
G01X410100Y1644900D02*
Y1651100D01*
G01X415669Y1644900D02*
X417869Y1643000D01*
G01X415669Y1648247D02*
Y1644900D01*
G01X424331Y1648247D02*
X415669D01*
G01X418600Y1659100D02*
X412400D01*
G01X414600Y1670900D02*
Y1674100D01*
G01X431274Y109212D02*
Y103012D01*
G01D02*
X434474D01*
G01D02*
Y109212D01*
G01X426474Y103012D02*
Y109212D01*
G01X427274D02*
Y103012D01*
G01D02*
X430474D01*
G01D02*
Y109212D01*
G01X435274D02*
Y103012D01*
G01D02*
X438474D01*
G01D02*
Y109212D01*
G01X439274D02*
Y103012D01*
G01D02*
X442474D01*
G01X428201Y118609D02*
X434401D01*
G01D02*
Y121809D01*
G01X428201D02*
Y118609D01*
G01X434474Y109212D02*
X431274D01*
G01X434826Y109905D02*
Y116105D01*
G01D02*
X431626D01*
G01D02*
Y109905D01*
G01D02*
X434826D01*
G01X427148Y113260D02*
Y119460D01*
G01X431326Y109905D02*
Y116105D01*
G01D02*
X428126D01*
G01D02*
Y109905D01*
G01D02*
X431326D01*
G01X430474Y109212D02*
X427274D01*
G01X438474D02*
X435274D01*
G01X442474D02*
X439274D01*
G01X434401Y121809D02*
X428201D01*
G01X433390Y141242D02*
Y135042D01*
G01D02*
X436590D01*
G01D02*
Y141242D01*
G01X429490D02*
Y135042D01*
G01D02*
X432690D01*
G01D02*
Y141242D01*
G01X425590D02*
Y135042D01*
G01D02*
X428790D01*
G01D02*
Y141242D01*
G01X437290D02*
Y135042D01*
G01D02*
X440490D01*
G01X428201Y122609D02*
X434401D01*
G01D02*
Y125809D01*
G01D02*
X428201D01*
G01D02*
Y122609D01*
G01Y130697D02*
X434401D01*
G01D02*
Y133897D01*
G01D02*
X428201D01*
G01D02*
Y130697D01*
G01Y126697D02*
X434401D01*
G01D02*
Y129897D01*
G01D02*
X428201D01*
G01D02*
Y126697D01*
G01X436590Y141242D02*
X433390D01*
G01X432690D02*
X429490D01*
G01X428790D02*
X425590D01*
G01X440490D02*
X437290D01*
G01X439310Y241065D02*
Y247265D01*
G01D02*
X436110D01*
G01D02*
Y241065D01*
G01D02*
X439310D01*
G01X432110Y247265D02*
Y241065D01*
G01D02*
X435310D01*
G01D02*
Y247265D01*
G01D02*
X432110D01*
G01X433252Y682281D02*
Y670281D01*
G01D02*
X439252D01*
G01D02*
Y682281D01*
G01D02*
X433252D01*
G01X435870Y694071D02*
Y687871D01*
G01D02*
X439070D01*
G01D02*
Y694071D01*
G01D02*
X435870D01*
G01X430553Y700394D02*
Y694194D01*
G01D02*
X433753D01*
G01D02*
Y700394D01*
G01D02*
X430553D01*
G01X431809Y710130D02*
Y745826D01*
G01X434851Y757458D02*
Y745458D01*
G01D02*
X440851D01*
G01Y757458D02*
X434851D01*
G01X430900Y857797D02*
X498500D01*
G01X433495Y966781D02*
X436595Y972151D01*
X433823Y973751D01*
X430723Y968381D01*
X433495Y966781D01*
G01X438559Y971866D02*
Y965666D01*
X441759D01*
Y971866D01*
X438559D01*
G01X430835Y981873D02*
X433935Y976503D01*
X436707Y978103D01*
X433607Y983473D01*
X430835Y981873D01*
G01X438559Y979366D02*
Y973166D01*
X441759D01*
Y979366D01*
X438559D01*
G01Y986866D02*
Y980666D01*
X441759D01*
Y986866D01*
X438559D01*
G01X435759D02*
X429559D01*
Y983666D01*
X435759D01*
Y986866D01*
G01Y999366D02*
X429559D01*
Y996166D01*
X435759D01*
Y999366D01*
G01Y992866D02*
X429559D01*
Y989666D01*
X435759D01*
Y992866D01*
G01X436984Y1000166D02*
X443184D01*
Y1003366D01*
X436984D01*
Y1000166D01*
G01X437059Y988166D02*
X443259D01*
Y991366D01*
X437059D01*
Y988166D01*
G01X436984Y996166D02*
X443184D01*
Y999366D01*
X436984D01*
Y996166D01*
G01Y992166D02*
X443184D01*
Y995366D01*
X436984D01*
Y992166D01*
G01X440482Y1004823D02*
Y1011023D01*
X437282D01*
Y1004823D01*
X440482D01*
G01X433341Y1013145D02*
X439541D01*
Y1016345D01*
X433341D01*
Y1013145D01*
G01X436741Y1004823D02*
Y1011023D01*
X433541D01*
Y1004823D01*
X436741D01*
G01X429261D02*
Y1011023D01*
X426061D01*
Y1004823D01*
X429261D01*
G01X433001D02*
Y1011023D01*
X429801D01*
Y1004823D01*
X433001D01*
G01X433341Y1021413D02*
X439541D01*
Y1024613D01*
X433341D01*
Y1021413D01*
G01X426066Y1033604D02*
Y1027404D01*
X429266D01*
Y1033604D01*
X426066D01*
G01X433341Y1017279D02*
X439541D01*
Y1020479D01*
X433341D01*
Y1017279D01*
G01X437286Y1033604D02*
Y1027404D01*
X440486D01*
Y1033604D01*
X437286D01*
G01X429806D02*
Y1027404D01*
X433006D01*
Y1033604D01*
X429806D01*
G01X433546D02*
Y1027404D01*
X436746D01*
Y1033604D01*
X433546D01*
G01X444259Y1044366D02*
X438059D01*
Y1041166D01*
X444259D01*
Y1044366D01*
G01Y1040366D02*
X438059D01*
Y1037166D01*
X444259D01*
Y1040366D01*
G01X435259Y1058366D02*
X429059D01*
Y1055166D01*
X435259D01*
Y1058366D01*
G01X437259Y1054866D02*
X431059D01*
Y1051666D01*
X437259D01*
Y1054866D01*
G01X436759Y1048866D02*
X430559D01*
Y1045666D01*
X436759D01*
Y1048866D01*
G01X431871Y1070088D02*
X425671D01*
Y1066888D01*
X431871D01*
Y1070088D01*
G01X427373Y1298368D02*
Y1310368D01*
G01X429091Y1301644D02*
X432291D01*
G01X429091Y1307844D02*
Y1301644D01*
G01X432291Y1307844D02*
X429091D01*
G01X432291Y1301644D02*
Y1307844D01*
G01X437402Y1504267D02*
Y1498267D01*
X449402D01*
Y1504267D01*
X437402D01*
G01X437153Y1533892D02*
X425153D01*
G01X437153Y1527892D02*
Y1533892D01*
G01X425153Y1527892D02*
X437153D01*
G01X425153Y1533892D02*
Y1527892D01*
G01X437179Y1534746D02*
Y1540746D01*
G01X425179Y1534746D02*
X437179D01*
G01X425179Y1540746D02*
Y1534746D01*
G01X432115Y1545899D02*
Y1550499D01*
G01X426315Y1545899D02*
Y1550499D01*
G01X437179Y1540746D02*
X425179D01*
G01X431577Y1606770D02*
Y1609970D01*
G01X425377Y1606770D02*
X431577D01*
G01X425377Y1609970D02*
Y1606770D01*
G01X431577Y1609970D02*
X425377D01*
G01X428920Y1613568D02*
Y1616768D01*
G01X434400Y1624400D02*
X440600D01*
G01X434400Y1627600D02*
Y1624400D01*
G01X428100Y1617850D02*
X428152Y1617543D01*
X428358Y1617275D01*
X428668Y1617045D01*
X429030Y1616892D01*
X429443Y1616815D01*
X429857D01*
X430270Y1616892D01*
X430632Y1617045D01*
X430942Y1617275D01*
X431148Y1617543D01*
X431200Y1617850D01*
X431148Y1618157D01*
X430942Y1618425D01*
X430632Y1618655D01*
X430270Y1618808D01*
X429857Y1618885D01*
X429443D01*
X429030Y1618808D01*
X428668Y1618655D01*
X428358Y1618425D01*
X428152Y1618157D01*
X428100Y1617850D01*
G01X428927Y1618157D02*
X428100Y1618617D01*
G01Y1620950D02*
X431200D01*
X430580Y1620490D01*
G01X428100D02*
Y1621410D01*
G01Y1624510D02*
X431200D01*
X428978Y1623092D01*
Y1625008D01*
G01X428100Y1627150D02*
X428152Y1627418D01*
X428307Y1627725D01*
X428565Y1627917D01*
X428927Y1627993D01*
X429288Y1627917D01*
X429598Y1627687D01*
X429753Y1627342D01*
Y1626958D01*
X429857Y1626728D01*
X430115Y1626537D01*
X430477Y1626460D01*
X430838Y1626575D01*
X431097Y1626843D01*
X431200Y1627150D01*
X431097Y1627457D01*
X430838Y1627725D01*
X430477Y1627840D01*
X430115Y1627763D01*
X429857Y1627572D01*
X429753Y1627342D01*
Y1626958D01*
X429598Y1626613D01*
X429288Y1626383D01*
X428927Y1626307D01*
X428565Y1626383D01*
X428307Y1626575D01*
X428152Y1626882D01*
X428100Y1627150D01*
G01X435400Y1643100D02*
Y1639900D01*
G01D02*
X441600D01*
G01X437400Y1628400D02*
X443600D01*
G01X437400Y1631600D02*
Y1628400D01*
G01X443600Y1631600D02*
X437400D01*
G01X440600Y1627600D02*
X434400D01*
G01X425669Y1628753D02*
X434331D01*
G01X432131Y1634000D02*
X434331Y1635900D01*
G01Y1632100D02*
X432131Y1634000D01*
G01X434331Y1628753D02*
Y1632100D01*
G01X425669Y1639247D02*
Y1628753D01*
G01X434331Y1639247D02*
X425669D01*
G01X434331Y1635900D02*
Y1639247D01*
G01X426400Y1641900D02*
X429600D01*
G01X426400Y1648100D02*
Y1641900D01*
G01X429600D02*
Y1648100D01*
G01D02*
X426400D01*
G01X441600Y1643100D02*
X435400D01*
G01Y1648100D02*
Y1644900D01*
G01X441600Y1648100D02*
X435400D01*
G01Y1644900D02*
X441600D01*
G01X430400Y1641900D02*
X433600D01*
G01X430400Y1648100D02*
Y1641900D01*
G01X433600Y1648100D02*
X430400D01*
G01X433600Y1641900D02*
Y1648100D01*
G01X448577Y1652942D02*
X448884Y1652994D01*
X449152Y1653200D01*
X449382Y1653510D01*
X449535Y1653872D01*
X449612Y1654285D01*
Y1654699D01*
X449535Y1655112D01*
X449382Y1655474D01*
X449152Y1655784D01*
X448884Y1655990D01*
X448577Y1656042D01*
X448270Y1655990D01*
X448002Y1655784D01*
X447772Y1655474D01*
X447619Y1655112D01*
X447542Y1654699D01*
Y1654285D01*
X447619Y1653872D01*
X447772Y1653510D01*
X448002Y1653200D01*
X448270Y1652994D01*
X448577Y1652942D01*
G01X448270Y1653769D02*
X447810Y1652942D01*
G01X445477D02*
Y1656042D01*
X445937Y1655422D01*
G01Y1652942D02*
X445017D01*
G01X442377Y1656042D02*
X442684Y1655939D01*
X442914Y1655680D01*
X443067Y1655370D01*
X443182Y1654957D01*
X443220Y1654492D01*
X443182Y1654027D01*
X443067Y1653614D01*
X442914Y1653304D01*
X442684Y1653045D01*
X442377Y1652942D01*
X442070Y1653045D01*
X441840Y1653304D01*
X441687Y1653614D01*
X441572Y1654027D01*
X441534Y1654492D01*
X441572Y1654957D01*
X441687Y1655370D01*
X441840Y1655680D01*
X442070Y1655939D01*
X442377Y1656042D01*
G01X439277Y1652942D02*
X439009Y1652994D01*
X438702Y1653149D01*
X438510Y1653407D01*
X438434Y1653769D01*
X438510Y1654130D01*
X438740Y1654440D01*
X439085Y1654595D01*
X439469D01*
X439699Y1654699D01*
X439890Y1654957D01*
X439967Y1655319D01*
X439852Y1655680D01*
X439584Y1655939D01*
X439277Y1656042D01*
X438970Y1655939D01*
X438702Y1655680D01*
X438587Y1655319D01*
X438664Y1654957D01*
X438855Y1654699D01*
X439085Y1654595D01*
X439469D01*
X439814Y1654440D01*
X440044Y1654130D01*
X440120Y1653769D01*
X440044Y1653407D01*
X439852Y1653149D01*
X439545Y1652994D01*
X439277Y1652942D01*
G01X453857Y105564D02*
Y99364D01*
G01D02*
X457057D01*
G01Y105564D02*
X453857D01*
G01X445093Y108090D02*
Y104890D01*
G01D02*
X451293D01*
G01D02*
Y108090D01*
G01Y104090D02*
X445093D01*
G01D02*
Y100890D01*
G01D02*
X451293D01*
G01D02*
Y104090D01*
G01X442474Y103012D02*
Y109212D01*
G01X451293Y108090D02*
X445093D01*
G01X450490Y108907D02*
Y115107D01*
G01D02*
X447290D01*
G01D02*
Y108907D01*
G01D02*
X450490D01*
G01X454490Y115107D02*
X451290D01*
G01D02*
Y108907D01*
G01D02*
X454490D01*
G01X449099Y123007D02*
Y117007D01*
G01D02*
X461099D01*
G01X441190Y141242D02*
Y135042D01*
G01D02*
X444390D01*
G01D02*
Y141242D01*
G01X440490Y135042D02*
Y141242D01*
G01X445090Y129242D02*
X451090D01*
G01D02*
Y141242D01*
G01X445090D02*
Y129242D01*
G01X461099Y123007D02*
X449099D01*
G01X444390Y141242D02*
X441190D01*
G01X451090D02*
X445090D01*
G01X452334Y148719D02*
Y135839D01*
G01D02*
X458734D01*
G01X452334Y148719D02*
X458734D01*
G01X453310Y240065D02*
Y246265D01*
G01D02*
X450110D01*
G01D02*
Y240065D01*
G01D02*
X453310D01*
G01X443310Y241065D02*
Y247265D01*
G01D02*
X440110D01*
G01D02*
Y241065D01*
G01D02*
X443310D01*
G01X449310Y240065D02*
Y246265D01*
G01D02*
X446110D01*
G01D02*
Y240065D01*
G01D02*
X449310D01*
G01X447551Y655978D02*
X453551D01*
G01D02*
Y667978D01*
G01X447551D02*
Y655978D01*
G01X440112Y682321D02*
Y670321D01*
G01D02*
X446112D01*
G01D02*
Y682321D01*
G01X448212D02*
Y670321D01*
G01D02*
X454212D01*
G01D02*
Y682321D01*
G01X453551Y667978D02*
X447551D01*
G01X457451Y682691D02*
Y680265D01*
G01X448293Y721226D02*
Y685530D01*
G01D02*
X466009D01*
G01X446112Y682321D02*
X440112D01*
G01X454212D02*
X448212D01*
G01X440351Y703449D02*
X446351D01*
G01D02*
Y715449D01*
G01D02*
X440351D01*
G01D02*
Y703449D01*
G01X454027Y730025D02*
X457127D01*
Y730945D01*
X456972Y731252D01*
X456610Y731482D01*
X456197Y731559D01*
X455784Y731482D01*
X455474Y731290D01*
X455319Y730945D01*
Y730025D01*
G01X456869Y734735D02*
X457024Y734505D01*
X457127Y734237D01*
Y733930D01*
X456972Y733585D01*
X456714Y733317D01*
X456404Y733125D01*
X455887Y732972D01*
X455422Y732934D01*
X454957Y733010D01*
X454647Y733125D01*
X454337Y733355D01*
X454130Y733624D01*
X454027Y733892D01*
Y734160D01*
X454130Y734429D01*
X454285Y734659D01*
X454492Y734850D01*
G01X454647Y736149D02*
X454285Y736379D01*
X454079Y736685D01*
X454027Y737030D01*
X454079Y737337D01*
X454337Y737644D01*
X454647Y737835D01*
X454957Y737874D01*
X455319Y737797D01*
X455577Y737529D01*
X455680Y737260D01*
Y736915D01*
G01Y737260D02*
X455835Y737490D01*
X456094Y737682D01*
X456404Y737759D01*
X456714Y737682D01*
X456972Y737490D01*
X457127Y737145D01*
X457075Y736800D01*
X456869Y736455D01*
G01X454027Y740552D02*
X457127D01*
X454905Y739134D01*
Y741050D01*
G01X454647Y742349D02*
X454285Y742579D01*
X454079Y742885D01*
X454027Y743230D01*
X454079Y743537D01*
X454337Y743844D01*
X454647Y744035D01*
X454957Y744074D01*
X455319Y743997D01*
X455577Y743729D01*
X455680Y743460D01*
Y743115D01*
G01Y743460D02*
X455835Y743690D01*
X456094Y743882D01*
X456404Y743959D01*
X456714Y743882D01*
X456972Y743690D01*
X457127Y743345D01*
X457075Y743000D01*
X456869Y742655D01*
G01X466009Y721226D02*
X448293D01*
G01X440851Y745458D02*
Y757458D01*
G01X449595Y968381D02*
X446495Y973751D01*
X443723Y972151D01*
X446823Y966781D01*
X449595Y968381D01*
G01X450171Y968388D02*
X456371D01*
Y971588D01*
X450171D01*
Y968388D01*
G01X452259Y983366D02*
X446059D01*
Y980166D01*
X452259D01*
Y983366D01*
G01X450759Y986866D02*
X444559D01*
Y983666D01*
X450759D01*
Y986866D01*
G01X459759Y983366D02*
X453559D01*
Y980166D01*
X459759D01*
Y983366D01*
G01X458259Y999366D02*
X452059D01*
Y996166D01*
X458259D01*
Y999366D01*
G01Y992866D02*
X452059D01*
Y989666D01*
X458259D01*
Y992866D01*
G01X459759Y989366D02*
X453559D01*
Y986166D01*
X459759D01*
Y989366D01*
G01X450759Y999366D02*
X444559D01*
Y996166D01*
X450759D01*
Y999366D01*
G01Y992866D02*
X444559D01*
Y989666D01*
X450759D01*
Y992866D01*
G01X447962Y1004823D02*
Y1011023D01*
X444762D01*
Y1004823D01*
X447962D01*
G01X451702D02*
Y1011023D01*
X448502D01*
Y1004823D01*
X451702D01*
G01X444222D02*
Y1011023D01*
X441022D01*
Y1004823D01*
X444222D01*
G01X455442D02*
Y1011023D01*
X452242D01*
Y1004823D01*
X455442D01*
G01X452435Y1013145D02*
X458635D01*
Y1016345D01*
X452435D01*
Y1013145D01*
G01X442199D02*
X448399D01*
Y1016345D01*
X442199D01*
Y1013145D01*
G01X441026Y1033604D02*
Y1027404D01*
X444226D01*
Y1033604D01*
X441026D01*
G01X448507D02*
Y1027404D01*
X451707D01*
Y1033604D01*
X448507D01*
G01X442199Y1021413D02*
X448399D01*
Y1024613D01*
X442199D01*
Y1021413D01*
G01X452247Y1033604D02*
Y1027404D01*
X455447D01*
Y1033604D01*
X452247D01*
G01X444766D02*
Y1027404D01*
X447966D01*
Y1033604D01*
X444766D01*
G01X452435Y1021413D02*
X458635D01*
Y1024613D01*
X452435D01*
Y1021413D01*
G01Y1017279D02*
X458635D01*
Y1020479D01*
X452435D01*
Y1017279D01*
G01X442199D02*
X448399D01*
Y1020479D01*
X442199D01*
Y1017279D01*
G01X459259Y1042366D02*
X453059D01*
Y1039166D01*
X459259D01*
Y1042366D01*
G01X452049Y1054866D02*
X445849D01*
Y1051666D01*
X452049D01*
Y1054866D01*
G01X453759Y1058366D02*
X447559D01*
Y1055166D01*
X453759D01*
Y1058366D01*
G01X442759Y1050166D02*
Y1056366D01*
X439559D01*
Y1050166D01*
X442759D01*
G01X459530Y1054866D02*
X453330D01*
Y1051666D01*
X459530D01*
Y1054866D01*
G01X451759Y1048866D02*
X445559D01*
Y1045666D01*
X451759D01*
Y1048866D01*
G01X459259D02*
X453059D01*
Y1045666D01*
X459259D01*
Y1048866D01*
G01X451171Y1066888D02*
X457371D01*
Y1070088D01*
X451171D01*
Y1066888D01*
G01X455590Y1488103D02*
X457830D01*
G01X456617Y1486478D02*
Y1489728D01*
G01X452985Y1491980D02*
X488725D01*
Y1508910D01*
X452985D01*
Y1491980D01*
G01X451785Y1491978D02*
X452985D01*
G01X451785D02*
X451791Y1508961D01*
G01X452385Y1491978D02*
X452381Y1508953D01*
G01X452985Y1491978D02*
X452982Y1508918D01*
G01X451835Y1508911D02*
X453344Y1508907D01*
G01X452352Y1534538D02*
Y1540738D01*
G01X449152Y1534538D02*
X452352D01*
G01X449152Y1540738D02*
Y1534538D01*
G01X453877Y1540738D02*
Y1534538D01*
X457077D01*
Y1540738D01*
X453877D01*
G01X452352D02*
X449152D01*
G01X445594Y1543812D02*
Y1537612D01*
G01X448794Y1543812D02*
X445594D01*
G01X448794Y1537612D02*
Y1543812D01*
G01X445594Y1537612D02*
X448794D01*
G01X440600Y1624400D02*
Y1627600D01*
G01X441600Y1639900D02*
Y1643100D01*
G01X443600Y1628400D02*
Y1631600D01*
G01X443253Y1648331D02*
Y1639669D01*
G01D02*
X453747D01*
G01D02*
Y1648331D01*
G01X441600Y1644900D02*
Y1648100D01*
G01X453747Y1648331D02*
X450400D01*
G01D02*
X448500Y1646131D01*
G01D02*
X446600Y1648331D01*
G01D02*
X443253D01*
G01X462000Y-630638D02*
Y-622638D01*
X460800Y-624238D01*
G01Y-630638D02*
X463200D01*
G01X469800D02*
X470000Y-628905D01*
X470300Y-627438D01*
X470700Y-626105D01*
X471200Y-624638D01*
X472000Y-622638D01*
X468000D01*
G01X478000Y-630905D02*
X477800Y-630771D01*
Y-630505D01*
X478000Y-630371D01*
X478200Y-630505D01*
Y-630771D01*
X478000Y-630905D01*
G01X484100Y-623971D02*
X484700Y-623171D01*
X485400Y-622771D01*
X486200Y-622638D01*
X487200Y-622905D01*
X487900Y-623571D01*
X488100Y-624371D01*
X488000Y-625172D01*
X487600Y-625838D01*
X485600Y-627171D01*
X484700Y-628105D01*
X484100Y-629438D01*
X483900Y-630638D01*
X488100D01*
G01X457857Y105564D02*
Y99364D01*
G01D02*
X461057D01*
G01D02*
Y105564D01*
G01D02*
X457857D01*
G01X457057Y99364D02*
Y105564D01*
G01X457932Y110439D02*
X464132D01*
G01D02*
Y113639D01*
G01D02*
X457932D01*
G01D02*
Y110439D01*
G01Y106439D02*
X464132D01*
G01D02*
Y109639D01*
G01D02*
X457932D01*
G01D02*
Y106439D01*
G01X454490Y108907D02*
Y115107D01*
G01X461099Y117007D02*
Y123007D01*
G01X458734Y135839D02*
Y148719D01*
G01X471912Y655921D02*
X465912D01*
G01D02*
Y643921D01*
G01D02*
X471912D01*
G01X465013Y643764D02*
Y655764D01*
G01X459013Y643764D02*
X465013D01*
G01X459013Y655764D02*
Y643764D01*
G01X465013Y655764D02*
X459013D01*
G01X468270Y669471D02*
Y663271D01*
G01D02*
X471470D01*
G01Y669471D02*
X468270D01*
G01X462953Y675794D02*
Y669594D01*
G01D02*
X466153D01*
G01D02*
Y675794D01*
G01X466009Y685530D02*
Y721226D01*
G01X466153Y675794D02*
X462953D01*
G01X467951Y690878D02*
X473951D01*
G01X467951Y702878D02*
Y690878D01*
G01X473951Y702878D02*
X467951D01*
G01X458474Y727394D02*
X456234D01*
G01X457447Y729019D02*
Y725769D01*
G01X463171Y964888D02*
X469371D01*
Y968088D01*
X463171D01*
Y964888D01*
G01X461871Y968088D02*
X455671D01*
Y964888D01*
X461871D01*
Y968088D01*
G01X474759Y983366D02*
X468559D01*
Y980166D01*
X474759D01*
Y983366D01*
G01X462559Y976666D02*
X468759D01*
Y979866D01*
X462559D01*
Y976666D01*
G01X461759Y979866D02*
X455559D01*
Y976666D01*
X461759D01*
Y979866D01*
G01X467259Y983366D02*
X461059D01*
Y980166D01*
X467259D01*
Y983366D01*
G01X465259Y992866D02*
X459059D01*
Y989666D01*
X465259D01*
Y992866D01*
G01Y999366D02*
X459059D01*
Y996166D01*
X465259D01*
Y999366D01*
G01X467259Y989366D02*
X461059D01*
Y986166D01*
X467259D01*
Y989366D01*
G01X474759D02*
X468559D01*
Y986166D01*
X474759D01*
Y989366D01*
G01X472759Y999366D02*
X466559D01*
Y996166D01*
X472759D01*
Y999366D01*
G01Y992866D02*
X466559D01*
Y989666D01*
X472759D01*
Y992866D01*
G01X467256Y1015204D02*
X461056D01*
Y1012004D01*
X467256D01*
Y1015204D01*
G01X459182Y1004823D02*
Y1011023D01*
X455982D01*
Y1004823D01*
X459182D01*
G01X467256Y1011464D02*
X461056D01*
Y1008264D01*
X467256D01*
Y1011464D01*
G01Y1007723D02*
X461056D01*
Y1004523D01*
X467256D01*
Y1007723D01*
G01Y1018944D02*
X461056D01*
Y1015744D01*
X467256D01*
Y1018944D01*
G01Y1026424D02*
X461056D01*
Y1023224D01*
X467256D01*
Y1026424D01*
G01Y1030164D02*
X461056D01*
Y1026964D01*
X467256D01*
Y1030164D01*
G01Y1022684D02*
X461056D01*
Y1019484D01*
X467256D01*
Y1022684D01*
G01X455987Y1033604D02*
Y1027404D01*
X459187D01*
Y1033604D01*
X455987D01*
G01X467256Y1033904D02*
X461056D01*
Y1030704D01*
X467256D01*
Y1033904D01*
G01X466759Y1042366D02*
X460559D01*
Y1039166D01*
X466759D01*
Y1042366D01*
G01X474259D02*
X468059D01*
Y1039166D01*
X474259D01*
Y1042366D01*
G01X466759Y1048866D02*
X460559D01*
Y1045666D01*
X466759D01*
Y1048866D01*
G01X474259D02*
X468059D01*
Y1045666D01*
X474259D01*
Y1048866D01*
G01X461259Y1058366D02*
X455059D01*
Y1055166D01*
X461259D01*
Y1058366D01*
G01X467010Y1054866D02*
X460810D01*
Y1051666D01*
X467010D01*
Y1054866D01*
G01X468759Y1058366D02*
X462559D01*
Y1055166D01*
X468759D01*
Y1058366D01*
G01X474259Y1054745D02*
X468059D01*
Y1051545D01*
X474259D01*
Y1054745D01*
G01X463259Y1061866D02*
X457059D01*
Y1058666D01*
X463259D01*
Y1061866D01*
G01X464059Y1058666D02*
X470259D01*
Y1061866D01*
X464059D01*
Y1058666D01*
G01X462871Y1073588D02*
X456671D01*
Y1070388D01*
X462871D01*
Y1073588D01*
G01X464171Y1070388D02*
X470371D01*
Y1073588D01*
X464171D01*
Y1070388D01*
G01X475882Y1489374D02*
X476112Y1489529D01*
X476380Y1489632D01*
X476687D01*
X477032Y1489477D01*
X477300Y1489219D01*
X477492Y1488909D01*
X477645Y1488392D01*
X477683Y1487927D01*
X477607Y1487462D01*
X477492Y1487152D01*
X477262Y1486842D01*
X476993Y1486635D01*
X476725Y1486532D01*
X476457D01*
X476188Y1486635D01*
X475958Y1486790D01*
X475767Y1486997D01*
G01X473702Y1486532D02*
X473625Y1487204D01*
X473510Y1487772D01*
X473357Y1488289D01*
X473165Y1488857D01*
X472858Y1489632D01*
X474392D01*
G01X470525D02*
X470832Y1489529D01*
X471062Y1489270D01*
X471215Y1488960D01*
X471330Y1488547D01*
X471368Y1488082D01*
X471330Y1487617D01*
X471215Y1487204D01*
X471062Y1486894D01*
X470832Y1486635D01*
X470525Y1486532D01*
X470218Y1486635D01*
X469988Y1486894D01*
X469835Y1487204D01*
X469720Y1487617D01*
X469682Y1488082D01*
X469720Y1488547D01*
X469835Y1488960D01*
X469988Y1489270D01*
X470218Y1489529D01*
X470525Y1489632D01*
G01X468153Y1489115D02*
X467923Y1489425D01*
X467655Y1489580D01*
X467348Y1489632D01*
X466965Y1489529D01*
X466697Y1489270D01*
X466620Y1488960D01*
X466658Y1488650D01*
X466812Y1488392D01*
X467578Y1487875D01*
X467923Y1487514D01*
X468153Y1486997D01*
X468230Y1486532D01*
X466620D01*
G01X464977Y1486894D02*
X464708Y1486635D01*
X464402Y1486532D01*
X464095Y1486635D01*
X463827Y1486945D01*
X463635Y1487410D01*
X463558Y1487875D01*
Y1488444D01*
X463635Y1488909D01*
X463827Y1489322D01*
X464057Y1489529D01*
X464325Y1489632D01*
X464632Y1489529D01*
X464862Y1489322D01*
X465015Y1489012D01*
X465092Y1488599D01*
X465015Y1488237D01*
X464823Y1487875D01*
X464593Y1487669D01*
X464325Y1487617D01*
X464018Y1487720D01*
X463788Y1487979D01*
X463558Y1488444D01*
G01X461802Y1534538D02*
Y1540738D01*
G01X458602Y1534538D02*
X461802D01*
G01X458602Y1540738D02*
Y1534538D01*
G01X463326Y1540738D02*
Y1534538D01*
X466526D01*
Y1540738D01*
X463326D01*
G01X468051D02*
Y1534538D01*
X471251D01*
Y1540738D01*
X468051D01*
G01X461802D02*
X458602D01*
G01X458751Y1634342D02*
Y1640542D01*
G01D02*
X455551D01*
G01Y1634342D02*
X458751D01*
G01X455551Y1640542D02*
Y1634342D01*
G01X459586Y1634350D02*
X462786D01*
G01X459586Y1640550D02*
Y1634350D01*
G01X462786Y1640550D02*
X459586D01*
G01X462786Y1634350D02*
Y1640550D01*
G01X459400Y1648600D02*
Y1642400D01*
G01X462600D02*
Y1648600D01*
G01D02*
X459400D01*
G01Y1642400D02*
X462600D01*
G01X458600Y1648600D02*
X455400D01*
G01X458600Y1642400D02*
Y1648600D01*
G01X455400Y1642400D02*
X458600D01*
G01X455400Y1648600D02*
Y1642400D01*
G01X486200Y-598305D02*
X485600Y-597905D01*
X484900Y-597638D01*
X484100D01*
X483200Y-598038D01*
X482500Y-598705D01*
X482000Y-599505D01*
X481600Y-600838D01*
X481500Y-602038D01*
X481700Y-603238D01*
X482000Y-604038D01*
X482600Y-604838D01*
X483300Y-605371D01*
X484000Y-605638D01*
X484700D01*
X485400Y-605371D01*
X486000Y-604971D01*
X486500Y-604438D01*
G01X476468Y279493D02*
X482668D01*
G01D02*
Y282693D01*
G01D02*
X476468D01*
G01D02*
Y279493D01*
G01X473318Y287293D02*
Y284093D01*
G01D02*
X479518D01*
G01D02*
Y287293D01*
G01D02*
X473318D01*
G01X475039Y317027D02*
Y310827D01*
G01D02*
X478239D01*
G01D02*
Y317027D01*
G01D02*
X475039D01*
G01X480251Y629478D02*
X486251D01*
G01Y641478D02*
X480251D01*
G01D02*
Y629478D01*
G01X471912Y643921D02*
Y655921D01*
G01X478812D02*
X472812D01*
G01D02*
Y643921D01*
G01D02*
X478812D01*
G01D02*
Y655921D01*
G01X486812D02*
X480812D01*
G01D02*
Y643921D01*
G01D02*
X486812D01*
G01X475893Y694660D02*
Y658964D01*
G01D02*
X493609D01*
G01X471470Y663271D02*
Y669471D01*
G01X486074Y700828D02*
X483834D01*
G01X485047Y702453D02*
Y699203D01*
G01X493609Y694660D02*
X475893D01*
G01X473951Y690878D02*
Y702878D01*
G01X484135Y968089D02*
X477935D01*
Y964889D01*
X484135D01*
Y968089D01*
G01X482259Y983366D02*
X476059D01*
Y980166D01*
X482259D01*
Y983366D01*
G01X489759D02*
X483559D01*
Y980166D01*
X489759D01*
Y983366D01*
G01X483835Y979866D02*
X477635D01*
Y976666D01*
X483835D01*
Y979866D01*
G01X482259Y1002366D02*
X476059D01*
Y999166D01*
X482259D01*
Y1002366D01*
G01Y995866D02*
X476059D01*
Y992666D01*
X482259D01*
Y995866D01*
G01X489759Y1002366D02*
X483559D01*
Y999166D01*
X489759D01*
Y1002366D01*
G01X482259Y989366D02*
X476059D01*
Y986166D01*
X482259D01*
Y989366D01*
G01X489759Y995866D02*
X483559D01*
Y992666D01*
X489759D01*
Y995866D01*
G01Y989366D02*
X483559D01*
Y986166D01*
X489759D01*
Y989366D01*
G01Y1008866D02*
X483559D01*
Y1005666D01*
X489759D01*
Y1008866D01*
G01Y1017074D02*
X483559D01*
Y1013874D01*
X489759D01*
Y1017074D01*
G01X482178D02*
X475978D01*
Y1013874D01*
X482178D01*
Y1017074D01*
G01X482259Y1008866D02*
X476059D01*
Y1005666D01*
X482259D01*
Y1008866D01*
G01X485259Y1029345D02*
X479059D01*
Y1026145D01*
X485259D01*
Y1029345D01*
G01X482178Y1020617D02*
X475978D01*
Y1017417D01*
X482178D01*
Y1020617D01*
G01Y1024160D02*
X475978D01*
Y1020960D01*
X482178D01*
Y1024160D01*
G01X489759Y1020617D02*
X483559D01*
Y1017417D01*
X489759D01*
Y1020617D01*
G01X486807Y1032845D02*
X480607D01*
Y1029645D01*
X486807D01*
Y1032845D01*
G01X489759Y1024160D02*
X483559D01*
Y1020960D01*
X489759D01*
Y1024160D01*
G01X488759Y1042366D02*
X482559D01*
Y1039166D01*
X488759D01*
Y1042366D01*
G01X483197Y1038866D02*
X476997D01*
Y1035666D01*
X483197D01*
Y1038866D01*
G01X481259Y1042366D02*
X475059D01*
Y1039166D01*
X481259D01*
Y1042366D01*
G01X488759Y1048866D02*
X482559D01*
Y1045666D01*
X488759D01*
Y1048866D01*
G01X481759D02*
X475559D01*
Y1045666D01*
X481759D01*
Y1048866D01*
G01X488759Y1054745D02*
X482559D01*
Y1051545D01*
X488759D01*
Y1054745D01*
G01X475759Y1058366D02*
X469559D01*
Y1055166D01*
X475759D01*
Y1058366D01*
G01X481259Y1054745D02*
X475059D01*
Y1051545D01*
X481259D01*
Y1054745D01*
G01X483259Y1058366D02*
X477059D01*
Y1055166D01*
X483259D01*
Y1058366D01*
G01X475559Y1058666D02*
X481759D01*
Y1061866D01*
X475559D01*
Y1058666D01*
G01X485371Y1073588D02*
X479171D01*
Y1070388D01*
X485371D01*
Y1073588D01*
G01X484223Y1490178D02*
X486649D01*
G01X480699Y1534538D02*
Y1540738D01*
G01X477499Y1534538D02*
X480699D01*
G01X477499Y1540738D02*
Y1534538D01*
G01X475975D02*
Y1540738D01*
G01X472775Y1534538D02*
X475975D01*
G01X472775Y1540738D02*
Y1534538D01*
G01X482224D02*
X485424D01*
G01X482224Y1540738D02*
Y1534538D01*
G01X480699Y1540738D02*
X477499D01*
G01X475975D02*
X472775D01*
G01X485424D02*
X482224D01*
G01X478346Y1646023D02*
Y1664200D01*
G01X568503Y1646023D02*
X478346D01*
G01X488000Y1735167D02*
X480500D01*
Y1732927D01*
X480875Y1732180D01*
X481750Y1731620D01*
X482750Y1731433D01*
X483750Y1731620D01*
X484500Y1732087D01*
X484875Y1732927D01*
Y1735167D01*
G01X488000Y1727667D02*
X480500D01*
Y1725333D01*
X480875Y1724587D01*
X481375Y1724120D01*
X482375Y1723933D01*
X483375Y1724120D01*
X484000Y1724680D01*
X484375Y1725333D01*
Y1727667D01*
G01Y1725333D02*
X488000Y1723933D01*
G01Y1716433D02*
Y1720167D01*
X480500D01*
Y1716433D01*
G01X484125Y1717927D02*
Y1720167D01*
G01X487000Y1712760D02*
X487625Y1712013D01*
X488000Y1711173D01*
Y1710427D01*
X487625Y1709680D01*
X487000Y1709120D01*
X486125Y1708840D01*
X485250Y1709027D01*
X484500Y1709493D01*
X484000Y1710333D01*
X483750Y1711453D01*
X483250Y1712107D01*
X482375Y1712387D01*
X481500Y1712200D01*
X480875Y1711733D01*
X480500Y1711080D01*
Y1710427D01*
X480750Y1709773D01*
X481375Y1709213D01*
G01X487000Y1705260D02*
X487625Y1704513D01*
X488000Y1703673D01*
Y1702927D01*
X487625Y1702180D01*
X487000Y1701620D01*
X486125Y1701340D01*
X485250Y1701527D01*
X484500Y1701993D01*
X484000Y1702833D01*
X483750Y1703953D01*
X483250Y1704607D01*
X482375Y1704887D01*
X481500Y1704700D01*
X480875Y1704233D01*
X480500Y1703580D01*
Y1702927D01*
X480750Y1702273D01*
X481375Y1701713D01*
G01X485500Y1697013D02*
Y1694587D01*
G01X488000Y1690073D02*
X480500D01*
Y1686527D01*
G01X484125Y1687833D02*
Y1690073D01*
G01X480500Y1681920D02*
Y1679680D01*
G01Y1680800D02*
X488000D01*
G01Y1681920D02*
Y1679680D01*
G01X480500Y1673300D02*
X488000D01*
G01X480500Y1675447D02*
Y1671153D01*
G01X478346Y1669300D02*
Y1698800D01*
G01Y1717500D02*
Y1781456D01*
G01D02*
X568503D01*
G01X501176Y132498D02*
X497976D01*
G01D02*
Y126298D01*
G01D02*
X501176D01*
G01X506356Y125368D02*
X496156D01*
G01D02*
Y120768D01*
G01D02*
X506356D01*
G01X500642Y145145D02*
X494442D01*
G01D02*
Y141945D01*
G01D02*
X500642D01*
G01Y149145D02*
X494442D01*
G01D02*
Y145945D01*
G01D02*
X500642D01*
G01X494052Y156145D02*
Y149945D01*
G01D02*
X497252D01*
G01D02*
Y156145D01*
G01X498052D02*
Y149945D01*
G01D02*
X501252D01*
G01X500642Y140198D02*
X494442D01*
G01D02*
Y136998D01*
G01D02*
X500642D01*
G01X497252Y156145D02*
X494052D01*
G01X501252D02*
X498052D01*
G01X497286Y169518D02*
Y159318D01*
G01D02*
X501886D01*
G01Y169518D02*
X497286D01*
G01X486898Y284293D02*
X493098D01*
G01D02*
Y287493D01*
G01X486898D02*
Y284293D01*
G01X493098Y287493D02*
X486898D01*
G01X499112Y621721D02*
Y609721D01*
G01D02*
X505112D01*
G01X498279Y609662D02*
Y621662D01*
G01X492279Y609662D02*
X498279D01*
G01X492279Y621662D02*
Y609662D01*
G01X505112Y621721D02*
X499112D01*
G01X498279Y621662D02*
X492279D01*
G01X486251Y629478D02*
Y641478D01*
G01X490414Y656594D02*
Y654168D01*
G01X495553Y649294D02*
Y643094D01*
G01D02*
X498753D01*
G01D02*
Y649294D01*
G01D02*
X495553D01*
G01X486812Y643921D02*
Y655921D01*
G01X495753Y694740D02*
Y659044D01*
G01D02*
X513469D01*
G01X493609Y658964D02*
Y694660D01*
G01X513469Y694740D02*
X495753D01*
G01X488187Y699929D02*
X491287D01*
Y700849D01*
X491132Y701156D01*
X490770Y701386D01*
X490357Y701463D01*
X489944Y701386D01*
X489634Y701194D01*
X489479Y700849D01*
Y699929D01*
G01X491029Y704639D02*
X491184Y704409D01*
X491287Y704141D01*
Y703834D01*
X491132Y703489D01*
X490874Y703221D01*
X490564Y703029D01*
X490047Y702876D01*
X489582Y702838D01*
X489117Y702914D01*
X488807Y703029D01*
X488497Y703259D01*
X488290Y703528D01*
X488187Y703796D01*
Y704064D01*
X488290Y704333D01*
X488445Y704563D01*
X488652Y704754D01*
G01X488807Y706053D02*
X488445Y706283D01*
X488239Y706589D01*
X488187Y706934D01*
X488239Y707241D01*
X488497Y707548D01*
X488807Y707739D01*
X489117Y707778D01*
X489479Y707701D01*
X489737Y707433D01*
X489840Y707164D01*
Y706819D01*
G01Y707164D02*
X489995Y707394D01*
X490254Y707586D01*
X490564Y707663D01*
X490874Y707586D01*
X491132Y707394D01*
X491287Y707049D01*
X491235Y706704D01*
X491029Y706359D01*
G01X488807Y709153D02*
X488445Y709383D01*
X488239Y709689D01*
X488187Y710034D01*
X488239Y710341D01*
X488497Y710648D01*
X488807Y710839D01*
X489117Y710878D01*
X489479Y710801D01*
X489737Y710533D01*
X489840Y710264D01*
Y709919D01*
G01Y710264D02*
X489995Y710494D01*
X490254Y710686D01*
X490564Y710763D01*
X490874Y710686D01*
X491132Y710494D01*
X491287Y710149D01*
X491235Y709804D01*
X491029Y709459D01*
G01X488187Y713019D02*
X488859Y713096D01*
X489427Y713211D01*
X489944Y713364D01*
X490512Y713556D01*
X491287Y713863D01*
Y712329D01*
G01X487905Y964096D02*
G03X497748Y973938I0J9843D01*
G01X488871Y964888D02*
Y971088D01*
X485671D01*
Y964888D01*
X488871D01*
G01X497748Y1064490D02*
Y973938D01*
G01X495135Y979866D02*
X488935D01*
Y976666D01*
X495135D01*
Y979866D01*
G01X496759Y983366D02*
X490559D01*
Y980166D01*
X496759D01*
Y983366D01*
G01Y995866D02*
X490559D01*
Y992666D01*
X496759D01*
Y995866D01*
G01Y1002366D02*
X490559D01*
Y999166D01*
X496759D01*
Y1002366D01*
G01Y989366D02*
X490559D01*
Y986166D01*
X496759D01*
Y989366D01*
G01Y1017074D02*
X490559D01*
Y1013874D01*
X496759D01*
Y1017074D01*
G01Y1008866D02*
X490559D01*
Y1005666D01*
X496759D01*
Y1008866D01*
G01X492759Y1029345D02*
X486559D01*
Y1026145D01*
X492759D01*
Y1029345D01*
G01X496759Y1024160D02*
X490559D01*
Y1020960D01*
X496759D01*
Y1024160D01*
G01X494208Y1032845D02*
X488008D01*
Y1029645D01*
X494208D01*
Y1032845D01*
G01X496759Y1020617D02*
X490559D01*
Y1017417D01*
X496759D01*
Y1020617D01*
G01X492759Y1036345D02*
X486559D01*
Y1033145D01*
X492759D01*
Y1036345D01*
G01X495759Y1042366D02*
X489559D01*
Y1039166D01*
X495759D01*
Y1042366D01*
G01X496259Y1054745D02*
X490059D01*
Y1051545D01*
X496259D01*
Y1054745D01*
G01X494135Y1061973D02*
X491035Y1056603D01*
X493807Y1055003D01*
X496907Y1060373D01*
X494135Y1061973D01*
G01X490759Y1058366D02*
X484559D01*
Y1055166D01*
X490759D01*
Y1058366D01*
G01X485771Y1058688D02*
X491971D01*
Y1061888D01*
X485771D01*
Y1058688D01*
G01X496259Y1048866D02*
X490059D01*
Y1045666D01*
X496259D01*
Y1048866D01*
G01X497748Y1064490D02*
G03X487905Y1074332I-9843J-1D01*
G01X486471Y1073388D02*
Y1067188D01*
X489671D01*
Y1073388D01*
X486471D01*
G01X495513Y1490462D02*
X493087D01*
G01X526011Y1508910D02*
X490271D01*
Y1491980D01*
X526011D01*
Y1508910D01*
G01X485424Y1534538D02*
Y1540738D01*
G01X490148Y1534538D02*
Y1540738D01*
G01X486948Y1534538D02*
X490148D01*
G01X486948Y1540738D02*
Y1534538D01*
G01X491673Y1540738D02*
Y1534538D01*
X494873D01*
Y1540738D01*
X491673D01*
G01X490148D02*
X486948D01*
G01X496711Y1668212D02*
X493611D01*
X494231Y1668672D01*
G01X496711D02*
Y1667752D01*
G01X491958Y1673177D02*
X488858D01*
X491958Y1671413D01*
X488858D01*
G01X491958Y1678016D02*
X488858D01*
X491441Y1677019D01*
X488858Y1676022D01*
X491958D01*
G01X488858Y1682510D02*
X491958D01*
Y1680976D01*
G01Y1687311D02*
X488858D01*
G01Y1685855D02*
X490770Y1687311D01*
G01X491958Y1685625D02*
X489891Y1686660D01*
G01X491338Y1691959D02*
X491648Y1691767D01*
X491855Y1691537D01*
X491958Y1691269D01*
X491855Y1690962D01*
X491648Y1690732D01*
X491338Y1690502D01*
X490925Y1690425D01*
X488858D01*
G01Y1696377D02*
Y1695457D01*
G01Y1695917D02*
X491958D01*
G01Y1696377D02*
Y1695457D01*
G01X491952Y1701017D02*
X488852D01*
G01Y1699407D02*
X491952D01*
G01X490402D02*
Y1701017D01*
G01X490302Y1704782D02*
Y1704015D01*
X491232D01*
X491542Y1704245D01*
X491749Y1704514D01*
X491852Y1704897D01*
X491749Y1705280D01*
X491542Y1705549D01*
X491232Y1705779D01*
X490870Y1705932D01*
X490457Y1706009D01*
X490095D01*
X489785Y1705932D01*
X489424Y1705779D01*
X489114Y1705549D01*
X488907Y1705319D01*
X488752Y1705012D01*
Y1704744D01*
X488855Y1704437D01*
X489062Y1704207D01*
G01X491958Y1710818D02*
X488858D01*
Y1709362D01*
G01X490356Y1709898D02*
Y1710818D01*
G01X491958Y1714047D02*
Y1715581D01*
X488858D01*
Y1714047D01*
G01X490356Y1714661D02*
Y1715581D01*
G01X491958Y1720382D02*
X488858D01*
Y1719616D01*
X489013Y1719309D01*
X489220Y1719079D01*
X489530Y1718887D01*
X489891Y1718734D01*
X490408Y1718696D01*
X490925Y1718734D01*
X491286Y1718887D01*
X491596Y1719079D01*
X491803Y1719309D01*
X491958Y1719616D01*
Y1720382D01*
G01X489116Y1723420D02*
X488961Y1723650D01*
X488858Y1723918D01*
Y1724225D01*
X489013Y1724570D01*
X489271Y1724838D01*
X489581Y1725030D01*
X490098Y1725183D01*
X490563Y1725221D01*
X491028Y1725145D01*
X491338Y1725030D01*
X491648Y1724800D01*
X491855Y1724531D01*
X491958Y1724263D01*
Y1723995D01*
X491855Y1723726D01*
X491700Y1723496D01*
X491493Y1723305D01*
G01X490305Y1728681D02*
X490150Y1728528D01*
X489891Y1728413D01*
X489530Y1728336D01*
X489220Y1728413D01*
X489013Y1728566D01*
X488858Y1728835D01*
Y1729870D01*
X491958D01*
Y1728605D01*
X491751Y1728336D01*
X491441Y1728183D01*
X491080Y1728106D01*
X490718Y1728183D01*
X490408Y1728413D01*
X490305Y1728681D01*
Y1729870D01*
G01X491752Y1735170D02*
X488652Y1734212D01*
X491752Y1733254D01*
G01X490667Y1733599D02*
Y1734825D01*
G01X512176Y130098D02*
X505976D01*
G01D02*
Y126898D01*
G01D02*
X512176D01*
G01D02*
Y130098D01*
G01X505976Y138098D02*
Y134898D01*
G01D02*
X512176D01*
G01D02*
Y138098D01*
G01Y134098D02*
X505976D01*
G01D02*
Y130898D01*
G01D02*
X512176D01*
G01D02*
Y134098D01*
G01X501176Y126298D02*
Y132498D01*
G01X505176Y126298D02*
Y132498D01*
G01D02*
X501976D01*
G01D02*
Y126298D01*
G01D02*
X505176D01*
G01X516176Y133098D02*
X512976D01*
G01D02*
Y126898D01*
G01D02*
X516176D01*
G01X510321Y122898D02*
X516521D01*
G01Y126098D02*
X510321D01*
G01D02*
Y122898D01*
G01X506356Y120768D02*
Y125368D01*
G01X512176Y138098D02*
X505976D01*
G01X500642Y141945D02*
Y145145D01*
G01Y145945D02*
Y149145D01*
G01X510270Y142945D02*
Y149145D01*
G01D02*
X507070D01*
G01D02*
Y142945D01*
G01D02*
X510270D01*
G01X506270D02*
Y149145D01*
G01D02*
X503070D01*
G01D02*
Y142945D01*
G01D02*
X506270D01*
G01X501252Y149945D02*
Y156145D01*
G01X500642Y136998D02*
Y140198D01*
G01X502826Y138898D02*
X509026D01*
G01D02*
Y142098D01*
G01D02*
X502826D01*
G01D02*
Y138898D01*
G01X504032Y156298D02*
X510232D01*
G01D02*
Y159498D01*
G01D02*
X504032D01*
G01D02*
Y156298D01*
G01Y152298D02*
X510232D01*
G01D02*
Y155498D01*
G01D02*
X504032D01*
G01D02*
Y152298D01*
G01X512018Y164548D02*
Y158348D01*
G01D02*
X515218D01*
G01Y164548D02*
X512018D01*
G01X506218Y162048D02*
Y168248D01*
G01X503018D02*
Y162048D01*
G01D02*
X506218D01*
G01X510218D02*
Y168248D01*
G01X507018D02*
Y162048D01*
G01D02*
X510218D01*
G01X501886Y159318D02*
Y169518D01*
G01X506218Y168248D02*
X503018D01*
G01X510218D02*
X507018D01*
G01X512798Y201143D02*
Y194943D01*
X515998D01*
Y201143D01*
X512798D01*
G01X515998Y191793D02*
Y197993D01*
X512798D01*
Y191793D01*
X515998D01*
G01X506223Y288010D02*
Y282010D01*
G01D02*
X518223D01*
G01Y288010D02*
X506223D01*
G01Y304115D02*
Y298115D01*
G01D02*
X518223D01*
G01X506223Y296060D02*
Y290060D01*
G01D02*
X518223D01*
G01Y296060D02*
X506223D01*
G01X518223Y304115D02*
X506223D01*
G01Y312170D02*
Y306170D01*
G01D02*
X518223D01*
G01Y312170D02*
X506223D01*
G01X513351Y595278D02*
X519351D01*
G01X513351Y607278D02*
Y595278D01*
G01X505112Y609721D02*
Y621721D01*
G01X519351Y607278D02*
X513351D01*
G01X506012Y621721D02*
Y609721D01*
G01D02*
X512012D01*
G01D02*
Y621721D01*
G01X514012D02*
Y609721D01*
G01D02*
X520012D01*
G01X512012Y621721D02*
X506012D01*
G01X520012D02*
X514012D01*
G01X500870Y642971D02*
Y636771D01*
G01D02*
X504070D01*
G01D02*
Y642971D01*
G01X504911Y656205D02*
Y653779D01*
G01X504070Y642971D02*
X500870D01*
G01X513469Y659044D02*
Y694740D01*
G01X509567Y699919D02*
X512667D01*
Y700839D01*
X512512Y701146D01*
X512150Y701376D01*
X511737Y701453D01*
X511324Y701376D01*
X511014Y701184D01*
X510859Y700839D01*
Y699919D01*
G01X512409Y704629D02*
X512564Y704399D01*
X512667Y704131D01*
Y703824D01*
X512512Y703479D01*
X512254Y703211D01*
X511944Y703019D01*
X511427Y702866D01*
X510962Y702828D01*
X510497Y702904D01*
X510187Y703019D01*
X509877Y703249D01*
X509670Y703518D01*
X509567Y703786D01*
Y704054D01*
X509670Y704323D01*
X509825Y704553D01*
X510032Y704744D01*
G01X510187Y706043D02*
X509825Y706273D01*
X509619Y706579D01*
X509567Y706924D01*
X509619Y707231D01*
X509877Y707538D01*
X510187Y707729D01*
X510497Y707768D01*
X510859Y707691D01*
X511117Y707423D01*
X511220Y707154D01*
Y706809D01*
G01Y707154D02*
X511375Y707384D01*
X511634Y707576D01*
X511944Y707653D01*
X512254Y707576D01*
X512512Y707384D01*
X512667Y707039D01*
X512615Y706694D01*
X512409Y706349D01*
G01X509567Y710446D02*
X512667D01*
X510445Y709028D01*
Y710944D01*
G01X512667Y713086D02*
X512564Y712779D01*
X512305Y712549D01*
X511995Y712396D01*
X511582Y712281D01*
X511117Y712243D01*
X510652Y712281D01*
X510239Y712396D01*
X509929Y712549D01*
X509670Y712779D01*
X509567Y713086D01*
X509670Y713393D01*
X509929Y713623D01*
X510239Y713776D01*
X510652Y713891D01*
X511117Y713929D01*
X511582Y713891D01*
X511995Y713776D01*
X512305Y713623D01*
X512564Y713393D01*
X512667Y713086D01*
G01X505934Y700908D02*
X503694D01*
G01X504907Y702533D02*
Y699283D01*
G01X507400Y857797D02*
X521074D01*
G01X514878Y1489564D02*
X515108Y1489719D01*
X515376Y1489822D01*
X515683D01*
X516028Y1489667D01*
X516296Y1489409D01*
X516488Y1489099D01*
X516641Y1488582D01*
X516679Y1488117D01*
X516603Y1487652D01*
X516488Y1487342D01*
X516258Y1487032D01*
X515989Y1486825D01*
X515721Y1486722D01*
X515453D01*
X515184Y1486825D01*
X514954Y1486980D01*
X514763Y1487187D01*
G01X512698Y1486722D02*
X512621Y1487394D01*
X512506Y1487962D01*
X512353Y1488479D01*
X512161Y1489047D01*
X511854Y1489822D01*
X513388D01*
G01X509521D02*
X509828Y1489719D01*
X510058Y1489460D01*
X510211Y1489150D01*
X510326Y1488737D01*
X510364Y1488272D01*
X510326Y1487807D01*
X510211Y1487394D01*
X510058Y1487084D01*
X509828Y1486825D01*
X509521Y1486722D01*
X509214Y1486825D01*
X508984Y1487084D01*
X508831Y1487394D01*
X508716Y1487807D01*
X508678Y1488272D01*
X508716Y1488737D01*
X508831Y1489150D01*
X508984Y1489460D01*
X509214Y1489719D01*
X509521Y1489822D01*
G01X507264Y1487342D02*
X507034Y1486980D01*
X506728Y1486774D01*
X506383Y1486722D01*
X506076Y1486774D01*
X505769Y1487032D01*
X505578Y1487342D01*
X505539Y1487652D01*
X505616Y1488014D01*
X505884Y1488272D01*
X506153Y1488375D01*
X506498D01*
G01X506153D02*
X505923Y1488530D01*
X505731Y1488789D01*
X505654Y1489099D01*
X505731Y1489409D01*
X505923Y1489667D01*
X506268Y1489822D01*
X506613Y1489770D01*
X506958Y1489564D01*
G01X503321Y1489822D02*
X503628Y1489719D01*
X503858Y1489460D01*
X504011Y1489150D01*
X504126Y1488737D01*
X504164Y1488272D01*
X504126Y1487807D01*
X504011Y1487394D01*
X503858Y1487084D01*
X503628Y1486825D01*
X503321Y1486722D01*
X503014Y1486825D01*
X502784Y1487084D01*
X502631Y1487394D01*
X502516Y1487807D01*
X502478Y1488272D01*
X502516Y1488737D01*
X502631Y1489150D01*
X502784Y1489460D01*
X503014Y1489719D01*
X503321Y1489822D01*
G01X504321Y1534538D02*
Y1540738D01*
G01X501121Y1534538D02*
X504321D01*
G01X501121Y1540738D02*
Y1534538D01*
G01X509046D02*
Y1540738D01*
G01X505846Y1534538D02*
X509046D01*
G01X505846Y1540738D02*
Y1534538D01*
G01X510570Y1540738D02*
Y1534538D01*
X513770D01*
Y1540738D01*
X510570D01*
G01X504321D02*
X501121D01*
G01X509046D02*
X505846D01*
G01X511839Y1669055D02*
X512201Y1668825D01*
X512407Y1668519D01*
X512459Y1668174D01*
X512407Y1667867D01*
X512149Y1667560D01*
X511839Y1667369D01*
X511529Y1667330D01*
X511167Y1667407D01*
X510909Y1667675D01*
X510806Y1667944D01*
Y1668289D01*
G01Y1667944D02*
X510651Y1667714D01*
X510392Y1667522D01*
X510082Y1667445D01*
X509772Y1667522D01*
X509514Y1667714D01*
X509359Y1668059D01*
X509411Y1668404D01*
X509617Y1668749D01*
G01X502002Y1668940D02*
X501692Y1668710D01*
X501537Y1668442D01*
X501485Y1668135D01*
X501588Y1667752D01*
X501847Y1667484D01*
X502157Y1667407D01*
X502467Y1667445D01*
X502725Y1667599D01*
X503242Y1668365D01*
X503603Y1668710D01*
X504120Y1668940D01*
X504585Y1669017D01*
Y1667407D01*
G01X520691Y120607D02*
Y126807D01*
G01X517491D02*
Y120607D01*
G01D02*
X520691D01*
G01X516176Y126898D02*
Y133098D01*
G01X516521Y122898D02*
Y126098D01*
G01X525491Y127607D02*
X531691D01*
G01Y130807D02*
X525491D01*
G01D02*
Y127607D01*
G01X520691Y126807D02*
X517491D01*
G01X520691Y127607D02*
Y133807D01*
G01D02*
X517491D01*
G01D02*
Y127607D01*
G01D02*
X520691D01*
G01X524691D02*
Y133807D01*
G01D02*
X521491D01*
G01D02*
Y127607D01*
G01D02*
X524691D01*
G01X525491Y131607D02*
X531691D01*
G01Y134807D02*
X525491D01*
G01D02*
Y131607D01*
G01X515218Y158348D02*
Y164548D01*
G01X516018D02*
Y158348D01*
G01D02*
X519218D01*
G01D02*
Y164548D01*
G01D02*
X516018D01*
G01X524018D02*
Y158348D01*
G01D02*
X527218D01*
G01D02*
Y164548D01*
G01D02*
X524018D01*
G01X520018D02*
Y158348D01*
G01D02*
X523218D01*
G01D02*
Y164548D01*
G01D02*
X520018D01*
G01X533967Y163519D02*
X527767D01*
G01D02*
Y160319D01*
G01D02*
X533967D01*
G01Y159519D02*
X527767D01*
G01D02*
Y156319D01*
G01D02*
X533967D01*
G01X527767Y168537D02*
Y165337D01*
G01D02*
X533967D01*
G01Y168537D02*
X527767D01*
G01X518223Y282010D02*
Y288010D01*
G01Y298115D02*
Y304115D01*
G01Y290060D02*
Y296060D01*
G01Y306170D02*
Y312170D01*
G01X519351Y595278D02*
Y607278D01*
G01X528853Y615194D02*
Y608994D01*
G01D02*
X532053D01*
G01X520012Y609721D02*
Y621721D01*
G01X532053Y615194D02*
X528853D01*
G01X514931Y644358D02*
X520931D01*
G01D02*
Y656358D01*
G01D02*
X514931D01*
G01D02*
Y644358D01*
G01X521931D02*
X527931D01*
G01D02*
Y656358D01*
G01D02*
X521931D01*
G01D02*
Y644358D01*
G01X528951Y644178D02*
X534951D01*
G01Y656178D02*
X528951D01*
G01D02*
Y644178D01*
G01X519675Y836282D02*
Y842482D01*
G01X516475Y836282D02*
X519675D01*
G01X516475Y842482D02*
Y836282D01*
G01X519675Y842482D02*
X516475D01*
G01X530822Y849324D02*
G03X521074Y857797I-9747J-1370D01*
G01Y1180631D02*
G03X530822Y1189104I1J9843D01*
G01X527161Y1491979D02*
X525652Y1491983D01*
G01X527211Y1508912D02*
X527205Y1491929D01*
G01X526611Y1508912D02*
X526615Y1491937D01*
G01X526011Y1508912D02*
X526014Y1491972D01*
G01X530836Y1500897D02*
X528596D01*
G01X529809Y1502522D02*
Y1499272D01*
G01X527211Y1508912D02*
X526011D01*
G01X515295Y1540738D02*
Y1534538D01*
X518495D01*
Y1540738D01*
X515295D01*
G01X520019D02*
Y1534538D01*
X523219D01*
Y1540738D01*
X520019D01*
G01X525350D02*
Y1534538D01*
X528550D01*
Y1540738D01*
X525350D01*
G01X527742Y1669055D02*
X528000Y1668825D01*
X528155Y1668557D01*
X528207Y1668212D01*
X528104Y1667867D01*
X527897Y1667599D01*
X527535Y1667407D01*
X527122Y1667369D01*
X526709Y1667445D01*
X526450Y1667637D01*
X526244Y1667905D01*
X526192Y1668174D01*
X526244Y1668442D01*
X526450Y1668787D01*
X525107Y1668672D01*
Y1667637D01*
G01X520333Y1667752D02*
X517233D01*
X519455Y1669170D01*
Y1667254D01*
G01X540720Y32462D02*
Y38662D01*
G01D02*
X537520D01*
G01D02*
Y32462D01*
G01D02*
X540720D01*
G01X536717Y32435D02*
Y38635D01*
G01D02*
X533517D01*
G01D02*
Y32435D01*
G01D02*
X536717D01*
G01X544323Y38676D02*
X541123D01*
G01D02*
Y32476D01*
G01D02*
X544323D01*
G01X538691Y134807D02*
X532491D01*
G01D02*
Y131607D01*
G01D02*
X538691D01*
G01D02*
Y134807D01*
G01X532491Y138807D02*
Y135607D01*
G01D02*
X538691D01*
G01D02*
Y138807D01*
G01X536476Y122389D02*
Y128589D01*
G01D02*
X533276D01*
G01D02*
Y122389D01*
G01D02*
X536476D01*
G01X531691Y127607D02*
Y130807D01*
G01Y131607D02*
Y134807D01*
G01X540476Y122389D02*
Y128589D01*
G01D02*
X537276D01*
G01D02*
Y122389D01*
G01D02*
X540476D01*
G01X546049Y131617D02*
X541449D01*
G01D02*
Y121417D01*
G01D02*
X546049D01*
G01X532491Y150807D02*
Y147607D01*
G01D02*
X538691D01*
G01D02*
Y150807D01*
G01X542780Y142893D02*
X548980D01*
G01Y146093D02*
X542780D01*
G01D02*
Y142893D01*
G01Y146893D02*
X548980D01*
G01Y150093D02*
X542780D01*
G01D02*
Y146893D01*
G01X538691Y138807D02*
X532491D01*
G01X538691Y142807D02*
X532491D01*
G01D02*
Y139607D01*
G01D02*
X538691D01*
G01D02*
Y142807D01*
G01Y146807D02*
X532491D01*
G01D02*
Y143607D01*
G01D02*
X538691D01*
G01D02*
Y146807D01*
G01X546280Y142093D02*
X543080D01*
G01D02*
Y135893D01*
G01D02*
X546280D01*
G01X538691Y150807D02*
X532491D01*
G01X538691Y154807D02*
X532491D01*
G01D02*
Y151607D01*
G01D02*
X538691D01*
G01D02*
Y154807D01*
G01X542780Y158893D02*
X548980D01*
G01Y162093D02*
X542780D01*
G01D02*
Y158893D01*
G01Y162893D02*
X548980D01*
G01X542780Y166093D02*
Y162893D01*
G01Y154893D02*
X548980D01*
G01Y158093D02*
X542780D01*
G01D02*
Y154893D01*
G01Y150893D02*
X548980D01*
G01Y154093D02*
X542780D01*
G01D02*
Y150893D01*
G01X533967Y160319D02*
Y163519D01*
G01Y156319D02*
Y159519D01*
G01Y165337D02*
Y168537D01*
G01X534942Y166628D02*
Y156428D01*
G01D02*
X539542D01*
G01D02*
Y166628D01*
G01X548980Y166093D02*
X542780D01*
G01X539542Y166628D02*
X534942D01*
G01X547751Y173965D02*
X534871D01*
G01Y167565D02*
X547751D01*
G01X534871Y173965D02*
Y167565D01*
G01X537368Y255235D02*
Y249035D01*
G01D02*
X540568D01*
G01D02*
Y255235D01*
G01X541426Y255213D02*
Y249013D01*
G01D02*
X544626D01*
G01X540568Y255235D02*
X537368D01*
G01X544626Y255213D02*
X541426D01*
G01X534016Y276005D02*
X534284Y275953D01*
X534591Y275798D01*
X534783Y275540D01*
X534859Y275178D01*
X534783Y274817D01*
X534553Y274507D01*
X534208Y274352D01*
X533824D01*
X533594Y274248D01*
X533403Y273990D01*
X533326Y273628D01*
X533441Y273267D01*
X533709Y273008D01*
X534016Y272905D01*
X534323Y273008D01*
X534591Y273267D01*
X534706Y273628D01*
X534629Y273990D01*
X534438Y274248D01*
X534208Y274352D01*
X533824D01*
X533479Y274507D01*
X533249Y274817D01*
X533173Y275178D01*
X533249Y275540D01*
X533441Y275798D01*
X533748Y275953D01*
X534016Y276005D01*
G01X534170Y608871D02*
Y602671D01*
G01D02*
X537370D01*
G01D02*
Y608871D01*
G01D02*
X534170D01*
G01X532053Y608994D02*
Y615194D01*
G01X543051Y652538D02*
Y646338D01*
G01D02*
X546251D01*
G01Y652538D02*
X543051D01*
G01X535851Y644178D02*
X541851D01*
G01D02*
Y656178D01*
G01D02*
X535851D01*
G01D02*
Y644178D01*
G01X534951D02*
Y656178D01*
G01X530822Y849324D02*
X535078Y819025D01*
G01D02*
G03X544826Y810553I9747J1371D01*
G01X530822Y1189104D02*
X535078Y1219403D01*
G01X544826Y1227875D02*
G03X535078Y1219403I-1J-9843D01*
G01X538497Y1517953D02*
Y1529953D01*
G01X532497Y1517953D02*
X538497D01*
G01X532497Y1529953D02*
Y1517953D01*
G01X539305D02*
X545305D01*
G01X539305Y1529953D02*
Y1517953D01*
G01X534317Y1517277D02*
Y1510877D01*
G01D02*
X547197D01*
G01Y1517277D02*
X534317D01*
G01X538497Y1529953D02*
X532497D01*
G01X545305D02*
X539305D01*
G01X533119Y1532721D02*
X545119D01*
G01X533119Y1538721D02*
Y1532721D01*
G01X545119Y1538721D02*
X533119D01*
G01Y1539575D02*
X545119D01*
G01X533119Y1545575D02*
Y1539575D01*
G01X545119Y1545575D02*
X533119D01*
G01X543955Y1668289D02*
X543283Y1668212D01*
X542715Y1668097D01*
X542198Y1667944D01*
X541630Y1667752D01*
X540855Y1667445D01*
Y1668979D01*
G01X534789Y1668940D02*
X534428Y1668672D01*
X534221Y1668442D01*
X534118Y1668135D01*
X534221Y1667867D01*
X534428Y1667675D01*
X534738Y1667522D01*
X535099Y1667484D01*
X535409Y1667522D01*
X535719Y1667675D01*
X535978Y1667905D01*
X536081Y1668174D01*
X535978Y1668480D01*
X535668Y1668749D01*
X535203Y1668902D01*
X534686Y1668940D01*
X534014Y1668864D01*
X533653Y1668749D01*
X533291Y1668557D01*
X533033Y1668289D01*
X532981Y1668020D01*
X533084Y1667752D01*
X533343Y1667560D01*
G01X555220Y32662D02*
Y38862D01*
G01D02*
X552020D01*
G01D02*
Y32662D01*
G01D02*
X555220D01*
G01X551519Y32562D02*
Y38762D01*
G01D02*
X548319D01*
G01D02*
Y32562D01*
G01D02*
X551519D01*
G01X544750Y38685D02*
Y32485D01*
G01D02*
X547950D01*
G01D02*
Y38685D01*
G01D02*
X544750D01*
G01X544323Y32476D02*
Y38676D01*
G01X558600Y57288D02*
Y51088D01*
G01D02*
X561800D01*
G01Y57288D02*
X558600D01*
G01X550210Y50135D02*
Y56335D01*
X547010D01*
Y50135D01*
X550210D01*
G01X546780Y135093D02*
Y128893D01*
G01D02*
X549980D01*
G01D02*
Y135093D01*
G01D02*
X546780D01*
G01X546049Y121417D02*
Y131617D01*
G01X563660Y134993D02*
X550780D01*
G01Y128593D02*
X563660D01*
G01X550780Y134993D02*
Y128593D01*
G01X548980Y142893D02*
Y146093D01*
G01Y146893D02*
Y150093D01*
G01X550280Y135893D02*
Y142093D01*
G01D02*
X547080D01*
G01D02*
Y135893D01*
G01D02*
X550280D01*
G01X546280D02*
Y142093D01*
G01X555680Y135893D02*
Y146093D01*
G01D02*
X551080D01*
G01D02*
Y135893D01*
G01D02*
X555680D01*
G01X548980Y158893D02*
Y162093D01*
G01Y162893D02*
Y166093D01*
G01Y154893D02*
Y158093D01*
G01Y150893D02*
Y154093D01*
G01X547751Y173965D02*
Y167565D01*
G01X557368Y255235D02*
Y249035D01*
G01D02*
X560568D01*
G01X544626Y249013D02*
Y255213D01*
G01X560568Y255235D02*
X557368D01*
G01X546251Y646338D02*
Y652538D01*
G01X544826Y810553D02*
X614677D01*
G01X544826Y1227875D02*
X614677D01*
G01X546244Y1519522D02*
X549444D01*
G01X546244Y1525722D02*
Y1519522D01*
G01X549444D02*
Y1525722D01*
G01X550244Y1519522D02*
X553444D01*
G01X550244Y1525722D02*
Y1519522D01*
G01X553444D02*
Y1525722D01*
G01X545305Y1517953D02*
Y1529953D01*
G01X547197Y1517277D02*
Y1510877D01*
G01X549444Y1525722D02*
X546244D01*
G01X553444D02*
X550244D01*
G01X546459Y1540146D02*
Y1528146D01*
G01X552459D02*
Y1540146D01*
G01X546459Y1528146D02*
X552459D01*
G01X553241Y1534746D02*
X565241D01*
G01X553241Y1540746D02*
Y1534746D01*
G01X565215Y1533892D02*
X553215D01*
G01Y1527892D02*
X565215D01*
G01X553215Y1533892D02*
Y1527892D01*
G01X545119Y1532721D02*
Y1538721D01*
G01X544177Y1550499D02*
Y1545899D01*
G01X554377Y1550499D02*
X544177D01*
G01X554377Y1545899D02*
Y1550499D01*
G01X544177Y1545899D02*
X554377D01*
G01X549977Y1550499D02*
Y1545899D01*
G01X560177Y1550499D02*
X549977D01*
G01Y1545899D02*
X560177D01*
G01X552459Y1540146D02*
X546459D01*
G01X565241Y1540746D02*
X553241D01*
G01X545119Y1539575D02*
Y1545575D01*
G01X545276Y1646023D02*
Y1781456D01*
G01X614400Y1646023D02*
X545276D01*
G01X558888Y1673177D02*
X555788D01*
X558888Y1671413D01*
X555788D01*
G01X551829Y1668212D02*
X551777Y1667944D01*
X551622Y1667637D01*
X551364Y1667445D01*
X551002Y1667369D01*
X550641Y1667445D01*
X550331Y1667675D01*
X550176Y1668020D01*
Y1668404D01*
X550072Y1668634D01*
X549814Y1668825D01*
X549452Y1668902D01*
X549091Y1668787D01*
X548832Y1668519D01*
X548729Y1668212D01*
X548832Y1667905D01*
X549091Y1667637D01*
X549452Y1667522D01*
X549814Y1667599D01*
X550072Y1667790D01*
X550176Y1668020D01*
Y1668404D01*
X550331Y1668749D01*
X550641Y1668979D01*
X551002Y1669055D01*
X551364Y1668979D01*
X551622Y1668787D01*
X551777Y1668480D01*
X551829Y1668212D01*
G01X558888Y1678016D02*
X555788D01*
X558371Y1677019D01*
X555788Y1676022D01*
X558888D01*
G01X555788Y1682510D02*
X558888D01*
Y1680976D01*
G01Y1687311D02*
X555788D01*
G01Y1685855D02*
X557700Y1687311D01*
G01X558888Y1685625D02*
X556821Y1686660D01*
G01X558268Y1691959D02*
X558578Y1691767D01*
X558785Y1691537D01*
X558888Y1691269D01*
X558785Y1690962D01*
X558578Y1690732D01*
X558268Y1690502D01*
X557855Y1690425D01*
X555788D01*
G01Y1696377D02*
Y1695457D01*
G01Y1695917D02*
X558888D01*
G01Y1696377D02*
Y1695457D01*
G01X558882Y1701017D02*
X555782D01*
G01Y1699407D02*
X558882D01*
G01X557332D02*
Y1701017D01*
G01X557232Y1704782D02*
Y1704015D01*
X558162D01*
X558472Y1704245D01*
X558679Y1704514D01*
X558782Y1704897D01*
X558679Y1705280D01*
X558472Y1705549D01*
X558162Y1705779D01*
X557800Y1705932D01*
X557387Y1706009D01*
X557025D01*
X556715Y1705932D01*
X556354Y1705779D01*
X556044Y1705549D01*
X555837Y1705319D01*
X555682Y1705012D01*
Y1704744D01*
X555785Y1704437D01*
X555992Y1704207D01*
G01X558888Y1710818D02*
X555788D01*
Y1709362D01*
G01X557286Y1709898D02*
Y1710818D01*
G01X558888Y1714047D02*
Y1715581D01*
X555788D01*
Y1714047D01*
G01X557286Y1714661D02*
Y1715581D01*
G01X558888Y1720382D02*
X555788D01*
Y1719616D01*
X555943Y1719309D01*
X556150Y1719079D01*
X556460Y1718887D01*
X556821Y1718734D01*
X557338Y1718696D01*
X557855Y1718734D01*
X558216Y1718887D01*
X558526Y1719079D01*
X558733Y1719309D01*
X558888Y1719616D01*
Y1720382D01*
G01X556046Y1723420D02*
X555891Y1723650D01*
X555788Y1723918D01*
Y1724225D01*
X555943Y1724570D01*
X556201Y1724838D01*
X556511Y1725030D01*
X557028Y1725183D01*
X557493Y1725221D01*
X557958Y1725145D01*
X558268Y1725030D01*
X558578Y1724800D01*
X558785Y1724531D01*
X558888Y1724263D01*
Y1723995D01*
X558785Y1723726D01*
X558630Y1723496D01*
X558423Y1723305D01*
G01X557235Y1728681D02*
X557080Y1728528D01*
X556821Y1728413D01*
X556460Y1728336D01*
X556150Y1728413D01*
X555943Y1728566D01*
X555788Y1728835D01*
Y1729870D01*
X558888D01*
Y1728605D01*
X558681Y1728336D01*
X558371Y1728183D01*
X558010Y1728106D01*
X557648Y1728183D01*
X557338Y1728413D01*
X557235Y1728681D01*
Y1729870D01*
G01X558682Y1735170D02*
X555582Y1734212D01*
X558682Y1733254D01*
G01X557597Y1733599D02*
Y1734825D01*
G01X545276Y1781456D02*
X635433D01*
G01X562600Y57282D02*
Y51082D01*
G01D02*
X565800D01*
G01D02*
Y57282D01*
G01D02*
X562600D01*
G01X570600D02*
Y51082D01*
G01D02*
X573800D01*
G01Y57282D02*
X570600D01*
G01X566600Y57293D02*
Y51093D01*
G01D02*
X569800D01*
G01D02*
Y57293D01*
G01D02*
X566600D01*
G01X561800Y51088D02*
Y57288D01*
G01X565733Y71262D02*
Y65062D01*
G01D02*
X568933D01*
G01D02*
Y71262D01*
G01D02*
X565733D01*
G01X563660Y134993D02*
Y128593D01*
G01X560568Y249035D02*
Y255235D01*
G01X567673Y323593D02*
X561473D01*
G01D02*
Y320393D01*
G01D02*
X567673D01*
G01D02*
Y323593D01*
G01X573771Y804988D02*
X570571D01*
G01Y798788D02*
X573771D01*
G01X570571Y804988D02*
Y798788D01*
G01X567461Y1235675D02*
Y1232475D01*
G01X573661Y1235675D02*
X567461D01*
G01X573661Y1232475D02*
Y1235675D01*
G01X567461Y1232475D02*
X573661D01*
G01X567481Y1239765D02*
Y1236565D01*
G01D02*
X573681D01*
G01Y1239765D02*
X567481D01*
G01X568257Y1254388D02*
Y1251188D01*
G01D02*
X574457D01*
G01X567501Y1247565D02*
Y1244365D01*
G01X573701Y1247565D02*
X567501D01*
G01Y1244365D02*
X573701D01*
G01X567501Y1243705D02*
Y1240505D01*
G01X573701Y1243705D02*
X567501D01*
G01Y1240505D02*
X573701D01*
G01X560055Y1247527D02*
Y1244327D01*
G01X566255Y1247527D02*
X560055D01*
G01X566255Y1244327D02*
Y1247527D01*
G01X560055Y1244327D02*
X566255D01*
G01X574457Y1254388D02*
X568257D01*
G01X571746Y1263513D02*
Y1260313D01*
G01X577946Y1263513D02*
X571746D01*
G01Y1260313D02*
X577946D01*
G01X568621Y1266518D02*
X574821D01*
G01X568621Y1269718D02*
Y1266518D01*
G01X574821Y1269718D02*
X568621D01*
G01X565642Y1504985D02*
Y1498985D01*
X577642D01*
Y1504985D01*
X565642D01*
G01X565241Y1534746D02*
Y1540746D01*
G01X565215Y1527892D02*
Y1533892D01*
G01X576856Y1543812D02*
X573656D01*
G01Y1537612D02*
X576856D01*
G01X573656Y1543812D02*
Y1537612D01*
G01X560177Y1545899D02*
Y1550499D01*
G01X568503Y1666210D02*
Y1646023D01*
G01X568932Y1668940D02*
X568622Y1668710D01*
X568467Y1668442D01*
X568415Y1668135D01*
X568518Y1667752D01*
X568777Y1667484D01*
X569087Y1667407D01*
X569397Y1667445D01*
X569655Y1667599D01*
X570172Y1668365D01*
X570533Y1668710D01*
X571050Y1668940D01*
X571515Y1669017D01*
Y1667407D01*
G01X563641Y1668212D02*
X560541D01*
X561161Y1668672D01*
G01X563641D02*
Y1667752D01*
G01X568503Y1781456D02*
Y1737460D01*
G01X574600Y57322D02*
Y51122D01*
G01D02*
X577800D01*
G01D02*
Y57322D01*
G01D02*
X574600D01*
G01X573800Y51082D02*
Y57282D01*
G01X588497D02*
Y51082D01*
G01D02*
X591697D01*
G01Y57282D02*
X588497D01*
G01X591044Y72761D02*
X587844D01*
G01D02*
Y66561D01*
G01D02*
X591044D01*
G01X587368Y255235D02*
Y249035D01*
G01D02*
X590568D01*
G01Y255235D02*
X587368D01*
G01X578171Y798788D02*
X581371D01*
G01X578171Y804988D02*
Y798788D01*
G01X581371Y804988D02*
X578171D01*
G01X581371Y798788D02*
Y804988D01*
G01X582071Y798888D02*
X585271D01*
G01X582071Y805088D02*
Y798888D01*
G01X585271Y805088D02*
X582071D01*
G01X585271Y798888D02*
Y805088D01*
G01X589171D02*
X585971D01*
G01Y798888D02*
X589171D01*
G01X585971Y805088D02*
Y798888D01*
G01X573771Y798788D02*
Y804988D01*
G01X577271D02*
X574071D01*
G01X577271Y798788D02*
Y804988D01*
G01X574071Y798788D02*
X577271D01*
G01X574071Y804988D02*
Y798788D01*
G01X586259Y1236475D02*
Y1239675D01*
G01X580059Y1236475D02*
X586259D01*
G01X580059Y1239675D02*
Y1236475D01*
G01X587059Y1239675D02*
Y1236475D01*
G01D02*
X593259D01*
G01X580059Y1235675D02*
Y1232475D01*
G01X586259Y1235675D02*
X580059D01*
G01X586259Y1232475D02*
Y1235675D01*
G01X580059Y1232475D02*
X586259D01*
G01X587059D02*
X593259D01*
G01X587059Y1235675D02*
Y1232475D01*
G01X593259Y1235675D02*
X587059D01*
G01X573681Y1236565D02*
Y1239765D01*
G01X586259Y1239675D02*
X580059D01*
G01X593259D02*
X587059D01*
G01X574457Y1251188D02*
Y1254388D01*
G01X573701Y1244365D02*
Y1247565D01*
G01Y1240505D02*
Y1243705D01*
G01X594585Y1253633D02*
X579333D01*
G01Y1241517D02*
X594585D01*
G01X579333Y1253633D02*
Y1241517D01*
G01X577946Y1260313D02*
Y1263513D01*
G01X574821Y1266518D02*
Y1269718D01*
G01X591646Y1256519D02*
Y1257914D01*
X592413Y1259619D01*
G01X590879D02*
X591646Y1257914D01*
G01X588086Y1256519D02*
Y1259619D01*
X589504Y1257397D01*
X587588D01*
G01X584212Y1489223D02*
X586452D01*
G01X585239Y1487598D02*
Y1490848D01*
G01X581047Y1491980D02*
X616787D01*
Y1508910D01*
X581047D01*
Y1491980D01*
G01X579847Y1491978D02*
X581047D01*
G01X579847D02*
X579853Y1508961D01*
G01X580447Y1491978D02*
X580443Y1508953D01*
G01X581047Y1491978D02*
X581044Y1508918D01*
G01X579897Y1508911D02*
X581406Y1508907D01*
G01X580414Y1534538D02*
Y1540738D01*
G01X577214Y1534538D02*
X580414D01*
G01X577214Y1540738D02*
Y1534538D01*
G01X586664D02*
X589864D01*
G01X586664Y1540738D02*
Y1534538D01*
G01X581939Y1540738D02*
Y1534538D01*
X585139D01*
Y1540738D01*
X581939D01*
G01X576856Y1537612D02*
Y1543812D01*
G01X580414Y1540738D02*
X577214D01*
G01X589864D02*
X586664D01*
G01X587263Y1667752D02*
X584163D01*
X586385Y1669170D01*
Y1667254D01*
G01X578769Y1669055D02*
X579131Y1668825D01*
X579337Y1668519D01*
X579389Y1668174D01*
X579337Y1667867D01*
X579079Y1667560D01*
X578769Y1667369D01*
X578459Y1667330D01*
X578097Y1667407D01*
X577839Y1667675D01*
X577736Y1667944D01*
Y1668289D01*
G01Y1667944D02*
X577581Y1667714D01*
X577322Y1667522D01*
X577012Y1667445D01*
X576702Y1667522D01*
X576444Y1667714D01*
X576289Y1668059D01*
X576341Y1668404D01*
X576547Y1668749D01*
G01X600750Y57282D02*
Y51082D01*
G01D02*
X603950D01*
G01Y57282D02*
X600750D01*
G01X592805D02*
Y51082D01*
G01D02*
X596005D01*
G01D02*
Y57282D01*
G01D02*
X592805D01*
G01X591697Y51082D02*
Y57282D01*
G01X596044Y66561D02*
Y72761D01*
G01D02*
X592844D01*
G01D02*
Y66561D01*
G01D02*
X596044D01*
G01X591044D02*
Y72761D01*
G01X603934Y69443D02*
X600734D01*
G01D02*
Y63243D01*
G01D02*
X603934D01*
G01X590568Y249035D02*
Y255235D01*
G01X593223Y297010D02*
Y291010D01*
G01D02*
X605223D01*
G01Y297010D02*
X593223D01*
G01Y305060D02*
Y299060D01*
G01D02*
X605223D01*
G01X593223Y313115D02*
Y307115D01*
G01D02*
X605223D01*
G01Y313115D02*
X593223D01*
G01X605223Y305060D02*
X593223D01*
G01Y321170D02*
Y315170D01*
G01D02*
X605223D01*
G01Y321170D02*
X593223D01*
G01X605371Y787488D02*
X602171D01*
G01Y781288D02*
X605371D01*
G01X602171Y787488D02*
Y781288D01*
G01X593971Y792088D02*
X597171D01*
G01X593971Y798288D02*
Y792088D01*
G01X597171Y798288D02*
X593971D01*
G01X597171Y792088D02*
Y798288D01*
G01X597871Y792088D02*
X601071D01*
G01X597871Y798288D02*
Y792088D01*
G01X601071Y798288D02*
X597871D01*
G01X601071Y792088D02*
Y798288D01*
G01X589171Y798888D02*
Y805088D01*
G01X593171Y798288D02*
X589971D01*
G01X593171Y792088D02*
Y798288D01*
G01X589971Y792088D02*
X593171D01*
G01X589971Y798288D02*
Y792088D01*
G01X604861Y802040D02*
X601661D01*
G01Y795840D02*
X604861D01*
G01X601661Y802040D02*
Y795840D01*
G01X593259Y1236475D02*
Y1239675D01*
G01Y1232475D02*
Y1235675D01*
G01X600601Y1232975D02*
X603801D01*
G01X600601Y1239175D02*
Y1232975D01*
G01X599571Y1248588D02*
X596371D01*
G01X599571Y1242388D02*
Y1248588D01*
G01X596371Y1242388D02*
X599571D01*
G01X596371Y1248588D02*
Y1242388D01*
G01X603801Y1239175D02*
X600601D01*
G01X601059Y1243175D02*
Y1239975D01*
G01X607259Y1243175D02*
X601059D01*
G01Y1239975D02*
X607259D01*
G01X596659Y1249975D02*
Y1258175D01*
X611659D01*
Y1249975D01*
X596659D01*
G01X594585Y1241517D02*
Y1253633D01*
G01X600171Y1268173D02*
X603371D01*
G01X600171Y1274373D02*
Y1268173D01*
G01X603371D02*
Y1274373D01*
G01D02*
X600171D01*
G01X603550Y1489384D02*
X603780Y1489539D01*
X604048Y1489642D01*
X604355D01*
X604700Y1489487D01*
X604968Y1489229D01*
X605160Y1488919D01*
X605313Y1488402D01*
X605351Y1487937D01*
X605275Y1487472D01*
X605160Y1487162D01*
X604930Y1486852D01*
X604661Y1486645D01*
X604393Y1486542D01*
X604125D01*
X603856Y1486645D01*
X603626Y1486800D01*
X603435Y1487007D01*
G01X601370Y1486542D02*
X601293Y1487214D01*
X601178Y1487782D01*
X601025Y1488299D01*
X600833Y1488867D01*
X600526Y1489642D01*
X602060D01*
G01X598193D02*
X598500Y1489539D01*
X598730Y1489280D01*
X598883Y1488970D01*
X598998Y1488557D01*
X599036Y1488092D01*
X598998Y1487627D01*
X598883Y1487214D01*
X598730Y1486904D01*
X598500Y1486645D01*
X598193Y1486542D01*
X597886Y1486645D01*
X597656Y1486904D01*
X597503Y1487214D01*
X597388Y1487627D01*
X597350Y1488092D01*
X597388Y1488557D01*
X597503Y1488970D01*
X597656Y1489280D01*
X597886Y1489539D01*
X598193Y1489642D01*
G01X595821Y1489125D02*
X595591Y1489435D01*
X595323Y1489590D01*
X595016Y1489642D01*
X594633Y1489539D01*
X594365Y1489280D01*
X594288Y1488970D01*
X594326Y1488660D01*
X594480Y1488402D01*
X595246Y1487885D01*
X595591Y1487524D01*
X595821Y1487007D01*
X595898Y1486542D01*
X594288D01*
G01X592070D02*
X591993Y1487214D01*
X591878Y1487782D01*
X591725Y1488299D01*
X591533Y1488867D01*
X591226Y1489642D01*
X592760D01*
G01X600837Y1534538D02*
X604037D01*
G01X600837Y1540738D02*
Y1534538D01*
G01X594588D02*
Y1540738D01*
G01X591388Y1534538D02*
X594588D01*
G01X591388Y1540738D02*
Y1534538D01*
G01X589864D02*
Y1540738D01*
G01X596113D02*
Y1534538D01*
X599313D01*
Y1540738D01*
X596113D01*
G01X604037D02*
X600837D01*
G01X594588D02*
X591388D01*
G01X594672Y1669055D02*
X594930Y1668825D01*
X595085Y1668557D01*
X595137Y1668212D01*
X595034Y1667867D01*
X594827Y1667599D01*
X594465Y1667407D01*
X594052Y1667369D01*
X593639Y1667445D01*
X593380Y1667637D01*
X593174Y1667905D01*
X593122Y1668174D01*
X593174Y1668442D01*
X593380Y1668787D01*
X592037Y1668672D01*
Y1667637D01*
G01X601719Y1668940D02*
X601358Y1668672D01*
X601151Y1668442D01*
X601048Y1668135D01*
X601151Y1667867D01*
X601358Y1667675D01*
X601668Y1667522D01*
X602029Y1667484D01*
X602339Y1667522D01*
X602649Y1667675D01*
X602908Y1667905D01*
X603011Y1668174D01*
X602908Y1668480D01*
X602598Y1668749D01*
X602133Y1668902D01*
X601616Y1668940D01*
X600944Y1668864D01*
X600583Y1668749D01*
X600221Y1668557D01*
X599963Y1668289D01*
X599911Y1668020D01*
X600014Y1667752D01*
X600273Y1667560D01*
G01X610172Y31075D02*
Y37275D01*
X606972D01*
Y31075D01*
X610172D01*
G01X606972Y40425D02*
Y34225D01*
X610172D01*
Y40425D01*
X606972D01*
G01X613245Y57282D02*
Y51082D01*
G01D02*
X616445D01*
G01D02*
Y57282D01*
G01D02*
X613245D01*
G01X608685D02*
Y51082D01*
G01D02*
X611885D01*
G01D02*
Y57282D01*
G01D02*
X608685D01*
G01X604730D02*
Y51082D01*
G01D02*
X607930D01*
G01D02*
Y57282D01*
G01D02*
X604730D01*
G01X603950Y51082D02*
Y57282D01*
G01X617445Y54082D02*
X623645D01*
G01Y57282D02*
X617445D01*
G01D02*
Y54082D01*
G01X618415Y69443D02*
X615215D01*
G01D02*
Y63243D01*
G01D02*
X618415D01*
G01X611915D02*
Y69443D01*
G01D02*
X608715D01*
G01D02*
Y63243D01*
G01D02*
X611915D01*
G01X607863D02*
Y69443D01*
G01D02*
X604663D01*
G01D02*
Y63243D01*
G01D02*
X607863D01*
G01X603934D02*
Y69443D01*
G01X613816Y275605D02*
Y272505D01*
X613356Y273125D01*
G01Y275605D02*
X614276D01*
G01X605223Y291010D02*
Y297010D01*
G01Y299060D02*
Y305060D01*
G01Y307115D02*
Y313115D01*
G01Y315170D02*
Y321170D01*
G01X606071Y781288D02*
X609271D01*
G01X606071Y787488D02*
Y781288D01*
G01X609271Y787488D02*
X606071D01*
G01X609271Y781288D02*
Y787488D01*
G01X610071Y781288D02*
X613271D01*
G01X610071Y787488D02*
Y781288D01*
G01X613271Y787488D02*
X610071D01*
G01X613271Y781288D02*
Y787488D01*
G01X617171D02*
X613971D01*
G01X617171Y781288D02*
Y787488D01*
G01X613971Y781288D02*
X617171D01*
G01X613971Y787488D02*
Y781288D01*
G01X605371D02*
Y787488D01*
G01X604861Y795840D02*
Y802040D01*
G01X614677Y810553D02*
G03X624519Y820395I0J9842D01*
G01X603801Y1232975D02*
Y1239175D01*
G01X607801Y1232975D02*
Y1239175D01*
G01X604601Y1232975D02*
X607801D01*
G01X604601Y1239175D02*
Y1232975D01*
G01X624519Y1218033D02*
G03X614677Y1227875I-9842J0D01*
G01X613771Y1247388D02*
X610571D01*
G01X613771Y1241188D02*
Y1247388D01*
G01X610571Y1241188D02*
X613771D01*
G01X610571Y1247388D02*
Y1241188D01*
G01X607801Y1239175D02*
X604601D01*
G01X607259Y1239975D02*
Y1243175D01*
G01X617993Y1254499D02*
Y1255894D01*
X618760Y1257599D01*
G01X617226D02*
X617993Y1255894D01*
G01X615736Y1254964D02*
X615506Y1254706D01*
X615238Y1254551D01*
X614893Y1254499D01*
X614548Y1254602D01*
X614280Y1254809D01*
X614088Y1255171D01*
X614050Y1255584D01*
X614126Y1255997D01*
X614318Y1256256D01*
X614586Y1256462D01*
X614855Y1256514D01*
X615123Y1256462D01*
X615468Y1256256D01*
X615353Y1257599D01*
X614318D01*
G01X611671Y1268588D02*
Y1265388D01*
G01X617871Y1268588D02*
X611671D01*
G01X617871Y1265388D02*
Y1268588D01*
G01X611671Y1265388D02*
X617871D01*
G01Y1261388D02*
Y1264588D01*
G01X611671Y1261388D02*
X617871D01*
G01X611671Y1264588D02*
Y1261388D01*
G01X617871Y1264588D02*
X611671D01*
G01X604171Y1268173D02*
X607371D01*
G01X604171Y1274373D02*
Y1268173D01*
G01X607371D02*
Y1274373D01*
G01X617881Y1269288D02*
Y1272488D01*
G01X611681Y1269288D02*
X617881D01*
G01X611681Y1272488D02*
Y1269288D01*
G01X617881Y1272488D02*
X611681D01*
G01Y1280268D02*
Y1277068D01*
G01X617881Y1280268D02*
X611681D01*
G01X617881Y1277068D02*
Y1280268D01*
G01X611681Y1277068D02*
X617881D01*
G01Y1273198D02*
Y1276398D01*
G01X611681Y1273198D02*
X617881D01*
G01X611681Y1276398D02*
Y1273198D01*
G01X617881Y1276398D02*
X611681D01*
G01X607371Y1274373D02*
X604171D01*
G01X615116Y1380693D02*
Y1377493D01*
G01X621316Y1380693D02*
X615116D01*
G01Y1377493D02*
X621316D01*
G01X654073Y1508910D02*
X618333D01*
Y1491980D01*
X654073D01*
Y1508910D01*
G01X612095Y1490178D02*
X614521D01*
G01X604037Y1534538D02*
Y1540738D01*
G01X608761Y1534538D02*
Y1540738D01*
G01X605561Y1534538D02*
X608761D01*
G01X605561Y1540738D02*
Y1534538D01*
G01X618210D02*
Y1540738D01*
G01X615010Y1534538D02*
X618210D01*
G01X615010Y1540738D02*
Y1534538D01*
G01X613486D02*
Y1540738D01*
G01X610286Y1534538D02*
X613486D01*
G01X610286Y1540738D02*
Y1534538D01*
G01X608761Y1540738D02*
X605561D01*
G01X618210D02*
X615010D01*
G01X613486D02*
X610286D01*
G01X618759Y1668212D02*
X618707Y1667944D01*
X618552Y1667637D01*
X618294Y1667445D01*
X617932Y1667369D01*
X617571Y1667445D01*
X617261Y1667675D01*
X617106Y1668020D01*
Y1668404D01*
X617002Y1668634D01*
X616744Y1668825D01*
X616382Y1668902D01*
X616021Y1668787D01*
X615762Y1668519D01*
X615659Y1668212D01*
X615762Y1667905D01*
X616021Y1667637D01*
X616382Y1667522D01*
X616744Y1667599D01*
X617002Y1667790D01*
X617106Y1668020D01*
Y1668404D01*
X617261Y1668749D01*
X617571Y1668979D01*
X617932Y1669055D01*
X618294Y1668979D01*
X618552Y1668787D01*
X618707Y1668480D01*
X618759Y1668212D01*
G01X610885Y1668289D02*
X610213Y1668212D01*
X609645Y1668097D01*
X609128Y1667944D01*
X608560Y1667752D01*
X607785Y1667445D01*
Y1668979D01*
G01X632620Y63565D02*
Y57365D01*
G01D02*
X635820D01*
G01X623645Y54082D02*
Y57282D01*
G01X628695Y53282D02*
X622495D01*
G01X628695Y50082D02*
Y53282D01*
G01X622495Y50082D02*
X628695D01*
G01X622495Y53282D02*
Y50082D01*
G01X618415Y63243D02*
Y69443D01*
G01X635820Y63565D02*
X632620D01*
G01X635745Y71640D02*
X629545D01*
G01D02*
Y68440D01*
G01D02*
X635745D01*
G01Y67640D02*
X629545D01*
G01D02*
Y64440D01*
G01D02*
X635745D01*
G01X620682Y63573D02*
X626882D01*
G01D02*
Y66773D01*
G01D02*
X620682D01*
G01D02*
Y63573D01*
G01X620407Y67648D02*
X623607D01*
G01X620407Y73848D02*
Y67648D01*
G01X623607Y73848D02*
X620407D01*
G01X623607Y67648D02*
Y73848D01*
G01X625896Y82061D02*
Y75861D01*
G01D02*
X629096D01*
G01D02*
Y82061D01*
G01D02*
X625896D01*
G01X631200Y749500D02*
X634400D01*
G01X631200Y755700D02*
Y749500D01*
G01X634400Y755700D02*
X631200D01*
G01X627200Y749500D02*
X630400D01*
G01X627200Y755700D02*
Y749500D01*
G01X630400Y755700D02*
X627200D01*
G01X630400Y749500D02*
Y755700D01*
G01X630008Y760479D02*
Y766679D01*
X626808D01*
Y760479D01*
X630008D01*
G01Y757329D02*
Y763529D01*
X626808D01*
Y757329D01*
X630008D01*
G01X624519Y820395D02*
Y985749D01*
G01D02*
X636724Y997560D01*
G01Y1040868D02*
X624519Y1052679D01*
G01D02*
Y1218033D01*
G01X632733Y1367152D02*
Y1370352D01*
G01X626533D02*
Y1367152D01*
G01X632733Y1370352D02*
X626533D01*
G01Y1367152D02*
X632733D01*
G01X620520Y1389657D02*
Y1386457D01*
G01X626720D02*
Y1389657D01*
G01X620520Y1386457D02*
X626720D01*
G01X621316Y1377493D02*
Y1380693D01*
G01X626720Y1389657D02*
X620520D01*
G01X624505Y1490292D02*
X622079D01*
G01X645170Y1489574D02*
X645400Y1489729D01*
X645668Y1489832D01*
X645975D01*
X646320Y1489677D01*
X646588Y1489419D01*
X646780Y1489109D01*
X646933Y1488592D01*
X646971Y1488127D01*
X646895Y1487662D01*
X646780Y1487352D01*
X646550Y1487042D01*
X646281Y1486835D01*
X646013Y1486732D01*
X645745D01*
X645476Y1486835D01*
X645246Y1486990D01*
X645055Y1487197D01*
G01X642990Y1486732D02*
X642913Y1487404D01*
X642798Y1487972D01*
X642645Y1488489D01*
X642453Y1489057D01*
X642146Y1489832D01*
X643680D01*
G01X639813D02*
X640120Y1489729D01*
X640350Y1489470D01*
X640503Y1489160D01*
X640618Y1488747D01*
X640656Y1488282D01*
X640618Y1487817D01*
X640503Y1487404D01*
X640350Y1487094D01*
X640120Y1486835D01*
X639813Y1486732D01*
X639506Y1486835D01*
X639276Y1487094D01*
X639123Y1487404D01*
X639008Y1487817D01*
X638970Y1488282D01*
X639008Y1488747D01*
X639123Y1489160D01*
X639276Y1489470D01*
X639506Y1489729D01*
X639813Y1489832D01*
G01X637441Y1489315D02*
X637211Y1489625D01*
X636943Y1489780D01*
X636636Y1489832D01*
X636253Y1489729D01*
X635985Y1489470D01*
X635908Y1489160D01*
X635946Y1488850D01*
X636100Y1488592D01*
X636866Y1488075D01*
X637211Y1487714D01*
X637441Y1487197D01*
X637518Y1486732D01*
X635908D01*
G01X634341Y1488024D02*
X634073Y1488385D01*
X633843Y1488592D01*
X633536Y1488695D01*
X633268Y1488592D01*
X633076Y1488385D01*
X632923Y1488075D01*
X632885Y1487714D01*
X632923Y1487404D01*
X633076Y1487094D01*
X633306Y1486835D01*
X633575Y1486732D01*
X633881Y1486835D01*
X634150Y1487145D01*
X634303Y1487610D01*
X634341Y1488127D01*
X634265Y1488799D01*
X634150Y1489160D01*
X633958Y1489522D01*
X633690Y1489780D01*
X633421Y1489832D01*
X633153Y1489729D01*
X632961Y1489470D01*
G01X629183Y1540738D02*
Y1534538D01*
X632383D01*
Y1540738D01*
X629183D01*
G01X619735D02*
Y1534538D01*
X622935D01*
Y1540738D01*
X619735D01*
G01X634441Y1633586D02*
Y1631364D01*
X634288Y1630899D01*
X633981Y1630589D01*
X633598Y1630486D01*
X633215Y1630589D01*
X632908Y1630899D01*
X632755Y1631364D01*
Y1633586D01*
G01X630038Y1630486D02*
Y1633586D01*
X631456Y1631364D01*
X629540D01*
G01X628241Y1631106D02*
X628011Y1630744D01*
X627705Y1630538D01*
X627360Y1630486D01*
X627053Y1630538D01*
X626746Y1630796D01*
X626555Y1631106D01*
X626516Y1631416D01*
X626593Y1631778D01*
X626861Y1632036D01*
X627130Y1632139D01*
X627475D01*
G01X627130D02*
X626900Y1632294D01*
X626708Y1632553D01*
X626631Y1632863D01*
X626708Y1633173D01*
X626900Y1633431D01*
X627245Y1633586D01*
X627590Y1633534D01*
X627935Y1633328D01*
G01X626258Y1648777D02*
Y1638663D01*
G01D02*
X634398D01*
G01Y1648777D02*
X626258D01*
G01X633248Y1733579D02*
X625748D01*
Y1731339D01*
X626123Y1730592D01*
X626998Y1730032D01*
X627998Y1729845D01*
X628998Y1730032D01*
X629748Y1730499D01*
X630123Y1731339D01*
Y1733579D01*
G01X633248Y1726079D02*
X625748D01*
Y1723745D01*
X626123Y1722999D01*
X626623Y1722532D01*
X627623Y1722345D01*
X628623Y1722532D01*
X629248Y1723092D01*
X629623Y1723745D01*
Y1726079D01*
G01Y1723745D02*
X633248Y1722345D01*
G01Y1714845D02*
Y1718579D01*
X625748D01*
Y1714845D01*
G01X629373Y1716339D02*
Y1718579D01*
G01X632248Y1711172D02*
X632873Y1710425D01*
X633248Y1709585D01*
Y1708839D01*
X632873Y1708092D01*
X632248Y1707532D01*
X631373Y1707252D01*
X630498Y1707439D01*
X629748Y1707905D01*
X629248Y1708745D01*
X628998Y1709865D01*
X628498Y1710519D01*
X627623Y1710799D01*
X626748Y1710612D01*
X626123Y1710145D01*
X625748Y1709492D01*
Y1708839D01*
X625998Y1708185D01*
X626623Y1707625D01*
G01X632248Y1703672D02*
X632873Y1702925D01*
X633248Y1702085D01*
Y1701339D01*
X632873Y1700592D01*
X632248Y1700032D01*
X631373Y1699752D01*
X630498Y1699939D01*
X629748Y1700405D01*
X629248Y1701245D01*
X628998Y1702365D01*
X628498Y1703019D01*
X627623Y1703299D01*
X626748Y1703112D01*
X626123Y1702645D01*
X625748Y1701992D01*
Y1701339D01*
X625998Y1700685D01*
X626623Y1700125D01*
G01X630748Y1695425D02*
Y1692999D01*
G01X633248Y1688485D02*
X625748D01*
Y1684939D01*
G01X629373Y1686245D02*
Y1688485D01*
G01X625748Y1680332D02*
Y1678092D01*
G01Y1679212D02*
X633248D01*
G01Y1680332D02*
Y1678092D01*
G01X625748Y1671712D02*
X633248D01*
G01X625748Y1673859D02*
Y1669565D01*
G01X644746Y32386D02*
Y38586D01*
G01D02*
X641546D01*
G01D02*
Y32386D01*
G01D02*
X644746D01*
G01X646072Y38586D02*
Y32386D01*
G01D02*
X649272D01*
G01Y38586D02*
X646072D01*
G01X636622Y52147D02*
X642822D01*
G01D02*
Y55347D01*
G01D02*
X636622D01*
G01D02*
Y52147D01*
G01X635820Y57365D02*
Y63565D01*
G01X647622Y56860D02*
Y50660D01*
G01D02*
X650822D01*
G01Y56860D02*
X647622D01*
G01X643622D02*
Y50660D01*
G01D02*
X646822D01*
G01D02*
Y56860D01*
G01D02*
X643622D01*
G01X636545Y68440D02*
X642745D01*
G01D02*
Y71640D01*
G01D02*
X636545D01*
G01D02*
Y68440D01*
G01X635745D02*
Y71640D01*
G01X636545Y64440D02*
X642745D01*
G01D02*
Y67640D01*
G01D02*
X636545D01*
G01D02*
Y64440D01*
G01X635745D02*
Y67640D01*
G01X646339Y63145D02*
X652539D01*
G01Y66345D02*
X646339D01*
G01D02*
Y63145D01*
G01X646307Y66972D02*
X652507D01*
G01Y70172D02*
X646307D01*
G01D02*
Y66972D01*
G01X639070Y82061D02*
Y75861D01*
G01D02*
X642270D01*
G01D02*
Y82061D01*
G01D02*
X639070D01*
G01X645119Y432537D02*
Y426337D01*
G01D02*
X648319D01*
G01Y432537D02*
X645119D01*
G01X642744Y437918D02*
X648944D01*
G01Y441118D02*
X642744D01*
G01D02*
Y437918D01*
G01X650202Y446536D02*
X644002D01*
G01D02*
Y443336D01*
G01D02*
X650202D01*
G01X641570Y463530D02*
Y460330D01*
G01X647770Y463530D02*
X641570D01*
G01X647770Y460330D02*
Y463530D01*
G01X641570Y460330D02*
X647770D01*
G01X642817Y477541D02*
X649017D01*
G01X642817Y480741D02*
Y477541D01*
G01X649055Y475477D02*
X642855D01*
G01D02*
Y472277D01*
G01D02*
X649055D01*
G01X649017Y471427D02*
X642817D01*
G01D02*
Y468227D01*
G01D02*
X649017D01*
G01Y480741D02*
X642817D01*
G01X634400Y749500D02*
Y755700D01*
G01X643890Y752866D02*
Y749666D01*
G01X650090Y752866D02*
X643890D01*
G01Y749666D02*
X650090D01*
G01X641355Y755505D02*
X653355D01*
G01X641355Y761505D02*
Y755505D01*
G01X653355Y761505D02*
X641355D01*
G01X636546Y759528D02*
Y765728D01*
X633346D01*
Y759528D01*
X636546D01*
G01Y756378D02*
Y762578D01*
X633346D01*
Y756378D01*
X636546D01*
G01X647230Y762166D02*
X653430D01*
G01X647230Y765366D02*
Y762166D01*
G01X653430Y765366D02*
X647230D01*
G01X647229Y768866D02*
Y765666D01*
G01X653429Y768866D02*
X647229D01*
G01Y765666D02*
X653429D01*
G01X636724Y997560D02*
Y1040868D01*
G01X643851Y1369189D02*
X650051D01*
G01X643851Y1372389D02*
Y1369189D01*
G01X650051Y1372389D02*
X643851D01*
G01X650051Y1382553D02*
X643851D01*
G01Y1379353D02*
X650051D01*
G01X643851Y1382553D02*
Y1379353D01*
G01Y1373314D02*
X650051D01*
G01X643851Y1376514D02*
Y1373314D01*
G01X650051Y1376514D02*
X643851D01*
G01X648081Y1534538D02*
X651281D01*
G01X648081Y1540738D02*
Y1534538D01*
G01X643357Y1540738D02*
Y1534538D01*
X646557D01*
Y1540738D01*
X643357D01*
G01X633908D02*
Y1534538D01*
X637108D01*
Y1540738D01*
X633908D01*
G01X638632D02*
Y1534538D01*
X641832D01*
Y1540738D01*
X638632D01*
G01X651281D02*
X648081D01*
G01X634398Y1638663D02*
Y1648777D01*
G01X648042Y1635215D02*
Y1638415D01*
G01X641842Y1635215D02*
X648042D01*
G01X641842Y1638415D02*
Y1635215D01*
G01X648042Y1638415D02*
X641842D01*
G01X635433Y1694200D02*
Y1652500D01*
G01X645658Y1699170D02*
X648858D01*
G01X645658Y1705370D02*
Y1699170D01*
G01X644858D02*
Y1705370D01*
G01X641658Y1699170D02*
X644858D01*
G01X641658Y1705370D02*
Y1699170D01*
G01X644858Y1698370D02*
X641658D01*
G01X644858Y1692170D02*
Y1698370D01*
G01X641658Y1692170D02*
X644858D01*
G01X641658Y1698370D02*
Y1692170D01*
G01X645658D02*
X648858D01*
G01X645658Y1698370D02*
Y1692170D01*
G01X648858Y1698370D02*
X645658D01*
G01X635433Y1708500D02*
Y1699600D01*
G01X645658Y1713170D02*
X648858D01*
G01X645658Y1719370D02*
Y1713170D01*
G01X648858Y1705370D02*
X645658D01*
G01X644858Y1713170D02*
Y1719370D01*
G01X641658Y1713170D02*
X644858D01*
G01X641658Y1719370D02*
Y1713170D01*
G01X648858Y1712370D02*
X645658D01*
G01Y1706170D02*
X648858D01*
G01X645658Y1712370D02*
Y1706170D01*
G01X641658D02*
X644858D01*
G01X641658Y1712370D02*
Y1706170D01*
G01X644858Y1712370D02*
X641658D01*
G01X644858Y1706170D02*
Y1712370D01*
G01Y1705370D02*
X641658D01*
G01X635433Y1781456D02*
Y1714700D01*
G01X648858Y1719370D02*
X645658D01*
G01X644858D02*
X641658D01*
G01X657886Y32386D02*
Y38586D01*
G01D02*
X654686D01*
G01D02*
Y32386D01*
G01D02*
X657886D01*
G01X650310Y38586D02*
Y32386D01*
G01D02*
X653510D01*
G01D02*
Y38586D01*
G01D02*
X650310D01*
G01X649272Y32386D02*
Y38586D01*
G01X664463Y60050D02*
X661263D01*
G01D02*
Y53850D01*
G01D02*
X664463D01*
G01X660335Y53839D02*
Y60039D01*
G01D02*
X657135D01*
G01D02*
Y53839D01*
G01D02*
X660335D01*
G01X650822Y50660D02*
Y56860D01*
G01X652539Y63145D02*
Y66345D01*
G01X652507Y66972D02*
Y70172D01*
G01X657445Y419461D02*
Y413261D01*
G01D02*
X660645D01*
G01D02*
Y419461D01*
G01D02*
X657445D01*
G01X648319Y426337D02*
Y432537D01*
G01X654204Y442897D02*
X660404D01*
G01D02*
Y446097D01*
G01D02*
X654204D01*
G01D02*
Y442897D01*
G01X648944Y437918D02*
Y441118D01*
G01X650202Y443336D02*
Y446536D01*
G01X661038Y455480D02*
X654838D01*
G01D02*
Y452280D01*
G01D02*
X661038D01*
G01D02*
Y455480D01*
G01X654900Y456262D02*
X661100D01*
G01D02*
Y459462D01*
G01D02*
X654900D01*
G01D02*
Y456262D01*
G01X649017Y477541D02*
Y480741D01*
G01X649055Y472277D02*
Y475477D01*
G01X649017Y468227D02*
Y471427D01*
G01X654900Y468262D02*
X661100D01*
G01D02*
Y471462D01*
G01D02*
X654900D01*
G01D02*
Y468262D01*
G01Y464262D02*
X661100D01*
G01D02*
Y467462D01*
G01D02*
X654900D01*
G01D02*
Y464262D01*
G01X650090Y749666D02*
Y752866D01*
G01X657590Y749666D02*
Y752866D01*
G01X651390Y749666D02*
X657590D01*
G01X651390Y752866D02*
Y749666D01*
G01X657590Y752866D02*
X651390D01*
G01X653355Y755505D02*
Y761505D01*
G01X669497D02*
X657497D01*
G01Y755505D02*
X669497D01*
G01X657497Y761505D02*
Y755505D01*
G01X657421Y762166D02*
X663621D01*
G01X657421Y765366D02*
Y762166D01*
G01X663621Y765366D02*
X657421D01*
G01X653430Y762166D02*
Y765366D01*
G01X653429Y765666D02*
Y768866D01*
G01X657422Y768900D02*
Y765700D01*
G01X663622Y768900D02*
X657422D01*
G01Y765700D02*
X663622D01*
G01X657422Y769500D02*
X663622D01*
Y772700D01*
X657422D01*
Y769500D01*
G01X662671Y959366D02*
Y962566D01*
G01X656471Y959366D02*
X662671D01*
G01X656471Y962566D02*
Y959366D01*
G01X662671Y962566D02*
X656471D01*
G01X650051Y1369189D02*
Y1372389D01*
G01X660203Y1371604D02*
X657003D01*
G01X660203Y1365404D02*
Y1371604D01*
G01X657003Y1365404D02*
X660203D01*
G01X657003Y1371604D02*
Y1365404D01*
G01X650051Y1379353D02*
Y1382553D01*
G01Y1373314D02*
Y1376514D01*
G01X664267Y1382436D02*
X658067D01*
G01Y1379236D02*
X664267D01*
G01X658067Y1382436D02*
Y1379236D01*
G01Y1375236D02*
X664267D01*
G01X658067Y1378436D02*
Y1375236D01*
G01X664267Y1378436D02*
X658067D01*
G01X655223Y1491979D02*
X653714Y1491983D01*
G01X655273Y1508912D02*
X655267Y1491929D01*
G01X654673Y1508912D02*
X654677Y1491937D01*
G01X654073Y1508912D02*
X654076Y1491972D01*
G01X658898Y1500897D02*
X656658D01*
G01X657871Y1502522D02*
Y1499272D01*
G01X655273Y1508912D02*
X654073D01*
G01X651281Y1534538D02*
Y1540738D01*
G01X653412D02*
Y1534538D01*
X656612D01*
Y1540738D01*
X653412D01*
G01X662983Y1624259D02*
X663035Y1623952D01*
X663241Y1623684D01*
X663551Y1623454D01*
X663913Y1623301D01*
X664326Y1623224D01*
X664740D01*
X665153Y1623301D01*
X665515Y1623454D01*
X665825Y1623684D01*
X666031Y1623952D01*
X666083Y1624259D01*
X666031Y1624566D01*
X665825Y1624834D01*
X665515Y1625064D01*
X665153Y1625217D01*
X664740Y1625294D01*
X664326D01*
X663913Y1625217D01*
X663551Y1625064D01*
X663241Y1624834D01*
X663035Y1624566D01*
X662983Y1624259D01*
G01X663810Y1624566D02*
X662983Y1625026D01*
G01Y1627359D02*
X666083D01*
X665463Y1626899D01*
G01X662983D02*
Y1627819D01*
G01X665566Y1629731D02*
X665876Y1629961D01*
X666031Y1630229D01*
X666083Y1630536D01*
X665980Y1630919D01*
X665721Y1631187D01*
X665411Y1631264D01*
X665101Y1631226D01*
X664843Y1631072D01*
X664326Y1630306D01*
X663965Y1629961D01*
X663448Y1629731D01*
X662983Y1629654D01*
Y1631264D01*
G01Y1633559D02*
X663035Y1633827D01*
X663190Y1634134D01*
X663448Y1634326D01*
X663810Y1634402D01*
X664171Y1634326D01*
X664481Y1634096D01*
X664636Y1633751D01*
Y1633367D01*
X664740Y1633137D01*
X664998Y1632946D01*
X665360Y1632869D01*
X665721Y1632984D01*
X665980Y1633252D01*
X666083Y1633559D01*
X665980Y1633866D01*
X665721Y1634134D01*
X665360Y1634249D01*
X664998Y1634172D01*
X664740Y1633981D01*
X664636Y1633751D01*
Y1633367D01*
X664481Y1633022D01*
X664171Y1632792D01*
X663810Y1632716D01*
X663448Y1632792D01*
X663190Y1632984D01*
X663035Y1633291D01*
X662983Y1633559D01*
G01X650502Y1627422D02*
Y1624075D01*
G01X659164D02*
Y1634569D01*
G01X650502Y1624075D02*
X659164D01*
G01X655867Y1643122D02*
Y1639922D01*
G01X662067D02*
Y1643122D01*
G01X655867Y1639922D02*
X662067D01*
G01X648867Y1643122D02*
Y1639922D01*
G01X655067D02*
Y1643122D01*
G01X648867Y1639922D02*
X655067D01*
G01X652717Y1639122D02*
Y1635922D01*
G01X658917Y1639122D02*
X652717D01*
G01X658917Y1635922D02*
Y1639122D01*
G01X652717Y1635922D02*
X658917D01*
G01X652702Y1629322D02*
X650502Y1627422D01*
G01Y1631222D02*
X652702Y1629322D01*
G01X650502Y1634569D02*
Y1631222D01*
G01X659164Y1634569D02*
X650502D01*
G01X662067Y1643122D02*
X655867D01*
G01X662067Y1643922D02*
Y1647122D01*
G01X655867Y1643922D02*
X662067D01*
G01X655867Y1647122D02*
Y1643922D01*
G01X662067Y1647122D02*
X655867D01*
G01X648867D02*
Y1643922D01*
G01X655067D02*
Y1647122D01*
G01X648867Y1643922D02*
X655067D01*
G01Y1647122D02*
X648867D01*
G01X655067Y1643122D02*
X648867D01*
G01X658118Y1665683D02*
X668232D01*
G01X658118Y1673823D02*
Y1665683D01*
G01X666701Y1683490D02*
Y1681268D01*
X666548Y1680803D01*
X666241Y1680493D01*
X665858Y1680390D01*
X665475Y1680493D01*
X665168Y1680803D01*
X665015Y1681268D01*
Y1683490D01*
G01X662298Y1680390D02*
Y1683490D01*
X663716Y1681268D01*
X661800D01*
G01X659658Y1680390D02*
Y1683490D01*
X660118Y1682870D01*
G01Y1680390D02*
X659198D01*
G01X668232Y1673823D02*
X658118D01*
G01X648858Y1699170D02*
Y1705370D01*
G01Y1692170D02*
Y1698370D01*
G01X649658Y1702220D02*
Y1696020D01*
G01D02*
X652858D01*
G01D02*
Y1702220D01*
G01X654211Y1702467D02*
Y1693805D01*
G01X661358D02*
X664705D01*
G01X659458Y1696005D02*
X661358Y1693805D01*
G01X657558D02*
X659458Y1696005D01*
G01X654211Y1693805D02*
X657558D01*
G01X648858Y1713170D02*
Y1719370D01*
G01Y1706170D02*
Y1712370D01*
G01X649658Y1716220D02*
Y1710020D01*
G01D02*
X652858D01*
G01D02*
Y1716220D01*
G01Y1702220D02*
X649658D01*
G01X654211Y1716467D02*
Y1707805D01*
G01X661358D02*
X664705D01*
G01X659458Y1710005D02*
X661358Y1707805D01*
G01X657558D02*
X659458Y1710005D01*
G01X654211Y1707805D02*
X657558D01*
G01X664705Y1702467D02*
X654211D01*
G01X652858Y1716220D02*
X649658D01*
G01X664705Y1716467D02*
X654211D01*
G01X676563Y28642D02*
Y34842D01*
G01X673363D02*
Y28642D01*
G01D02*
X676563D01*
G01X672564D02*
Y34842D01*
G01X669364D02*
Y28642D01*
G01D02*
X672564D01*
G01X676563Y34842D02*
X673363D01*
G01X672564D02*
X669364D01*
G01X664463Y53850D02*
Y60050D01*
G01X679891Y56782D02*
X676691D01*
G01D02*
Y50582D01*
G01D02*
X679891D01*
G01X664670Y194972D02*
X674870D01*
G01D02*
Y199572D01*
G01X664670D02*
Y194972D01*
G01X664880Y208762D02*
X671080D01*
G01D02*
Y211962D01*
G01X664880D02*
Y208762D01*
G01Y204762D02*
X671080D01*
G01D02*
Y207962D01*
G01D02*
X664880D01*
G01D02*
Y204762D01*
G01Y200762D02*
X671080D01*
G01D02*
Y203962D01*
G01D02*
X664880D01*
G01D02*
Y200762D01*
G01X674870Y199572D02*
X664670D01*
G01X671080Y211962D02*
X664880D01*
G01X672100Y383262D02*
Y389462D01*
G01X668900D02*
Y383262D01*
G01D02*
X672100D01*
G01X673900Y389462D02*
Y383262D01*
G01D02*
X677100D01*
G01D02*
Y389462D01*
G01X677900D02*
Y383262D01*
G01D02*
X681100D01*
G01X677100Y391762D02*
Y397962D01*
G01D02*
X673900D01*
G01D02*
Y391762D01*
G01D02*
X677100D01*
G01X681100Y397962D02*
X677900D01*
G01D02*
Y391762D01*
G01D02*
X681100D01*
G01X672100Y389462D02*
X668900D01*
G01X677100D02*
X673900D01*
G01X681100D02*
X677900D01*
G01X670898Y403046D02*
X677098D01*
G01D02*
Y406246D01*
G01X670898D02*
Y403046D01*
G01X670912Y412263D02*
X677112D01*
G01D02*
Y415463D01*
G01D02*
X670912D01*
G01D02*
Y412263D01*
G01X670896Y419459D02*
Y416259D01*
G01D02*
X677096D01*
G01D02*
Y419459D01*
G01X677098Y406246D02*
X670898D01*
G01X670921Y407622D02*
X677121D01*
G01D02*
Y410822D01*
G01D02*
X670921D01*
G01D02*
Y407622D01*
G01X670972Y420400D02*
X677172D01*
G01D02*
Y423600D01*
G01D02*
X670972D01*
G01D02*
Y420400D01*
G01X677096Y419459D02*
X670896D01*
G01X670900Y435462D02*
Y432262D01*
G01D02*
X677100D01*
G01D02*
Y435462D01*
G01X677450Y430952D02*
X671250D01*
G01D02*
Y427752D01*
G01D02*
X677450D01*
G01D02*
Y430952D01*
G01X671050Y448802D02*
Y445602D01*
G01D02*
X677250D01*
G01D02*
Y448802D01*
G01X677100Y443462D02*
X670900D01*
G01D02*
Y440262D01*
G01D02*
X677100D01*
G01D02*
Y443462D01*
G01Y435462D02*
X670900D01*
G01X677150Y439332D02*
X670950D01*
G01D02*
Y436132D01*
G01D02*
X677150D01*
G01D02*
Y439332D01*
G01X677250Y448802D02*
X671050D01*
G01X677100Y459462D02*
X670900D01*
G01D02*
Y456262D01*
G01D02*
X677100D01*
G01D02*
Y459462D01*
G01Y455462D02*
X670900D01*
G01D02*
Y452262D01*
G01D02*
X677100D01*
G01D02*
Y455462D01*
G01Y467462D02*
X670900D01*
G01D02*
Y464262D01*
G01D02*
X677100D01*
G01D02*
Y467462D01*
G01X670925Y471762D02*
X677125D01*
G01D02*
Y474962D01*
G01D02*
X670925D01*
G01D02*
Y471762D01*
G01X673390Y753366D02*
Y750166D01*
G01X679590Y753366D02*
X673390D01*
G01Y750166D02*
X679590D01*
G01X671056Y755505D02*
X683056D01*
G01X671056Y761505D02*
Y755505D01*
G01X683056Y761505D02*
X671056D01*
G01X669497Y755505D02*
Y761505D01*
G01X663621Y762166D02*
Y765366D01*
G01X676931Y762166D02*
X683131D01*
G01X676931Y765366D02*
Y762166D01*
G01X683131Y765366D02*
X676931D01*
G01X676930Y768866D02*
Y765666D01*
G01X683130Y768866D02*
X676930D01*
G01Y765666D02*
X683130D01*
G01X663622Y765700D02*
Y768900D01*
G01X675552Y1341488D02*
X681552D01*
G01X675552Y1353488D02*
Y1341488D01*
G01X681552Y1353488D02*
X675552D01*
G01X664267Y1379236D02*
Y1382436D01*
G01Y1375236D02*
Y1378436D01*
G01X675861Y1634642D02*
Y1631442D01*
G01X682061Y1634642D02*
X675861D01*
G01Y1631442D02*
X682061D01*
G01X675861Y1640442D02*
X682061D01*
G01X675861Y1643642D02*
Y1640442D01*
G01Y1638642D02*
Y1635442D01*
G01X682061Y1638642D02*
X675861D01*
G01Y1635442D02*
X682061D01*
G01X675861Y1627442D02*
X682061D01*
G01X675861Y1630642D02*
Y1627442D01*
G01X682061Y1630642D02*
X675861D01*
G01X675297Y1648019D02*
Y1644819D01*
G01X681497Y1648019D02*
X675297D01*
G01Y1644819D02*
X681497D01*
G01X675297Y1652019D02*
Y1648819D01*
G01X681497Y1652019D02*
X675297D01*
G01Y1648819D02*
X681497D01*
G01X682061Y1643642D02*
X675861D01*
G01X668232Y1665683D02*
Y1673823D01*
G01X673972Y1683139D02*
X680172D01*
G01X673972Y1686339D02*
Y1683139D01*
G01X672900Y1698564D02*
Y1701764D01*
G01X666700Y1698564D02*
X672900D01*
G01X666700Y1701764D02*
Y1698564D01*
G01X680172Y1686339D02*
X673972D01*
G01X683072Y1698129D02*
X683379Y1698181D01*
X683647Y1698387D01*
X683877Y1698697D01*
X684030Y1699059D01*
X684107Y1699472D01*
Y1699886D01*
X684030Y1700299D01*
X683877Y1700661D01*
X683647Y1700971D01*
X683379Y1701177D01*
X683072Y1701229D01*
X682765Y1701177D01*
X682497Y1700971D01*
X682267Y1700661D01*
X682114Y1700299D01*
X682037Y1699886D01*
Y1699472D01*
X682114Y1699059D01*
X682267Y1698697D01*
X682497Y1698387D01*
X682765Y1698181D01*
X683072Y1698129D01*
G01X682765Y1698956D02*
X682305Y1698129D01*
G01X679972D02*
Y1701229D01*
X680432Y1700609D01*
G01Y1698129D02*
X679512D01*
G01X677715Y1698749D02*
X677485Y1698387D01*
X677179Y1698181D01*
X676834Y1698129D01*
X676527Y1698181D01*
X676220Y1698439D01*
X676029Y1698749D01*
X675990Y1699059D01*
X676067Y1699421D01*
X676335Y1699679D01*
X676604Y1699782D01*
X676949D01*
G01X676604D02*
X676374Y1699937D01*
X676182Y1700196D01*
X676105Y1700506D01*
X676182Y1700816D01*
X676374Y1701074D01*
X676719Y1701229D01*
X677064Y1701177D01*
X677409Y1700971D01*
G01X673772Y1698129D02*
Y1701229D01*
X674232Y1700609D01*
G01Y1698129D02*
X673312D01*
G01X664705Y1693805D02*
Y1702467D01*
G01X689512Y1692810D02*
Y1690588D01*
X689359Y1690123D01*
X689052Y1689813D01*
X688669Y1689710D01*
X688286Y1689813D01*
X687979Y1690123D01*
X687826Y1690588D01*
Y1692810D01*
G01X686297Y1691002D02*
X686029Y1691363D01*
X685799Y1691570D01*
X685492Y1691673D01*
X685224Y1691570D01*
X685032Y1691363D01*
X684879Y1691053D01*
X684841Y1690692D01*
X684879Y1690382D01*
X685032Y1690072D01*
X685262Y1689813D01*
X685531Y1689710D01*
X685837Y1689813D01*
X686106Y1690123D01*
X686259Y1690588D01*
X686297Y1691105D01*
X686221Y1691777D01*
X686106Y1692138D01*
X685914Y1692500D01*
X685646Y1692758D01*
X685377Y1692810D01*
X685109Y1692707D01*
X684917Y1692448D01*
G01X682469Y1692810D02*
X682776Y1692707D01*
X683006Y1692448D01*
X683159Y1692138D01*
X683274Y1691725D01*
X683312Y1691260D01*
X683274Y1690795D01*
X683159Y1690382D01*
X683006Y1690072D01*
X682776Y1689813D01*
X682469Y1689710D01*
X682162Y1689813D01*
X681932Y1690072D01*
X681779Y1690382D01*
X681664Y1690795D01*
X681626Y1691260D01*
X681664Y1691725D01*
X681779Y1692138D01*
X681932Y1692448D01*
X682162Y1692707D01*
X682469Y1692810D01*
G01X679369D02*
X679676Y1692707D01*
X679906Y1692448D01*
X680059Y1692138D01*
X680174Y1691725D01*
X680212Y1691260D01*
X680174Y1690795D01*
X680059Y1690382D01*
X679906Y1690072D01*
X679676Y1689813D01*
X679369Y1689710D01*
X679062Y1689813D01*
X678832Y1690072D01*
X678679Y1690382D01*
X678564Y1690795D01*
X678526Y1691260D01*
X678564Y1691725D01*
X678679Y1692138D01*
X678832Y1692448D01*
X679062Y1692707D01*
X679369Y1692810D01*
G01X675809Y1689710D02*
Y1692810D01*
X677227Y1690588D01*
X675311D01*
G01X669658Y1712852D02*
Y1719052D01*
G01X666458Y1712852D02*
X669658D01*
G01X666458Y1719052D02*
Y1712852D01*
G01X672900Y1701764D02*
X666700D01*
G01X681072Y1712129D02*
X681379Y1712181D01*
X681647Y1712387D01*
X681877Y1712697D01*
X682030Y1713059D01*
X682107Y1713472D01*
Y1713886D01*
X682030Y1714299D01*
X681877Y1714661D01*
X681647Y1714971D01*
X681379Y1715177D01*
X681072Y1715229D01*
X680765Y1715177D01*
X680497Y1714971D01*
X680267Y1714661D01*
X680114Y1714299D01*
X680037Y1713886D01*
Y1713472D01*
X680114Y1713059D01*
X680267Y1712697D01*
X680497Y1712387D01*
X680765Y1712181D01*
X681072Y1712129D01*
G01X680765Y1712956D02*
X680305Y1712129D01*
G01X677972D02*
Y1715229D01*
X678432Y1714609D01*
G01Y1712129D02*
X677512D01*
G01X675715Y1712749D02*
X675485Y1712387D01*
X675179Y1712181D01*
X674834Y1712129D01*
X674527Y1712181D01*
X674220Y1712439D01*
X674029Y1712749D01*
X673990Y1713059D01*
X674067Y1713421D01*
X674335Y1713679D01*
X674604Y1713782D01*
X674949D01*
G01X674604D02*
X674374Y1713937D01*
X674182Y1714196D01*
X674105Y1714506D01*
X674182Y1714816D01*
X674374Y1715074D01*
X674719Y1715229D01*
X675064Y1715177D01*
X675409Y1714971D01*
G01X672500Y1714712D02*
X672270Y1715022D01*
X672002Y1715177D01*
X671695Y1715229D01*
X671312Y1715126D01*
X671044Y1714867D01*
X670967Y1714557D01*
X671005Y1714247D01*
X671159Y1713989D01*
X671925Y1713472D01*
X672270Y1713111D01*
X672500Y1712594D01*
X672577Y1712129D01*
X670967D01*
G01X664705Y1707805D02*
Y1716467D01*
G01X669658Y1719052D02*
X666458D01*
G01X682221Y28642D02*
Y34842D01*
G01X679021D02*
Y28642D01*
G01D02*
X682221D01*
G01X687438Y28620D02*
Y34820D01*
G01X684238D02*
Y28620D01*
G01D02*
X687438D01*
G01X682221Y34842D02*
X679021D01*
G01X694066Y43050D02*
X690866D01*
G01D02*
Y36850D01*
G01D02*
X694066D01*
G01X687438Y34820D02*
X684238D01*
G01X688691Y59432D02*
Y53232D01*
G01D02*
X691891D01*
G01D02*
Y59432D01*
G01D02*
X688691D01*
G01X683891Y49722D02*
Y55922D01*
G01D02*
X680691D01*
G01D02*
Y49722D01*
G01D02*
X683891D01*
G01X692800Y57282D02*
Y51082D01*
G01D02*
X696000D01*
G01Y57282D02*
X692800D01*
G01X687891Y51082D02*
Y57282D01*
G01D02*
X684691D01*
G01D02*
Y51082D01*
G01D02*
X687891D01*
G01X679891Y50582D02*
Y56782D01*
G01X678844Y77227D02*
Y74027D01*
G01D02*
X685044D01*
G01D02*
Y77227D01*
G01D02*
X678844D01*
G01X682920Y100062D02*
Y94062D01*
G01D02*
X694920D01*
G01Y100062D02*
X682920D01*
G01X679900Y115400D02*
X683100D01*
G01X679900Y121600D02*
Y115400D01*
G01X683100D02*
Y121600D01*
G01X695554Y129627D02*
X692354D01*
G01D02*
Y123427D01*
G01D02*
X695554D01*
G01X683100Y121600D02*
X679900D01*
G01X681900Y389462D02*
Y383262D01*
G01D02*
X685100D01*
G01D02*
Y389462D01*
G01X681100Y383262D02*
Y389462D01*
G01X685100D02*
X681900D01*
G01X685100Y391762D02*
Y397962D01*
G01D02*
X681900D01*
G01D02*
Y391762D01*
G01D02*
X685100D01*
G01X681100D02*
Y397962D01*
G01X693100D02*
X689900D01*
G01D02*
Y391762D01*
G01D02*
X693100D01*
G01X689160D02*
Y397962D01*
G01D02*
X685960D01*
G01D02*
Y391762D01*
G01D02*
X689160D01*
G01X691952Y500934D02*
X698152D01*
G01Y504134D02*
X691952D01*
G01D02*
Y500934D01*
G01X686400Y498600D02*
Y495400D01*
G01X692600Y498600D02*
X686400D01*
G01X692600Y495400D02*
Y498600D01*
G01X686400Y495400D02*
X692600D01*
G01X679590Y750166D02*
Y753366D01*
G01X683056Y755505D02*
Y761505D01*
G01X699198D02*
X687198D01*
G01Y755505D02*
X699198D01*
G01X687198Y761505D02*
Y755505D01*
G01X687122Y762166D02*
X693322D01*
G01X687122Y765366D02*
Y762166D01*
G01X693322Y765366D02*
X687122D01*
G01X683131Y762166D02*
Y765366D01*
G01X683130Y765666D02*
Y768866D01*
G01X687123Y768900D02*
Y765700D01*
G01X693323Y768900D02*
X687123D01*
G01Y765700D02*
X693323D01*
G01X687123Y769500D02*
X693323D01*
Y772700D01*
X687123D01*
Y769500D01*
G01X692372Y959366D02*
Y962566D01*
G01X686172Y959366D02*
X692372D01*
G01X686172Y962566D02*
Y959366D01*
G01X692372Y962566D02*
X686172D01*
G01X690948Y1329472D02*
X693188D01*
G01X691975Y1327847D02*
Y1331097D01*
G01X683413Y1335640D02*
X701129D01*
G01X683413Y1371336D02*
Y1335640D01*
G01X681552Y1341488D02*
Y1353488D01*
G01X691971Y1374175D02*
Y1376601D01*
G01X701129Y1371336D02*
X683413D01*
G01X682061Y1631442D02*
Y1634642D01*
G01Y1640442D02*
Y1643642D01*
G01Y1635442D02*
Y1638642D01*
G01Y1627442D02*
Y1630642D01*
G01X689318Y1635967D02*
Y1627305D01*
G01X691980D02*
X694618Y1630136D01*
G01X689318Y1627305D02*
X691980D01*
G01X699918Y1635967D02*
X689318D01*
G01X698468Y1639911D02*
Y1637689D01*
X698315Y1637224D01*
X698008Y1636914D01*
X697625Y1636811D01*
X697242Y1636914D01*
X696935Y1637224D01*
X696782Y1637689D01*
Y1639911D01*
G01X694525Y1636811D02*
Y1639911D01*
X694985Y1639291D01*
G01Y1636811D02*
X694065D01*
G01X692077Y1637173D02*
X691808Y1636914D01*
X691502Y1636811D01*
X691195Y1636914D01*
X690927Y1637224D01*
X690735Y1637689D01*
X690658Y1638154D01*
Y1638723D01*
X690735Y1639188D01*
X690927Y1639601D01*
X691157Y1639808D01*
X691425Y1639911D01*
X691732Y1639808D01*
X691962Y1639601D01*
X692115Y1639291D01*
X692192Y1638878D01*
X692115Y1638516D01*
X691923Y1638154D01*
X691693Y1637948D01*
X691425Y1637896D01*
X691118Y1637999D01*
X690888Y1638258D01*
X690658Y1638723D01*
G01X689053Y1639394D02*
X688823Y1639704D01*
X688555Y1639859D01*
X688248Y1639911D01*
X687865Y1639808D01*
X687597Y1639549D01*
X687520Y1639239D01*
X687558Y1638929D01*
X687712Y1638671D01*
X688478Y1638154D01*
X688823Y1637793D01*
X689053Y1637276D01*
X689130Y1636811D01*
X687520D01*
G01X687600Y1656100D02*
X681400D01*
G01Y1652900D02*
X687600D01*
G01D02*
Y1656100D01*
G01X681400D02*
Y1652900D01*
G01X684998Y1651750D02*
X681798D01*
G01D02*
Y1645550D01*
G01D02*
X684998D01*
G01D02*
Y1651750D01*
G01X681497Y1644819D02*
Y1648019D01*
G01Y1648819D02*
Y1652019D01*
G01X694070Y1663941D02*
X687870D01*
G01Y1660741D02*
X694070D01*
G01X687870Y1663941D02*
Y1660741D01*
G01X694073Y1659931D02*
X687873D01*
G01Y1656731D02*
X694073D01*
G01X687873Y1659931D02*
Y1656731D01*
G01X684594Y1668688D02*
X696406D01*
G01X684594Y1681312D02*
Y1668688D01*
G01X680810Y1686360D02*
Y1683160D01*
G01X687010D02*
Y1686360D01*
G01X680810Y1683160D02*
X687010D01*
G01X680172Y1683139D02*
Y1686339D01*
G01X687715Y1683135D02*
X693915D01*
G01X687715Y1686335D02*
Y1683135D01*
G01X696406Y1681312D02*
X684594D01*
G01X687010Y1686360D02*
X680810D01*
G01X693915Y1686335D02*
X687715D01*
G01X699493Y36850D02*
Y43050D01*
G01D02*
X696293D01*
G01D02*
Y36850D01*
G01D02*
X699493D01*
G01X694066D02*
Y43050D01*
G01X700881Y57258D02*
Y51058D01*
G01D02*
X704081D01*
G01D02*
Y57258D01*
G01D02*
X700881D01*
G01X707703Y57811D02*
Y51611D01*
G01D02*
X710903D01*
G01Y57811D02*
X707703D01*
G01X696997Y57282D02*
Y51082D01*
G01D02*
X700197D01*
G01D02*
Y57282D01*
G01D02*
X696997D01*
G01X696000Y51082D02*
Y57282D01*
G01X694920Y94062D02*
Y100062D01*
G01X706249Y131793D02*
Y125593D01*
G01D02*
X709449D01*
G01Y131793D02*
X706249D01*
G01X695554Y123427D02*
Y129627D01*
G01X693100Y391762D02*
Y397962D01*
G01X709100D02*
X705900D01*
G01D02*
Y391762D01*
G01D02*
X709100D01*
G01X705100D02*
Y397962D01*
G01D02*
X701900D01*
G01D02*
Y391762D01*
G01D02*
X705100D01*
G01X697100D02*
Y397962D01*
G01D02*
X693900D01*
G01D02*
Y391762D01*
G01D02*
X697100D01*
G01X701100D02*
Y397962D01*
X697900D01*
Y391762D01*
X701100D01*
G01X707200Y417020D02*
X710400D01*
G01X707200Y423220D02*
Y417020D01*
G01X710400Y423220D02*
X707200D01*
G01X707052Y502444D02*
Y496244D01*
G01D02*
X710252D01*
G01Y502444D02*
X707052D01*
G01X699052D02*
Y496244D01*
G01D02*
X702252D01*
G01D02*
Y502444D01*
G01D02*
X699052D01*
G01X698152Y500934D02*
Y504134D01*
G01X706252Y502444D02*
X703052D01*
G01X706252Y496244D02*
Y502444D01*
G01X703052Y496244D02*
X706252D01*
G01X703052Y502444D02*
Y496244D01*
G01X698638Y526300D02*
Y523100D01*
G01D02*
X704838D01*
G01D02*
Y526300D01*
G01X706200Y527162D02*
Y520962D01*
G01D02*
X709400D01*
G01X704838Y526300D02*
X698638D01*
G01X709400Y527162D02*
X706200D01*
G01X702890Y753366D02*
Y750166D01*
G01X709090Y753366D02*
X702890D01*
G01Y750166D02*
X709090D01*
G01X700757Y755505D02*
X712757D01*
G01X700757Y761505D02*
Y755505D01*
G01X712757Y761505D02*
X700757D01*
G01X699198Y755505D02*
Y761505D01*
G01X693322Y762166D02*
Y765366D01*
G01X706631Y768866D02*
Y765666D01*
G01X712831Y768866D02*
X706631D01*
G01Y765666D02*
X712831D01*
G01X693323Y765700D02*
Y768900D01*
G01X706632Y762166D02*
X712832D01*
G01X706632Y765366D02*
Y762166D01*
G01X712832Y765366D02*
X706632D01*
G01X704555Y1324917D02*
X707655D01*
Y1325837D01*
X707500Y1326144D01*
X707138Y1326374D01*
X706725Y1326451D01*
X706312Y1326374D01*
X706002Y1326182D01*
X705847Y1325837D01*
Y1324917D01*
G01X707397Y1329627D02*
X707552Y1329397D01*
X707655Y1329129D01*
Y1328822D01*
X707500Y1328477D01*
X707242Y1328209D01*
X706932Y1328017D01*
X706415Y1327864D01*
X705950Y1327826D01*
X705485Y1327902D01*
X705175Y1328017D01*
X704865Y1328247D01*
X704658Y1328516D01*
X704555Y1328784D01*
Y1329052D01*
X704658Y1329321D01*
X704813Y1329551D01*
X705020Y1329742D01*
G01X704555Y1331884D02*
X704607Y1332152D01*
X704762Y1332459D01*
X705020Y1332651D01*
X705382Y1332727D01*
X705743Y1332651D01*
X706053Y1332421D01*
X706208Y1332076D01*
Y1331692D01*
X706312Y1331462D01*
X706570Y1331271D01*
X706932Y1331194D01*
X707293Y1331309D01*
X707552Y1331577D01*
X707655Y1331884D01*
X707552Y1332191D01*
X707293Y1332459D01*
X706932Y1332574D01*
X706570Y1332497D01*
X706312Y1332306D01*
X706208Y1332076D01*
Y1331692D01*
X706053Y1331347D01*
X705743Y1331117D01*
X705382Y1331041D01*
X705020Y1331117D01*
X704762Y1331309D01*
X704607Y1331616D01*
X704555Y1331884D01*
G01X707655Y1334984D02*
X707552Y1334677D01*
X707293Y1334447D01*
X706983Y1334294D01*
X706570Y1334179D01*
X706105Y1334141D01*
X705640Y1334179D01*
X705227Y1334294D01*
X704917Y1334447D01*
X704658Y1334677D01*
X704555Y1334984D01*
X704658Y1335291D01*
X704917Y1335521D01*
X705227Y1335674D01*
X705640Y1335789D01*
X706105Y1335827D01*
X706570Y1335789D01*
X706983Y1335674D01*
X707293Y1335521D01*
X707552Y1335291D01*
X707655Y1334984D01*
G01X707138Y1337356D02*
X707448Y1337586D01*
X707603Y1337854D01*
X707655Y1338161D01*
X707552Y1338544D01*
X707293Y1338812D01*
X706983Y1338889D01*
X706673Y1338851D01*
X706415Y1338697D01*
X705898Y1337931D01*
X705537Y1337586D01*
X705020Y1337356D01*
X704555Y1337279D01*
Y1338889D01*
G01X701129Y1335640D02*
Y1371336D01*
G01X703121Y1341488D02*
X709121D01*
G01X703121Y1353488D02*
Y1341488D01*
G01X709121Y1353488D02*
X703121D01*
G01X709605Y1375047D02*
Y1377473D01*
G01X704142Y1390446D02*
X707342D01*
G01X704142Y1396646D02*
Y1390446D01*
G01X707342Y1396646D02*
X704142D01*
G01X707342Y1390446D02*
Y1396646D01*
G01X707717Y1622686D02*
X710917D01*
G01X707717Y1628886D02*
Y1622686D01*
G01X705624Y1621954D02*
Y1619732D01*
X705471Y1619267D01*
X705164Y1618957D01*
X704781Y1618854D01*
X704398Y1618957D01*
X704091Y1619267D01*
X703938Y1619732D01*
Y1621954D01*
G01X701681Y1618854D02*
Y1621954D01*
X702141Y1621334D01*
G01Y1618854D02*
X701221D01*
G01X699233Y1619216D02*
X698964Y1618957D01*
X698658Y1618854D01*
X698351Y1618957D01*
X698083Y1619267D01*
X697891Y1619732D01*
X697814Y1620197D01*
Y1620766D01*
X697891Y1621231D01*
X698083Y1621644D01*
X698313Y1621851D01*
X698581Y1621954D01*
X698888Y1621851D01*
X699118Y1621644D01*
X699271Y1621334D01*
X699348Y1620921D01*
X699271Y1620559D01*
X699079Y1620197D01*
X698849Y1619991D01*
X698581Y1619939D01*
X698274Y1620042D01*
X698044Y1620301D01*
X697814Y1620766D01*
G01X696324Y1619319D02*
X696094Y1619061D01*
X695826Y1618906D01*
X695481Y1618854D01*
X695136Y1618957D01*
X694868Y1619164D01*
X694676Y1619526D01*
X694638Y1619939D01*
X694714Y1620352D01*
X694906Y1620611D01*
X695174Y1620817D01*
X695443Y1620869D01*
X695711Y1620817D01*
X696056Y1620611D01*
X695941Y1621954D01*
X694906D01*
G01X701158Y1632636D02*
Y1629436D01*
G01X707358Y1632636D02*
X701158D01*
G01X707358Y1629436D02*
Y1632636D01*
G01X701158Y1629436D02*
X707358D01*
G01X710917Y1639386D02*
X707717D01*
G01Y1633186D02*
X710917D01*
G01X707717Y1639386D02*
Y1633186D01*
G01X710917Y1628886D02*
X707717D01*
G01X697256Y1627305D02*
X699918D01*
G01X694618Y1630136D02*
X697256Y1627305D01*
G01X699918D02*
Y1635967D01*
G01X696582Y1653250D02*
Y1641250D01*
G01D02*
X707382D01*
G01D02*
Y1653250D01*
G01X707415Y1655856D02*
Y1662056D01*
G01X704215D02*
Y1655856D01*
G01D02*
X707415D01*
G01X703982Y1653250D02*
X701982Y1651250D01*
G01D02*
X699982Y1653250D01*
G01X707382D02*
X703982D01*
G01X699982D02*
X696582D01*
G01X707415Y1662056D02*
X704215D01*
G01X694846Y1656737D02*
X701046D01*
G01X694846Y1659937D02*
Y1656737D01*
G01X701046Y1659937D02*
X694846D01*
G01X701046Y1656737D02*
Y1659937D01*
G01X694070Y1660741D02*
Y1663941D01*
G01X694073Y1656731D02*
Y1659931D01*
G01X696406Y1668688D02*
Y1681312D01*
G01X699657Y1666726D02*
Y1672874D01*
G01X711075Y1666726D02*
X699657D01*
G01X693915Y1683135D02*
Y1686335D01*
G01X715590Y1689896D02*
Y1687674D01*
X715437Y1687209D01*
X715130Y1686899D01*
X714747Y1686796D01*
X714364Y1686899D01*
X714057Y1687209D01*
X713904Y1687674D01*
Y1689896D01*
G01X711647Y1686796D02*
Y1689896D01*
X712107Y1689276D01*
G01Y1686796D02*
X711187D01*
G01X708087D02*
Y1689896D01*
X709505Y1687674D01*
X707589D01*
G01X706175Y1689379D02*
X705945Y1689689D01*
X705677Y1689844D01*
X705370Y1689896D01*
X704987Y1689793D01*
X704719Y1689534D01*
X704642Y1689224D01*
X704680Y1688914D01*
X704834Y1688656D01*
X705600Y1688139D01*
X705945Y1687778D01*
X706175Y1687261D01*
X706252Y1686796D01*
X704642D01*
G01X699657Y1672874D02*
X702366Y1674783D01*
G01D02*
X699657Y1676692D01*
G01D02*
Y1682840D01*
G01D02*
X711075D01*
G01X710903Y51611D02*
Y57811D01*
G01X721550Y50445D02*
Y56645D01*
G01D02*
X718350D01*
G01D02*
Y50445D01*
G01D02*
X721550D01*
G01X716266Y90033D02*
Y96233D01*
G01X713066D02*
Y90033D01*
G01D02*
X716266D01*
G01X721066Y96233D02*
Y90033D01*
G01D02*
X724266D01*
G01X720266D02*
Y96233D01*
G01X717066D02*
Y90033D01*
G01D02*
X720266D01*
G01X712266D02*
Y96233D01*
G01X709066D02*
Y90033D01*
G01D02*
X712266D01*
G01X722400Y83329D02*
Y77129D01*
G01D02*
X725600D01*
G01Y83329D02*
X722400D01*
G01X718410D02*
Y77129D01*
G01D02*
X721610D01*
G01D02*
Y83329D01*
G01D02*
X718410D01*
G01X714433D02*
Y77129D01*
G01D02*
X717633D01*
G01D02*
Y83329D01*
G01D02*
X714433D01*
G01X710443D02*
Y77129D01*
G01D02*
X713643D01*
G01D02*
Y83329D01*
G01D02*
X710443D01*
G01X716266Y96233D02*
X713066D01*
G01X724266D02*
X721066D01*
G01X720266D02*
X717066D01*
G01X712266D02*
X709066D01*
G01X709449Y125593D02*
Y131793D01*
G01X717838Y385434D02*
Y379234D01*
G01D02*
X721038D01*
G01D02*
Y385434D01*
G01D02*
X717838D01*
G01X716303Y379276D02*
Y385476D01*
G01D02*
X713103D01*
G01D02*
Y379276D01*
G01D02*
X716303D01*
G01X713900Y397962D02*
Y391762D01*
G01D02*
X717100D01*
G01D02*
Y397962D01*
G01D02*
X713900D01*
G01X709900D02*
Y391762D01*
G01D02*
X713100D01*
G01D02*
Y397962D01*
G01D02*
X709900D01*
G01X717900D02*
Y391762D01*
G01D02*
X721100D01*
G01D02*
Y397962D01*
G01D02*
X717900D01*
G01X725100D02*
X721900D01*
G01D02*
Y391762D01*
G01D02*
X725100D01*
G01X709100D02*
Y397962D01*
G01X710400Y417020D02*
Y423220D01*
G01X715119Y449429D02*
Y447129D01*
G01D02*
X720569D01*
G01D02*
Y449429D01*
G01X721492Y437681D02*
X723792D01*
G01Y443131D02*
X721492D01*
G01D02*
Y437681D01*
G01X718268D02*
X720568D01*
G01D02*
Y443131D01*
G01D02*
X718268D01*
G01D02*
Y437681D01*
G01X715119Y453994D02*
Y451694D01*
G01D02*
X720569D01*
G01D02*
Y453994D01*
G01D02*
X715119D01*
G01X718269Y465098D02*
Y462798D01*
G01D02*
X723719D01*
G01X715119Y458799D02*
Y456499D01*
G01D02*
X720569D01*
G01D02*
Y458799D01*
G01D02*
X715119D01*
G01X726868Y453994D02*
X721418D01*
G01D02*
Y451694D01*
G01D02*
X726868D01*
G01X720569Y449429D02*
X715119D01*
G01X723719Y465098D02*
X718269D01*
G01X711052Y502444D02*
Y496244D01*
G01D02*
X714252D01*
G01D02*
Y502444D01*
G01D02*
X711052D01*
G01X719052D02*
Y496244D01*
G01D02*
X722252D01*
G01D02*
Y502444D01*
G01D02*
X719052D01*
G01X710252Y496244D02*
Y502444D01*
G01X709744Y526932D02*
Y520732D01*
G01D02*
X712944D01*
G01D02*
Y526932D01*
G01X709400Y520962D02*
Y527162D01*
G01X723509Y529852D02*
X720309D01*
G01D02*
Y523652D01*
G01D02*
X723509D01*
G01X712944Y526932D02*
X709744D01*
G01X716445Y530024D02*
X713245D01*
G01X716445Y523824D02*
Y530024D01*
G01X713245D02*
Y523824D01*
G01D02*
X716445D01*
G01X719981Y530041D02*
X716781D01*
G01X719981Y523841D02*
Y530041D01*
G01X716781Y523841D02*
X719981D01*
G01X716781Y530041D02*
Y523841D01*
G01X732080Y560760D02*
Y558538D01*
X731927Y558073D01*
X731620Y557763D01*
X731237Y557660D01*
X730854Y557763D01*
X730547Y558073D01*
X730394Y558538D01*
Y560760D01*
G01X728137Y557660D02*
X727869Y557712D01*
X727562Y557867D01*
X727370Y558125D01*
X727294Y558487D01*
X727370Y558848D01*
X727600Y559158D01*
X727945Y559313D01*
X728329D01*
X728559Y559417D01*
X728750Y559675D01*
X728827Y560037D01*
X728712Y560398D01*
X728444Y560657D01*
X728137Y560760D01*
X727830Y560657D01*
X727562Y560398D01*
X727447Y560037D01*
X727524Y559675D01*
X727715Y559417D01*
X727945Y559313D01*
X728329D01*
X728674Y559158D01*
X728904Y558848D01*
X728980Y558487D01*
X728904Y558125D01*
X728712Y557867D01*
X728405Y557712D01*
X728137Y557660D01*
G01X725037Y560760D02*
X725344Y560657D01*
X725574Y560398D01*
X725727Y560088D01*
X725842Y559675D01*
X725880Y559210D01*
X725842Y558745D01*
X725727Y558332D01*
X725574Y558022D01*
X725344Y557763D01*
X725037Y557660D01*
X724730Y557763D01*
X724500Y558022D01*
X724347Y558332D01*
X724232Y558745D01*
X724194Y559210D01*
X724232Y559675D01*
X724347Y560088D01*
X724500Y560398D01*
X724730Y560657D01*
X725037Y560760D01*
G01X721937D02*
X722244Y560657D01*
X722474Y560398D01*
X722627Y560088D01*
X722742Y559675D01*
X722780Y559210D01*
X722742Y558745D01*
X722627Y558332D01*
X722474Y558022D01*
X722244Y557763D01*
X721937Y557660D01*
X721630Y557763D01*
X721400Y558022D01*
X721247Y558332D01*
X721132Y558745D01*
X721094Y559210D01*
X721132Y559675D01*
X721247Y560088D01*
X721400Y560398D01*
X721630Y560657D01*
X721937Y560760D01*
G01X718837D02*
X719144Y560657D01*
X719374Y560398D01*
X719527Y560088D01*
X719642Y559675D01*
X719680Y559210D01*
X719642Y558745D01*
X719527Y558332D01*
X719374Y558022D01*
X719144Y557763D01*
X718837Y557660D01*
X718530Y557763D01*
X718300Y558022D01*
X718147Y558332D01*
X718032Y558745D01*
X717994Y559210D01*
X718032Y559675D01*
X718147Y560088D01*
X718300Y560398D01*
X718530Y560657D01*
X718837Y560760D01*
G01X722205Y564169D02*
X725843D01*
G01X722205Y572831D02*
Y564169D01*
G01X720100Y576100D02*
X716900D01*
G01X720100Y569900D02*
Y576100D01*
G01X716900Y569900D02*
X720100D01*
G01X716900Y576100D02*
Y569900D01*
G01X732835Y572831D02*
X722205D01*
G01X709090Y750166D02*
Y753366D01*
G01X712757Y755505D02*
Y761505D01*
G01X728899D02*
X716899D01*
G01Y755505D02*
X728899D01*
G01X716899Y761505D02*
Y755505D01*
G01X716823Y762166D02*
X723023D01*
G01X716823Y765366D02*
Y762166D01*
G01X723023Y765366D02*
X716823D01*
G01X712831Y765666D02*
Y768866D01*
G01X716824Y768900D02*
Y765700D01*
G01X723024Y768900D02*
X716824D01*
G01Y765700D02*
X723024D01*
G01X712832Y762166D02*
Y765366D01*
G01X716824Y769500D02*
X723024D01*
Y772700D01*
X716824D01*
Y769500D01*
G01X722073Y959366D02*
Y962566D01*
G01X715873Y959366D02*
X722073D01*
G01X715873Y962566D02*
Y959366D01*
G01X722073Y962566D02*
X715873D01*
G01X718948Y1331102D02*
X721188D01*
G01X719975Y1329477D02*
Y1332727D01*
G01X711413Y1337270D02*
X729129D01*
G01X711413Y1372966D02*
Y1337270D01*
G01X709121Y1341488D02*
Y1353488D01*
G01X729129Y1372966D02*
X711413D01*
G01X709459Y1384123D02*
X712659D01*
G01X709459Y1390323D02*
Y1384123D01*
G01X712659D02*
Y1390323D01*
G01X721198Y1388730D02*
Y1376730D01*
G01D02*
X727198D01*
G01X712659Y1390323D02*
X709459D01*
G01X727198Y1388730D02*
X721198D01*
G01X721900Y1391846D02*
X727900D01*
G01X721900Y1403846D02*
Y1391846D01*
G01X727900Y1403846D02*
X721900D01*
G01X722650Y1564733D02*
X728850D01*
G01X722650Y1567933D02*
Y1564733D01*
G01X720350Y1579258D02*
X723550D01*
G01X720350Y1585458D02*
Y1579258D01*
G01X718021Y1572683D02*
X724221D01*
G01X718021Y1575883D02*
Y1572683D01*
G01X724221Y1575883D02*
X718021D01*
G01X728850Y1567933D02*
X722650D01*
G01X723550Y1585458D02*
X720350D01*
G01X718650Y1592353D02*
Y1589153D01*
G01X724850Y1592353D02*
X718650D01*
G01Y1589153D02*
X724850D01*
G01X723490Y1606337D02*
X720290D01*
G01Y1600137D02*
X723490D01*
G01X720290Y1606337D02*
Y1600137D01*
G01X715690Y1605143D02*
X712490D01*
G01X715690Y1598943D02*
Y1605143D01*
G01X712490Y1598943D02*
X715690D01*
G01X712490Y1605143D02*
Y1598943D01*
G01X719294Y1606328D02*
X716094D01*
G01X719294Y1600128D02*
Y1606328D01*
G01X716094Y1600128D02*
X719294D01*
G01X716094Y1606328D02*
Y1600128D01*
G01X714917Y1622686D02*
Y1628886D01*
G01X711717Y1622686D02*
X714917D01*
G01X711717Y1628886D02*
Y1622686D01*
G01X710917D02*
Y1628886D01*
G01X716592Y1630511D02*
Y1627311D01*
G01X722792Y1630511D02*
X716592D01*
G01Y1627311D02*
X722792D01*
G01X716592Y1634561D02*
Y1631361D01*
G01X722792Y1634561D02*
X716592D01*
G01Y1631361D02*
X722792D01*
G01X714917Y1639386D02*
X711717D01*
G01Y1633186D02*
X714917D01*
G01X711717Y1639386D02*
Y1633186D01*
G01X714917D02*
Y1639386D01*
G01X710917Y1633186D02*
Y1639386D01*
G01X714917Y1628886D02*
X711717D01*
G01X711371Y1655865D02*
Y1662065D01*
G01X708171Y1655865D02*
X711371D01*
G01X708171Y1662065D02*
Y1655865D01*
G01X719022Y1644237D02*
Y1650437D01*
G01D02*
X715822D01*
G01D02*
Y1644237D01*
G01D02*
X719022D01*
G01X719349Y1655859D02*
Y1662059D01*
G01X716149D02*
Y1655859D01*
G01D02*
X719349D01*
G01X712171Y1655865D02*
X715371D01*
G01X712171Y1662065D02*
Y1655865D01*
G01X715371D02*
Y1662065D01*
G01X711371D02*
X708171D01*
G01X716901Y1669230D02*
X723101D01*
G01X716901Y1672430D02*
Y1669230D01*
G01X719349Y1662059D02*
X716149D01*
G01X715371Y1662065D02*
X712171D01*
G01X724230Y1668498D02*
X721030D01*
G01Y1662298D02*
X724230D01*
G01X721030Y1668498D02*
Y1662298D01*
G01X711075Y1682840D02*
Y1666726D01*
G01X723101Y1672430D02*
X716901D01*
G01X714327Y1677604D02*
X717527D01*
G01X714327Y1683804D02*
Y1677604D01*
G01X717527Y1683804D02*
X714327D01*
G01X717527Y1677604D02*
Y1683804D01*
G01X720032Y1672783D02*
X723232D01*
G01X720032Y1678983D02*
Y1672783D01*
G01X723232Y1678983D02*
X720032D01*
G01X726943Y-5731D02*
Y-22011D01*
X736543D01*
Y-5731D01*
X726943D01*
G01X739196Y56645D02*
X735996D01*
G01D02*
Y50445D01*
G01D02*
X739196D01*
G01X735243D02*
Y56645D01*
G01D02*
X732043D01*
G01D02*
Y50445D01*
G01D02*
X735243D01*
G01X726245D02*
Y56645D01*
G01D02*
X723045D01*
G01D02*
Y50445D01*
G01D02*
X726245D01*
G01X730894D02*
Y56645D01*
G01D02*
X727694D01*
G01D02*
Y50445D01*
G01D02*
X730894D01*
G01X724266Y90033D02*
Y96233D01*
G01X725600Y77129D02*
Y83329D01*
G01X737057Y379128D02*
Y385328D01*
G01D02*
X733857D01*
G01D02*
Y379128D01*
G01D02*
X737057D01*
G01X730100Y382462D02*
X723900D01*
G01D02*
Y379262D01*
G01D02*
X730100D01*
G01D02*
Y382462D01*
G01X737100Y391762D02*
Y397962D01*
G01D02*
X733900D01*
G01D02*
Y391762D01*
G01D02*
X737100D01*
G01X733100D02*
Y397962D01*
G01D02*
X729900D01*
G01D02*
Y391762D01*
G01D02*
X733100D01*
G01X725100D02*
Y397962D01*
G01X725900D02*
Y391762D01*
G01D02*
X729100D01*
G01D02*
Y397962D01*
G01D02*
X725900D01*
G01X731752Y435744D02*
Y441944D01*
G01D02*
X728552D01*
G01D02*
Y435744D01*
G01D02*
X731752D01*
G01X733936Y449429D02*
Y443979D01*
G01D02*
X736236D01*
G01D02*
Y449429D01*
G01X724568D02*
Y443979D01*
G01D02*
X726868D01*
G01D02*
Y449429D01*
G01X729002D02*
Y443979D01*
G01D02*
X731302D01*
G01D02*
Y449429D01*
G01X724568Y437681D02*
X726868D01*
G01D02*
Y443131D01*
G01D02*
X724568D01*
G01D02*
Y437681D01*
G01X733936Y443131D02*
Y440831D01*
G01D02*
X739386D01*
G01Y443131D02*
X733936D01*
G01X723792Y437681D02*
Y443131D01*
G01X737086Y465099D02*
Y459649D01*
G01D02*
X739386D01*
G01X736236Y449429D02*
X733936D01*
G01X726868D02*
X724568D01*
G01X731302D02*
X729002D01*
G01X724568Y468248D02*
Y462798D01*
G01D02*
X726868D01*
G01D02*
Y468248D01*
G01X733936Y465099D02*
Y459649D01*
G01D02*
X736236D01*
G01D02*
Y465099D01*
G01X729002Y468248D02*
Y462798D01*
G01D02*
X731302D01*
G01D02*
Y468248D01*
G01X733936Y453994D02*
Y451694D01*
G01D02*
X739386D01*
G01Y453994D02*
X733936D01*
G01X729002Y456499D02*
X731302D01*
G01D02*
Y461949D01*
G01D02*
X729002D01*
G01D02*
Y456499D01*
G01X724568D02*
X726868D01*
G01D02*
Y461949D01*
G01D02*
X724568D01*
G01D02*
Y456499D01*
G01X723719Y462798D02*
Y465098D01*
G01X726868Y451694D02*
Y453994D01*
G01X739386Y465099D02*
X737086D01*
G01X726868Y468248D02*
X724568D01*
G01X736236Y465099D02*
X733936D01*
G01X731302Y468248D02*
X729002D01*
G01X738039Y502444D02*
X734839D01*
G01D02*
Y496244D01*
G01D02*
X738039D01*
G01X723052Y502444D02*
Y496244D01*
G01D02*
X726252D01*
G01D02*
Y502444D01*
G01D02*
X723052D01*
G01X739210Y516754D02*
X736010D01*
G01D02*
Y510554D01*
G01D02*
X739210D01*
G01X728024Y528994D02*
Y522794D01*
G01D02*
X731224D01*
G01D02*
Y528994D01*
G01X734760Y521341D02*
Y527541D01*
G01X731560Y521341D02*
X734760D01*
G01X731560Y527541D02*
Y521341D01*
G01X734791Y521039D02*
X731591D01*
G01X734791Y514839D02*
Y521039D01*
G01X731591Y514839D02*
X734791D01*
G01X731591Y521039D02*
Y514839D01*
G01X731224Y528994D02*
X728024D01*
G01X723509Y523652D02*
Y529852D01*
G01X727024Y529838D02*
X723824D01*
G01X727024Y523638D02*
Y529838D01*
G01X723824Y523638D02*
X727024D01*
G01X723824Y529838D02*
Y523638D01*
G01X734760Y527541D02*
X731560D01*
G01X737603Y570845D02*
Y567645D01*
G01D02*
X743803D01*
G01X737400Y565600D02*
Y562400D01*
G01X743600Y565600D02*
X737400D01*
G01Y562400D02*
X743600D01*
G01X729157Y564169D02*
X732835D01*
G01X727657Y566169D02*
X729157Y564169D01*
G01X725843D02*
X727657Y566169D01*
G01X732835Y564169D02*
Y572831D01*
G01X743803Y570845D02*
X737603D01*
G01X727927Y583636D02*
Y580436D01*
G01X734127D02*
Y583636D01*
G01X727927Y580436D02*
X734127D01*
G01X737456Y574771D02*
Y571571D01*
G01X743656Y574771D02*
X737456D01*
G01Y571571D02*
X743656D01*
G01X734127Y583636D02*
X727927D01*
G01X732390Y753366D02*
Y750166D01*
G01X738590Y753366D02*
X732390D01*
G01Y750166D02*
X738590D01*
G01X728899Y755505D02*
Y761505D01*
G01X730457Y755505D02*
X742457D01*
G01X730457Y761505D02*
Y755505D01*
G01X742457Y761505D02*
X730457D01*
G01X723023Y762166D02*
Y765366D01*
G01X723024Y765700D02*
Y768900D01*
G01X736332Y762166D02*
X742532D01*
G01X736332Y765366D02*
Y762166D01*
G01X742532Y765366D02*
X736332D01*
G01Y768866D02*
Y765666D01*
G01X742532Y768866D02*
X736332D01*
G01Y765666D02*
X742532D01*
G01X732215Y1325537D02*
X735315D01*
Y1326457D01*
X735160Y1326764D01*
X734798Y1326994D01*
X734385Y1327071D01*
X733972Y1326994D01*
X733662Y1326802D01*
X733507Y1326457D01*
Y1325537D01*
G01X735057Y1330247D02*
X735212Y1330017D01*
X735315Y1329749D01*
Y1329442D01*
X735160Y1329097D01*
X734902Y1328829D01*
X734592Y1328637D01*
X734075Y1328484D01*
X733610Y1328446D01*
X733145Y1328522D01*
X732835Y1328637D01*
X732525Y1328867D01*
X732318Y1329136D01*
X732215Y1329404D01*
Y1329672D01*
X732318Y1329941D01*
X732473Y1330171D01*
X732680Y1330362D01*
G01Y1331661D02*
X732422Y1331891D01*
X732267Y1332159D01*
X732215Y1332504D01*
X732318Y1332849D01*
X732525Y1333117D01*
X732887Y1333309D01*
X733300Y1333347D01*
X733713Y1333271D01*
X733972Y1333079D01*
X734178Y1332811D01*
X734230Y1332542D01*
X734178Y1332274D01*
X733972Y1331929D01*
X735315Y1332044D01*
Y1333079D01*
G01X734798Y1334876D02*
X735108Y1335106D01*
X735263Y1335374D01*
X735315Y1335681D01*
X735212Y1336064D01*
X734953Y1336332D01*
X734643Y1336409D01*
X734333Y1336371D01*
X734075Y1336217D01*
X733558Y1335451D01*
X733197Y1335106D01*
X732680Y1334876D01*
X732215Y1334799D01*
Y1336409D01*
G01X732680Y1337861D02*
X732422Y1338091D01*
X732267Y1338359D01*
X732215Y1338704D01*
X732318Y1339049D01*
X732525Y1339317D01*
X732887Y1339509D01*
X733300Y1339547D01*
X733713Y1339471D01*
X733972Y1339279D01*
X734178Y1339011D01*
X734230Y1338742D01*
X734178Y1338474D01*
X733972Y1338129D01*
X735315Y1338244D01*
Y1339279D01*
G01X729129Y1337270D02*
Y1372966D01*
G01X732271Y1341488D02*
X738271D01*
G01X732271Y1353488D02*
Y1341488D01*
G01X738271Y1353488D02*
X732271D01*
G01X742426Y1376127D02*
Y1378553D01*
G01X729313Y1388730D02*
Y1376730D01*
G01X735313D02*
Y1388730D01*
G01X729313Y1376730D02*
X735313D01*
G01X727198D02*
Y1388730D01*
G01X736924Y1390546D02*
X740124D01*
G01X736924Y1396746D02*
Y1390546D01*
G01X740124Y1396746D02*
X736924D01*
G01X735313Y1388730D02*
X729313D01*
G01X727900Y1391846D02*
Y1403846D01*
G01X735141Y1411138D02*
X723141D01*
G01X735141Y1405138D02*
Y1411138D01*
G01X723141Y1405138D02*
X735141D01*
G01X723141Y1411138D02*
Y1405138D01*
G01X735000Y1412500D02*
Y1418500D01*
G01X723000Y1412500D02*
X735000D01*
G01X723000Y1418500D02*
Y1412500D01*
G01X735000Y1418500D02*
X723000D01*
G01Y1433150D02*
Y1427150D01*
X735000D01*
Y1433150D01*
X723000D01*
G01X728850Y1564733D02*
Y1567933D01*
G01X723550Y1579258D02*
Y1585458D01*
G01X724221Y1572683D02*
Y1575883D01*
G01X724850Y1589153D02*
Y1592353D01*
G01X723490Y1600137D02*
Y1606337D01*
G01X722792Y1627311D02*
Y1630511D01*
G01Y1631361D02*
Y1634561D01*
G01X723991Y1642397D02*
X730191D01*
G01D02*
Y1645597D01*
G01D02*
X723991D01*
G01D02*
Y1642397D01*
G01X730191Y1649597D02*
X723991D01*
G01D02*
Y1646397D01*
G01D02*
X730191D01*
G01D02*
Y1649597D01*
G01Y1654597D02*
X723991D01*
G01D02*
Y1651397D01*
G01D02*
X730191D01*
G01D02*
Y1654597D01*
G01X734016Y1641644D02*
Y1656356D01*
G01X745984Y1641644D02*
X734016D01*
G01X727902Y1665338D02*
X724702D01*
G01X727902Y1659138D02*
Y1665338D01*
G01X724702Y1659138D02*
X727902D01*
G01X724702Y1665338D02*
Y1659138D01*
G01X733400Y1661400D02*
X739600D01*
G01X733400Y1664600D02*
Y1661400D01*
G01X739600Y1664600D02*
X733400D01*
G01X723101Y1669230D02*
Y1672430D01*
G01X724230Y1662298D02*
Y1668498D01*
G01X731902Y1665338D02*
X728702D01*
G01X731902Y1659138D02*
Y1665338D01*
G01X728702Y1659138D02*
X731902D01*
G01X728702Y1665338D02*
Y1659138D01*
G01X734016Y1656356D02*
X745984D01*
G01X731398Y1670000D02*
X743602D01*
G01X731398Y1686000D02*
Y1670000D01*
G01X723232Y1672783D02*
Y1678983D01*
G01X730218Y1684060D02*
Y1687260D01*
G01X724018Y1684060D02*
X730218D01*
G01X724018Y1687260D02*
Y1684060D01*
G01X725642Y1671969D02*
X728842D01*
G01X725642Y1678169D02*
Y1671969D01*
G01X728842Y1678169D02*
X725642D01*
G01X728842Y1671969D02*
Y1678169D01*
G01X743602Y1686000D02*
X731398D01*
G01X736626Y1687239D02*
X742826D01*
G01X736626Y1690439D02*
Y1687239D01*
G01X742826Y1690439D02*
X736626D01*
G01X730218Y1687260D02*
X724018D01*
G01X749293Y-19501D02*
X748983Y-19309D01*
X748776Y-19079D01*
X748673Y-18811D01*
X748776Y-18504D01*
X748983Y-18274D01*
X749293Y-18044D01*
X749706Y-17967D01*
X751773D01*
G01X748673Y-15634D02*
X751773D01*
X751153Y-16094D01*
G01X748673D02*
Y-15174D01*
G01X751256Y-13262D02*
X751566Y-13032D01*
X751721Y-12764D01*
X751773Y-12457D01*
X751670Y-12074D01*
X751411Y-11806D01*
X751101Y-11729D01*
X750791Y-11767D01*
X750533Y-11921D01*
X750016Y-12687D01*
X749655Y-13032D01*
X749138Y-13262D01*
X748673Y-13339D01*
Y-11729D01*
G01X751773Y-9434D02*
X751670Y-9741D01*
X751411Y-9971D01*
X751101Y-10124D01*
X750688Y-10239D01*
X750223Y-10277D01*
X749758Y-10239D01*
X749345Y-10124D01*
X749035Y-9971D01*
X748776Y-9741D01*
X748673Y-9434D01*
X748776Y-9127D01*
X749035Y-8897D01*
X749345Y-8744D01*
X749758Y-8629D01*
X750223Y-8591D01*
X750688Y-8629D01*
X751101Y-8744D01*
X751411Y-8897D01*
X751670Y-9127D01*
X751773Y-9434D01*
G01X751078Y50445D02*
Y56645D01*
G01D02*
X747878D01*
G01D02*
Y50445D01*
G01D02*
X751078D01*
G01X747075D02*
Y56645D01*
G01D02*
X743875D01*
G01D02*
Y50445D01*
G01D02*
X747075D01*
G01X742978D02*
Y56645D01*
G01D02*
X739778D01*
G01D02*
Y50445D01*
G01D02*
X742978D01*
G01X739196D02*
Y56645D01*
G01X747563Y74429D02*
X753763D01*
G01X747563Y77629D02*
Y74429D01*
G01X753763Y77629D02*
X747563D01*
G01X755828Y278999D02*
X749628D01*
G01D02*
Y275799D01*
G01D02*
X755828D01*
G01X754636Y314345D02*
X751436D01*
G01D02*
Y308145D01*
G01D02*
X754636D01*
G01Y307345D02*
X751436D01*
G01D02*
Y301145D01*
G01D02*
X754636D01*
G01X749100Y379262D02*
Y385462D01*
G01D02*
X745900D01*
G01D02*
Y379262D01*
G01D02*
X749100D01*
G01X753100Y385462D02*
X749900D01*
G01D02*
Y379262D01*
G01D02*
X753100D01*
G01X745057Y379128D02*
Y385328D01*
G01D02*
X741857D01*
G01D02*
Y379128D01*
G01D02*
X745057D01*
G01X741057D02*
Y385328D01*
G01D02*
X737857D01*
G01D02*
Y379128D01*
G01D02*
X741057D01*
G01X745100Y391762D02*
Y397962D01*
G01D02*
X741900D01*
G01D02*
Y391762D01*
G01D02*
X745100D01*
G01X741252Y391744D02*
Y397944D01*
G01D02*
X738052D01*
G01D02*
Y391744D01*
G01D02*
X741252D01*
G01X753100Y397962D02*
X749900D01*
G01D02*
Y391762D01*
G01D02*
X753100D01*
G01X745900Y397962D02*
Y391762D01*
G01D02*
X749100D01*
G01D02*
Y397962D01*
G01D02*
X745900D01*
G01X745686Y447129D02*
Y449429D01*
G01X740236D02*
Y447129D01*
G01D02*
X745686D01*
G01X739386Y440831D02*
Y443131D01*
G01X745686Y456499D02*
Y458799D01*
G01D02*
X740236D01*
G01D02*
Y456499D01*
G01D02*
X745686D01*
G01Y451694D02*
Y453994D01*
G01D02*
X740236D01*
G01D02*
Y451694D01*
G01D02*
X745686D01*
G01X739386Y459649D02*
Y465099D01*
G01X745686Y449429D02*
X740236D01*
G01X739386Y451694D02*
Y453994D01*
G01X753572Y502556D02*
X750372D01*
G01D02*
Y496356D01*
G01D02*
X753572D01*
G01X746039Y496244D02*
Y502444D01*
G01D02*
X742839D01*
G01D02*
Y496244D01*
G01D02*
X746039D01*
G01X738039D02*
Y502444D01*
G01X742039Y496244D02*
Y502444D01*
G01D02*
X738839D01*
G01D02*
Y496244D01*
G01D02*
X742039D01*
G01X746407Y496640D02*
X749607D01*
G01X746407Y502840D02*
Y496640D01*
G01X749607Y502840D02*
X746407D01*
G01X749607Y496640D02*
Y502840D01*
G01X739210Y510554D02*
Y516754D01*
G01X744556Y534924D02*
Y541124D01*
G01X741356D02*
Y534924D01*
G01D02*
X744556D01*
G01X746882Y556110D02*
Y549910D01*
G01D02*
X750082D01*
G01D02*
Y556110D01*
G01X744556Y541124D02*
X741356D01*
G01X743803Y567645D02*
Y570845D01*
G01X750082Y556110D02*
X746882D01*
G01X743600Y562400D02*
Y565600D01*
G01X750656Y571571D02*
Y574771D01*
G01X744456Y571571D02*
X750656D01*
G01X744456Y574771D02*
Y571571D01*
G01X750656Y574771D02*
X744456D01*
G01X743656Y571571D02*
Y574771D01*
G01X786502Y605413D02*
G02I-22900J0D01*
G01X751390Y749666D02*
X757590D01*
G01X751390Y752866D02*
Y749666D01*
G01X757590Y752866D02*
X751390D01*
G01X738590Y750166D02*
Y753366D01*
G01X758599Y761505D02*
X746599D01*
G01Y755505D02*
X758599D01*
G01X746599Y761505D02*
Y755505D01*
G01X742457D02*
Y761505D01*
G01X746524Y762166D02*
X752724D01*
G01X746524Y765366D02*
Y762166D01*
G01X752724Y765366D02*
X746524D01*
G01Y768900D02*
Y765700D01*
G01X752724Y768900D02*
X746524D01*
G01Y765700D02*
X752724D01*
G01X742532Y762166D02*
Y765366D01*
G01Y765666D02*
Y768866D01*
G01X746524Y769500D02*
X752724D01*
Y772700D01*
X746524D01*
Y769500D01*
G01X751774Y959366D02*
Y962566D01*
G01X745574Y959366D02*
X751774D01*
G01X745574Y962566D02*
Y959366D01*
G01X751774Y962566D02*
X745574D01*
G01X751418Y1331012D02*
X753658D01*
G01X752445Y1329387D02*
Y1332637D01*
G01X743883Y1337180D02*
X761599D01*
G01X743883Y1372876D02*
Y1337180D01*
G01X738271Y1341488D02*
Y1353488D01*
G01X761599Y1372876D02*
X743883D01*
G01X742241Y1384223D02*
X745441D01*
G01X742241Y1390423D02*
Y1384223D01*
G01X745441D02*
Y1390423D01*
G01X740124Y1390546D02*
Y1396746D01*
G01X745441Y1390423D02*
X742241D01*
G01X754610Y1580698D02*
X751410D01*
G01Y1574498D02*
X754610D01*
G01X751410Y1580698D02*
Y1574498D01*
G01X754610Y1588698D02*
X751410D01*
G01Y1582498D02*
X754610D01*
G01X751410Y1588698D02*
Y1582498D01*
G01X751798Y1640341D02*
X749576D01*
X749111Y1640494D01*
X748801Y1640801D01*
X748698Y1641184D01*
X748801Y1641567D01*
X749111Y1641874D01*
X749576Y1642027D01*
X751798D01*
G01X748698Y1644284D02*
X748750Y1644552D01*
X748905Y1644859D01*
X749163Y1645051D01*
X749525Y1645127D01*
X749886Y1645051D01*
X750196Y1644821D01*
X750351Y1644476D01*
Y1644092D01*
X750455Y1643862D01*
X750713Y1643671D01*
X751075Y1643594D01*
X751436Y1643709D01*
X751695Y1643977D01*
X751798Y1644284D01*
X751695Y1644591D01*
X751436Y1644859D01*
X751075Y1644974D01*
X750713Y1644897D01*
X750455Y1644706D01*
X750351Y1644476D01*
Y1644092D01*
X750196Y1643747D01*
X749886Y1643517D01*
X749525Y1643441D01*
X749163Y1643517D01*
X748905Y1643709D01*
X748750Y1644016D01*
X748698Y1644284D01*
G01X751798Y1647384D02*
X751695Y1647077D01*
X751436Y1646847D01*
X751126Y1646694D01*
X750713Y1646579D01*
X750248Y1646541D01*
X749783Y1646579D01*
X749370Y1646694D01*
X749060Y1646847D01*
X748801Y1647077D01*
X748698Y1647384D01*
X748801Y1647691D01*
X749060Y1647921D01*
X749370Y1648074D01*
X749783Y1648189D01*
X750248Y1648227D01*
X750713Y1648189D01*
X751126Y1648074D01*
X751436Y1647921D01*
X751695Y1647691D01*
X751798Y1647384D01*
G01Y1650484D02*
X751695Y1650177D01*
X751436Y1649947D01*
X751126Y1649794D01*
X750713Y1649679D01*
X750248Y1649641D01*
X749783Y1649679D01*
X749370Y1649794D01*
X749060Y1649947D01*
X748801Y1650177D01*
X748698Y1650484D01*
X748801Y1650791D01*
X749060Y1651021D01*
X749370Y1651174D01*
X749783Y1651289D01*
X750248Y1651327D01*
X750713Y1651289D01*
X751126Y1651174D01*
X751436Y1651021D01*
X751695Y1650791D01*
X751798Y1650484D01*
G01X749163Y1652741D02*
X748905Y1652971D01*
X748750Y1653239D01*
X748698Y1653584D01*
X748801Y1653929D01*
X749008Y1654197D01*
X749370Y1654389D01*
X749783Y1654427D01*
X750196Y1654351D01*
X750455Y1654159D01*
X750661Y1653891D01*
X750713Y1653622D01*
X750661Y1653354D01*
X750455Y1653009D01*
X751798Y1653124D01*
Y1654159D01*
G01X745984Y1656356D02*
Y1641644D01*
G01X739600Y1661400D02*
Y1664600D01*
G01X746600Y1661400D02*
Y1664600D01*
G01X740400Y1661400D02*
X746600D01*
G01X740400Y1664600D02*
Y1661400D01*
G01X746600Y1664600D02*
X740400D01*
G01X743602Y1670000D02*
Y1676000D01*
G01Y1680000D02*
Y1686000D01*
G01X740500Y1678000D02*
X743602Y1680000D01*
G01Y1676000D02*
X740500Y1678000D01*
G01X742826Y1687239D02*
Y1690439D01*
G01X752469Y1701173D02*
X752239Y1700811D01*
X751933Y1700605D01*
X751588Y1700553D01*
X751281Y1700605D01*
X750974Y1700863D01*
X750783Y1701173D01*
X750744Y1701483D01*
X750821Y1701845D01*
X751089Y1702103D01*
X751358Y1702206D01*
X751703D01*
G01X751358D02*
X751128Y1702361D01*
X750936Y1702620D01*
X750859Y1702930D01*
X750936Y1703240D01*
X751128Y1703498D01*
X751473Y1703653D01*
X751818Y1703601D01*
X752163Y1703395D01*
G01X751368Y1720840D02*
Y1723940D01*
X751828Y1723320D01*
G01Y1720840D02*
X750908D01*
G01X753763Y74429D02*
Y77629D01*
G01X755828Y275799D02*
Y278999D01*
G01X758977Y274999D02*
X752777D01*
G01D02*
Y271799D01*
G01D02*
X758977D01*
G01D02*
Y274999D01*
G01X762139Y288232D02*
X755939D01*
G01D02*
Y285032D01*
G01D02*
X762139D01*
G01D02*
Y288232D01*
G01X758638Y312660D02*
Y318860D01*
G01X755438D02*
Y312660D01*
G01D02*
X758638D01*
G01X754636Y308145D02*
Y314345D01*
G01Y301145D02*
Y307345D01*
G01X758638Y318860D02*
X755438D01*
G01X753100Y379262D02*
Y385462D01*
G01X761900D02*
Y379262D01*
G01D02*
X765100D01*
G01D02*
Y385462D01*
G01D02*
X761900D01*
G01X765900D02*
Y379262D01*
G01D02*
X769100D01*
G01Y385462D02*
X765900D01*
G01X753100Y391762D02*
Y397962D01*
G01X757100Y391762D02*
Y397962D01*
G01D02*
X753900D01*
G01D02*
Y391762D01*
G01D02*
X757100D01*
G01X757900Y397962D02*
Y391762D01*
G01D02*
X761100D01*
G01D02*
Y397962D01*
G01D02*
X757900D01*
G01X769100D02*
X765900D01*
G01D02*
Y391762D01*
G01D02*
X769100D01*
G01X761900Y397962D02*
Y391762D01*
G01D02*
X765100D01*
G01D02*
Y397962D01*
G01D02*
X761900D01*
G01X762252Y496244D02*
Y502444D01*
G01D02*
X759052D01*
G01D02*
Y496244D01*
G01D02*
X762252D01*
G01X758252D02*
Y502444D01*
G01D02*
X755052D01*
G01D02*
Y496244D01*
G01D02*
X758252D01*
G01X765752D02*
Y502444D01*
G01D02*
X762552D01*
G01D02*
Y496244D01*
G01D02*
X765752D01*
G01X766152Y497744D02*
X772352D01*
G01Y500944D02*
X766152D01*
G01D02*
Y497744D01*
G01X753572Y496356D02*
Y502556D01*
G01X758917Y555984D02*
Y549784D01*
G01D02*
X762117D01*
G01D02*
Y555984D01*
G01X770100Y544962D02*
X766900D01*
G01D02*
Y538762D01*
G01D02*
X770100D01*
G01X762117Y555984D02*
X758917D01*
G01X757590Y749666D02*
Y752866D01*
G01X758599Y755505D02*
Y761505D01*
G01X760158Y755505D02*
X772158D01*
G01X760158Y761505D02*
Y755505D01*
G01X772158Y761505D02*
X760158D01*
G01X752724Y762166D02*
Y765366D01*
G01Y765700D02*
Y768900D01*
G01X766033Y762166D02*
X772233D01*
G01X766033Y765366D02*
Y762166D01*
G01X772233Y765366D02*
X766033D01*
G01Y768866D02*
Y765666D01*
G01X772233Y768866D02*
X766033D01*
G01Y765666D02*
X772233D01*
G01X761599Y1337180D02*
Y1372876D01*
G01X763455Y1340860D02*
X769455D01*
G01X763455Y1352860D02*
Y1340860D01*
G01X769455Y1352860D02*
X763455D01*
G01X753980Y1388830D02*
Y1376830D01*
G01X759980D02*
Y1388830D01*
G01X753980Y1376830D02*
X759980D01*
G01X762095Y1388830D02*
Y1376830D01*
G01D02*
X768095D01*
G01X759980Y1388830D02*
X753980D01*
G01X768095D02*
X762095D01*
G01X760919Y1391946D02*
Y1403946D01*
G01X754919Y1391946D02*
X760919D01*
G01X754919Y1403946D02*
Y1391946D01*
G01X760919Y1403946D02*
X754919D01*
G01X754610Y1574498D02*
Y1580698D01*
G01X760750Y1579708D02*
X763950D01*
G01X760750Y1585908D02*
Y1579708D01*
G01X763950D02*
Y1585908D01*
G01X754610Y1582498D02*
Y1588698D01*
G01X763950Y1585908D02*
X760750D01*
G01X763073Y1671778D02*
X760851D01*
X760386Y1671931D01*
X760076Y1672238D01*
X759973Y1672621D01*
X760076Y1673004D01*
X760386Y1673311D01*
X760851Y1673464D01*
X763073D01*
G01X759973Y1675721D02*
X760025Y1675989D01*
X760180Y1676296D01*
X760438Y1676488D01*
X760800Y1676564D01*
X761161Y1676488D01*
X761471Y1676258D01*
X761626Y1675913D01*
Y1675529D01*
X761730Y1675299D01*
X761988Y1675108D01*
X762350Y1675031D01*
X762711Y1675146D01*
X762970Y1675414D01*
X763073Y1675721D01*
X762970Y1676028D01*
X762711Y1676296D01*
X762350Y1676411D01*
X761988Y1676334D01*
X761730Y1676143D01*
X761626Y1675913D01*
Y1675529D01*
X761471Y1675184D01*
X761161Y1674954D01*
X760800Y1674878D01*
X760438Y1674954D01*
X760180Y1675146D01*
X760025Y1675453D01*
X759973Y1675721D01*
G01X763073Y1678821D02*
X762970Y1678514D01*
X762711Y1678284D01*
X762401Y1678131D01*
X761988Y1678016D01*
X761523Y1677978D01*
X761058Y1678016D01*
X760645Y1678131D01*
X760335Y1678284D01*
X760076Y1678514D01*
X759973Y1678821D01*
X760076Y1679128D01*
X760335Y1679358D01*
X760645Y1679511D01*
X761058Y1679626D01*
X761523Y1679664D01*
X761988Y1679626D01*
X762401Y1679511D01*
X762711Y1679358D01*
X762970Y1679128D01*
X763073Y1678821D01*
G01Y1681921D02*
X762970Y1681614D01*
X762711Y1681384D01*
X762401Y1681231D01*
X761988Y1681116D01*
X761523Y1681078D01*
X761058Y1681116D01*
X760645Y1681231D01*
X760335Y1681384D01*
X760076Y1681614D01*
X759973Y1681921D01*
X760076Y1682228D01*
X760335Y1682458D01*
X760645Y1682611D01*
X761058Y1682726D01*
X761523Y1682764D01*
X761988Y1682726D01*
X762401Y1682611D01*
X762711Y1682458D01*
X762970Y1682228D01*
X763073Y1681921D01*
G01X761265Y1684293D02*
X761626Y1684561D01*
X761833Y1684791D01*
X761936Y1685098D01*
X761833Y1685366D01*
X761626Y1685558D01*
X761316Y1685711D01*
X760955Y1685749D01*
X760645Y1685711D01*
X760335Y1685558D01*
X760076Y1685328D01*
X759973Y1685059D01*
X760076Y1684753D01*
X760386Y1684484D01*
X760851Y1684331D01*
X761368Y1684293D01*
X762040Y1684369D01*
X762401Y1684484D01*
X762763Y1684676D01*
X763021Y1684944D01*
X763073Y1685213D01*
X762970Y1685481D01*
X762711Y1685673D01*
G01X837186Y204724D02*
G02I-31496J0D01*
G01X787918Y267856D02*
Y265634D01*
X787765Y265169D01*
X787458Y264859D01*
X787075Y264756D01*
X786692Y264859D01*
X786385Y265169D01*
X786232Y265634D01*
Y267856D01*
G01X784703Y267339D02*
X784473Y267649D01*
X784205Y267804D01*
X783898Y267856D01*
X783515Y267753D01*
X783247Y267494D01*
X783170Y267184D01*
X783208Y266874D01*
X783362Y266616D01*
X784128Y266099D01*
X784473Y265738D01*
X784703Y265221D01*
X784780Y264756D01*
X783170D01*
G01X781603Y267339D02*
X781373Y267649D01*
X781105Y267804D01*
X780798Y267856D01*
X780415Y267753D01*
X780147Y267494D01*
X780070Y267184D01*
X780108Y266874D01*
X780262Y266616D01*
X781028Y266099D01*
X781373Y265738D01*
X781603Y265221D01*
X781680Y264756D01*
X780070D01*
G01X778618Y265376D02*
X778388Y265014D01*
X778082Y264808D01*
X777737Y264756D01*
X777430Y264808D01*
X777123Y265066D01*
X776932Y265376D01*
X776893Y265686D01*
X776970Y266048D01*
X777238Y266306D01*
X777507Y266409D01*
X777852D01*
G01X777507D02*
X777277Y266564D01*
X777085Y266823D01*
X777008Y267133D01*
X777085Y267443D01*
X777277Y267701D01*
X777622Y267856D01*
X777967Y267804D01*
X778312Y267598D01*
G01X773495Y289196D02*
Y269096D01*
G01D02*
X789295D01*
G01X768577Y313958D02*
Y293858D01*
G01D02*
X784377D01*
G01X783645Y289196D02*
X781395Y286946D01*
G01D02*
X779145Y289196D01*
G01D02*
X773495D01*
G01X784170Y318508D02*
Y316286D01*
X784017Y315821D01*
X783710Y315511D01*
X783327Y315408D01*
X782944Y315511D01*
X782637Y315821D01*
X782484Y316286D01*
Y318508D01*
G01X780955Y316700D02*
X780687Y317061D01*
X780457Y317268D01*
X780150Y317371D01*
X779882Y317268D01*
X779690Y317061D01*
X779537Y316751D01*
X779499Y316390D01*
X779537Y316080D01*
X779690Y315770D01*
X779920Y315511D01*
X780189Y315408D01*
X780495Y315511D01*
X780764Y315821D01*
X780917Y316286D01*
X780955Y316803D01*
X780879Y317475D01*
X780764Y317836D01*
X780572Y318198D01*
X780304Y318456D01*
X780035Y318508D01*
X779767Y318405D01*
X779575Y318146D01*
G01X777204Y315408D02*
X777127Y316080D01*
X777012Y316648D01*
X776859Y317165D01*
X776667Y317733D01*
X776360Y318508D01*
X777894D01*
G01X784377Y313958D02*
X778727D01*
G01D02*
X776477Y311708D01*
G01D02*
X774227Y313958D01*
G01D02*
X768577D01*
G01X769100Y379262D02*
Y385462D01*
G01Y391762D02*
Y397962D01*
G01X780752Y412944D02*
X774552D01*
G01D02*
Y409744D01*
G01D02*
X780752D01*
G01D02*
Y412944D01*
G01Y408944D02*
X774552D01*
G01D02*
Y405744D01*
G01D02*
X780752D01*
G01D02*
Y408944D01*
G01Y416944D02*
X774552D01*
G01D02*
Y413744D01*
G01D02*
X780752D01*
G01D02*
Y416944D01*
G01X773552Y420944D02*
Y417744D01*
G01D02*
X779752D01*
G01D02*
Y420944D01*
G01D02*
X773552D01*
G01Y421744D02*
X779752D01*
G01D02*
Y424944D01*
G01D02*
X773552D01*
G01D02*
Y421744D01*
G01X779752Y428944D02*
X773552D01*
G01D02*
Y425744D01*
G01D02*
X779752D01*
G01D02*
Y428944D01*
G01X784352Y440104D02*
X778152D01*
G01D02*
Y436904D01*
G01D02*
X784352D01*
G01X778702Y448164D02*
X772502D01*
G01D02*
Y444964D01*
G01D02*
X778702D01*
G01D02*
Y448164D01*
G01X778600Y440900D02*
Y444100D01*
G01X772400Y440900D02*
X778600D01*
G01X772400Y444100D02*
Y440900D01*
G01X778600Y444100D02*
X772400D01*
G01X785574Y460478D02*
X782374D01*
G01D02*
Y454278D01*
G01D02*
X785574D01*
G01X773552Y461744D02*
X779752D01*
G01D02*
Y464944D01*
G01X773552D02*
Y461744D01*
G01X779752Y464944D02*
X773552D01*
G01Y477744D02*
X779752D01*
G01D02*
Y480944D01*
G01X773552D02*
Y477744D01*
G01Y473744D02*
X779752D01*
G01D02*
Y476944D01*
G01D02*
X773552D01*
G01D02*
Y473744D01*
G01Y469744D02*
X779752D01*
G01D02*
Y472944D01*
G01D02*
X773552D01*
G01D02*
Y469744D01*
G01X776252Y481744D02*
X782452D01*
G01Y484944D02*
X776252D01*
G01D02*
Y481744D01*
G01X779752Y480944D02*
X773552D01*
G01X773852Y490044D02*
X780052D01*
G01D02*
Y493244D01*
G01D02*
X773852D01*
G01D02*
Y490044D01*
G01X773552Y497744D02*
X779752D01*
G01D02*
Y500944D01*
G01D02*
X773552D01*
G01D02*
Y497744D01*
G01Y493744D02*
X779752D01*
G01D02*
Y496944D01*
G01D02*
X773552D01*
G01D02*
Y493744D01*
G01X772352Y497744D02*
Y500944D01*
G01X770100Y538762D02*
Y544962D01*
G01X782870Y545288D02*
X780648D01*
X780183Y545441D01*
X779873Y545748D01*
X779770Y546131D01*
X779873Y546514D01*
X780183Y546821D01*
X780648Y546974D01*
X782870D01*
G01X779770Y549231D02*
X779822Y549499D01*
X779977Y549806D01*
X780235Y549998D01*
X780597Y550074D01*
X780958Y549998D01*
X781268Y549768D01*
X781423Y549423D01*
Y549039D01*
X781527Y548809D01*
X781785Y548618D01*
X782147Y548541D01*
X782508Y548656D01*
X782767Y548924D01*
X782870Y549231D01*
X782767Y549538D01*
X782508Y549806D01*
X782147Y549921D01*
X781785Y549844D01*
X781527Y549653D01*
X781423Y549423D01*
Y549039D01*
X781268Y548694D01*
X780958Y548464D01*
X780597Y548388D01*
X780235Y548464D01*
X779977Y548656D01*
X779822Y548963D01*
X779770Y549231D01*
G01X782870Y552331D02*
X782767Y552024D01*
X782508Y551794D01*
X782198Y551641D01*
X781785Y551526D01*
X781320Y551488D01*
X780855Y551526D01*
X780442Y551641D01*
X780132Y551794D01*
X779873Y552024D01*
X779770Y552331D01*
X779873Y552638D01*
X780132Y552868D01*
X780442Y553021D01*
X780855Y553136D01*
X781320Y553174D01*
X781785Y553136D01*
X782198Y553021D01*
X782508Y552868D01*
X782767Y552638D01*
X782870Y552331D01*
G01Y555431D02*
X782767Y555124D01*
X782508Y554894D01*
X782198Y554741D01*
X781785Y554626D01*
X781320Y554588D01*
X780855Y554626D01*
X780442Y554741D01*
X780132Y554894D01*
X779873Y555124D01*
X779770Y555431D01*
X779873Y555738D01*
X780132Y555968D01*
X780442Y556121D01*
X780855Y556236D01*
X781320Y556274D01*
X781785Y556236D01*
X782198Y556121D01*
X782508Y555968D01*
X782767Y555738D01*
X782870Y555431D01*
G01X779770Y558991D02*
X782870D01*
X780648Y557573D01*
Y559489D01*
G01X779400Y564900D02*
X782600D01*
G01X779400Y571100D02*
Y564900D01*
G01X782600Y571100D02*
X779400D01*
G01X772158Y755505D02*
Y761505D01*
G01X788300D02*
X776300D01*
G01Y755505D02*
X788300D01*
G01X776300Y761505D02*
Y755505D01*
G01X776375Y762166D02*
X782575D01*
G01X776375Y765366D02*
Y762166D01*
G01X782575Y765366D02*
X776375D01*
G01X772233Y762166D02*
Y765366D01*
G01Y765666D02*
Y768866D01*
G01X776225Y768900D02*
Y765700D01*
G01X782425Y768900D02*
X776225D01*
G01Y765700D02*
X782425D01*
G01X776225Y769500D02*
X782425D01*
Y772700D01*
X776225D01*
Y769500D01*
G01X781475Y959366D02*
Y962566D01*
G01X775275Y959366D02*
X781475D01*
G01X775275Y962566D02*
Y959366D01*
G01X781475Y962566D02*
X775275D01*
G01X782280Y1297259D02*
Y1309259D01*
G01X776280Y1297259D02*
X782280D01*
G01X776280Y1309259D02*
Y1297259D01*
G01X782280Y1309259D02*
X776280D01*
G01X770235Y1325617D02*
X773335D01*
Y1326537D01*
X773180Y1326844D01*
X772818Y1327074D01*
X772405Y1327151D01*
X771992Y1327074D01*
X771682Y1326882D01*
X771527Y1326537D01*
Y1325617D01*
G01X773077Y1330327D02*
X773232Y1330097D01*
X773335Y1329829D01*
Y1329522D01*
X773180Y1329177D01*
X772922Y1328909D01*
X772612Y1328717D01*
X772095Y1328564D01*
X771630Y1328526D01*
X771165Y1328602D01*
X770855Y1328717D01*
X770545Y1328947D01*
X770338Y1329216D01*
X770235Y1329484D01*
Y1329752D01*
X770338Y1330021D01*
X770493Y1330251D01*
X770700Y1330442D01*
G01Y1331741D02*
X770442Y1331971D01*
X770287Y1332239D01*
X770235Y1332584D01*
X770338Y1332929D01*
X770545Y1333197D01*
X770907Y1333389D01*
X771320Y1333427D01*
X771733Y1333351D01*
X771992Y1333159D01*
X772198Y1332891D01*
X772250Y1332622D01*
X772198Y1332354D01*
X771992Y1332009D01*
X773335Y1332124D01*
Y1333159D01*
G01X772818Y1334956D02*
X773128Y1335186D01*
X773283Y1335454D01*
X773335Y1335761D01*
X773232Y1336144D01*
X772973Y1336412D01*
X772663Y1336489D01*
X772353Y1336451D01*
X772095Y1336297D01*
X771578Y1335531D01*
X771217Y1335186D01*
X770700Y1334956D01*
X770235Y1334879D01*
Y1336489D01*
G01Y1338784D02*
X770287Y1339052D01*
X770442Y1339359D01*
X770700Y1339551D01*
X771062Y1339627D01*
X771423Y1339551D01*
X771733Y1339321D01*
X771888Y1338976D01*
Y1338592D01*
X771992Y1338362D01*
X772250Y1338171D01*
X772612Y1338094D01*
X772973Y1338209D01*
X773232Y1338477D01*
X773335Y1338784D01*
X773232Y1339091D01*
X772973Y1339359D01*
X772612Y1339474D01*
X772250Y1339397D01*
X771992Y1339206D01*
X771888Y1338976D01*
Y1338592D01*
X771733Y1338247D01*
X771423Y1338017D01*
X771062Y1337941D01*
X770700Y1338017D01*
X770442Y1338209D01*
X770287Y1338516D01*
X770235Y1338784D01*
G01X769455Y1340860D02*
Y1352860D01*
G01X781173Y1352396D02*
X793173D01*
G01X781173Y1358396D02*
Y1352396D01*
G01X793173Y1365296D02*
X781173D01*
G01Y1359296D02*
X793173D01*
G01X781173Y1365296D02*
Y1359296D01*
G01X793173Y1358396D02*
X781173D01*
G01X768095Y1376830D02*
Y1388830D01*
G01X768908Y1388684D02*
Y1376684D01*
G01X774908D02*
Y1388684D01*
G01X768908Y1376684D02*
X774908D01*
G01Y1388684D02*
X768908D01*
G01X771477Y1668906D02*
Y1787213D01*
G01X1086083Y1668906D02*
X771477D01*
G01Y1787213D02*
X1086083D01*
G01X789295Y269096D02*
Y289196D01*
G01X802600Y297088D02*
X796400D01*
G01D02*
Y293888D01*
G01D02*
X802600D01*
G01X784377Y293858D02*
Y313958D01*
G01X789295Y289196D02*
X783645D01*
G01X802491Y305662D02*
X796291D01*
G01D02*
Y302462D01*
G01D02*
X802491D01*
G01X796291Y306462D02*
X802491D01*
G01Y309662D02*
X796291D01*
G01D02*
Y306462D01*
G01X784352Y436904D02*
Y440104D01*
G01X785574Y454278D02*
Y460478D01*
G01X788725Y458118D02*
Y454918D01*
G01X794925Y458118D02*
X788725D01*
G01X794925Y454918D02*
Y458118D01*
G01X788725Y454918D02*
X794925D01*
G01X788725Y462118D02*
Y458918D01*
G01X794925Y462118D02*
X788725D01*
G01X794925Y458918D02*
Y462118D01*
G01X788725Y458918D02*
X794925D01*
G01X794252Y476944D02*
X788052D01*
G01D02*
Y473744D01*
G01D02*
X794252D01*
G01D02*
Y476944D01*
G01X788052Y477744D02*
X794252D01*
G01D02*
Y480944D01*
G01X788052D02*
Y477744D01*
G01Y481744D02*
X794252D01*
G01D02*
Y484944D01*
G01D02*
X788052D01*
G01D02*
Y481744D01*
G01X782452D02*
Y484944D01*
G01X784393Y485924D02*
X790593D01*
G01Y489124D02*
X784393D01*
G01D02*
Y485924D01*
G01X790593D02*
Y489124D01*
G01X794252Y480944D02*
X788052D01*
G01X783900Y527900D02*
X787100D01*
G01X783900Y534100D02*
Y527900D01*
G01X787100Y534100D02*
X783900D01*
G01X787100Y527900D02*
Y534100D01*
G01Y534900D02*
Y541100D01*
G01X783900Y534900D02*
X787100D01*
G01X783900Y541100D02*
Y534900D01*
G01X793100Y546100D02*
X789900D01*
G01X793100Y539900D02*
Y546100D01*
G01X789900Y539900D02*
X793100D01*
G01X789900Y546100D02*
Y539900D01*
G01X787100Y541100D02*
X783900D01*
G01X787169Y550669D02*
X789500Y553000D01*
G01X787169Y547560D02*
Y550669D01*
G01X795831Y547560D02*
X787169D01*
G01X795831Y558440D02*
Y547560D01*
G01X789500Y553000D02*
X787169Y555331D01*
G01X786600Y564900D02*
Y571100D01*
G01X783400Y564900D02*
X786600D01*
G01X783400Y571100D02*
Y564900D01*
G01X782600D02*
Y571100D01*
G01X790600Y564900D02*
Y571100D01*
G01X787400Y564900D02*
X790600D01*
G01X787400Y571100D02*
Y564900D01*
G01X787169Y558440D02*
X795831D01*
G01X787169Y555331D02*
Y558440D01*
G01X786600Y571100D02*
X783400D01*
G01X790600D02*
X787400D01*
G01X792795Y753365D02*
Y750165D01*
G01X798995Y753365D02*
X792795D01*
G01Y750165D02*
X798995D01*
G01X789859Y755504D02*
X801859D01*
G01X789859Y761504D02*
Y755504D01*
G01X801859Y761504D02*
X789859D01*
G01X788300Y755505D02*
Y761505D01*
G01X782575Y762166D02*
Y765366D01*
G01X795734Y762165D02*
X801934D01*
G01X795734Y765365D02*
Y762165D01*
G01X801934Y765365D02*
X795734D01*
G01X795733Y768866D02*
Y765666D01*
G01X801933Y768866D02*
X795733D01*
G01Y765666D02*
X801933D01*
G01X782425Y765700D02*
Y768900D01*
G01X792280Y1297259D02*
X798280D01*
G01X792280Y1309259D02*
Y1297259D01*
G01X790280D02*
Y1309259D01*
G01X784280Y1297259D02*
X790280D01*
G01X784280Y1309259D02*
Y1297259D01*
G01X798280Y1309259D02*
X792280D01*
G01X790280D02*
X784280D01*
G01X792775Y1347523D02*
Y1344323D01*
G01X798975Y1347523D02*
X792775D01*
G01Y1344323D02*
X798975D01*
G01X793173Y1352396D02*
Y1358396D01*
G01Y1359296D02*
Y1365296D01*
G01X809820Y144662D02*
X806620D01*
G01X809820Y138462D02*
Y144662D01*
G01X806620Y138462D02*
X809820D01*
G01X806620Y144662D02*
Y138462D01*
G01X797420Y145862D02*
Y142662D01*
G01X803620Y145862D02*
X797420D01*
G01X803620Y142662D02*
Y145862D01*
G01X797420Y142662D02*
X803620D01*
G01X797420Y140862D02*
Y137662D01*
G01X803620Y140862D02*
X797420D01*
G01X803620Y137662D02*
Y140862D01*
G01X797420Y137662D02*
X803620D01*
G01X801777Y270221D02*
Y267021D01*
G01D02*
X807977D01*
G01D02*
Y270221D01*
G01X805464Y275220D02*
X811664D01*
G01D02*
Y278420D01*
G01D02*
X805464D01*
G01D02*
Y275220D01*
G01X805518Y282711D02*
X811718D01*
G01D02*
Y285911D01*
G01X805518D02*
Y282711D01*
G01X807977Y270221D02*
X801777D01*
G01X811718Y285911D02*
X805518D01*
G01X802600Y293888D02*
Y297088D01*
G01X805770Y314373D02*
X799570D01*
G01D02*
Y311173D01*
G01D02*
X805770D01*
G01D02*
Y314373D01*
G01X802491Y302462D02*
Y305662D01*
G01Y306462D02*
Y309662D01*
G01X804579Y505861D02*
Y502661D01*
G01X810779Y505861D02*
X804579D01*
G01X810779Y502661D02*
Y505861D01*
G01X804579Y502661D02*
X810779D01*
G01X810762Y506566D02*
Y509766D01*
G01X804562Y506566D02*
X810762D01*
G01X804562Y509766D02*
Y506566D01*
G01X810762Y509766D02*
X804562D01*
G01X798995Y750165D02*
Y753365D01*
G01X801859Y755504D02*
Y761504D01*
G01X818000D02*
X806000D01*
G01Y755504D02*
X818000D01*
G01X806000Y761504D02*
Y755504D01*
G01X808795Y762165D02*
X814995D01*
G01X808795Y765365D02*
Y762165D01*
G01X814995Y765365D02*
X808795D01*
G01X801934Y762165D02*
Y765365D01*
G01X801933Y765666D02*
Y768866D01*
G01X808795Y766065D02*
X814995D01*
G01Y769265D02*
X808795D01*
G01D02*
Y766065D01*
G01X814995Y773065D02*
X808795D01*
Y769865D01*
X814995D01*
Y773065D01*
G01X811175Y959366D02*
Y962566D01*
G01X804975Y959366D02*
X811175D01*
G01X804975Y962566D02*
Y959366D01*
G01X811175Y962566D02*
X804975D01*
G01X806280Y1297259D02*
Y1309259D01*
G01X800280Y1297259D02*
X806280D01*
G01X800280Y1309259D02*
Y1297259D01*
G01X798280D02*
Y1309259D01*
G01X806280D02*
X800280D01*
G01X799646Y1347478D02*
Y1344278D01*
G01X805846Y1347478D02*
X799646D01*
G01X805846Y1344278D02*
Y1347478D01*
G01X799646Y1344278D02*
X805846D01*
G01X798975Y1344323D02*
Y1347523D01*
G01X872736Y1420331D02*
G02I-31496J0D01*
G01X809614Y1488476D02*
Y1485276D01*
G01X815814Y1488476D02*
X809614D01*
G01Y1485276D02*
X815814D01*
G01X809614Y1489276D02*
X815814D01*
G01X809614Y1492476D02*
Y1489276D01*
G01Y1498476D02*
Y1495276D01*
G01X815814Y1498476D02*
X809614D01*
G01Y1495276D02*
X815814D01*
G01Y1492476D02*
X809614D01*
G01Y1502476D02*
Y1499276D01*
G01X815814Y1502476D02*
X809614D01*
G01Y1499276D02*
X815814D01*
G01X809614Y1504684D02*
X815814D01*
G01X809614Y1507884D02*
Y1504684D01*
G01Y1517884D02*
Y1514684D01*
G01X815814Y1517884D02*
X809614D01*
G01Y1514684D02*
X815814D01*
G01Y1507884D02*
X809614D01*
G01Y1511884D02*
Y1508684D01*
G01X815814Y1511884D02*
X809614D01*
G01Y1508684D02*
X815814D01*
G01X809614Y1518684D02*
X815814D01*
G01X809614Y1521884D02*
Y1518684D01*
G01X815814Y1521884D02*
X809614D01*
G01X807050Y1588708D02*
X803850D01*
G01Y1582508D02*
X807050D01*
G01X803850Y1588708D02*
Y1582508D01*
G01X807050D02*
Y1588708D01*
G01X817622Y-33785D02*
X817312Y-33593D01*
X817105Y-33363D01*
X817002Y-33095D01*
X817105Y-32788D01*
X817312Y-32558D01*
X817622Y-32328D01*
X818035Y-32251D01*
X820102D01*
G01X817002Y-29995D02*
X817674Y-29918D01*
X818242Y-29803D01*
X818759Y-29650D01*
X819327Y-29458D01*
X820102Y-29151D01*
Y-30685D01*
G01X818294Y-27546D02*
X818655Y-27278D01*
X818862Y-27048D01*
X818965Y-26741D01*
X818862Y-26473D01*
X818655Y-26281D01*
X818345Y-26128D01*
X817984Y-26090D01*
X817674Y-26128D01*
X817364Y-26281D01*
X817105Y-26511D01*
X817002Y-26780D01*
X817105Y-27086D01*
X817415Y-27355D01*
X817880Y-27508D01*
X818397Y-27546D01*
X819069Y-27470D01*
X819430Y-27355D01*
X819792Y-27163D01*
X820050Y-26895D01*
X820102Y-26626D01*
X819999Y-26358D01*
X819740Y-26166D01*
G01X817851Y-14815D02*
X817541Y-14623D01*
X817334Y-14393D01*
X817231Y-14125D01*
X817334Y-13818D01*
X817541Y-13588D01*
X817851Y-13358D01*
X818264Y-13281D01*
X820331D01*
G01X817231Y-10948D02*
X820331D01*
X819711Y-11408D01*
G01X817231D02*
Y-10488D01*
G01X819814Y-8576D02*
X820124Y-8346D01*
X820279Y-8078D01*
X820331Y-7771D01*
X820228Y-7388D01*
X819969Y-7120D01*
X819659Y-7043D01*
X819349Y-7081D01*
X819091Y-7235D01*
X818574Y-8001D01*
X818213Y-8346D01*
X817696Y-8576D01*
X817231Y-8653D01*
Y-7043D01*
G01Y-4748D02*
X820331D01*
X819711Y-5208D01*
G01X817231D02*
Y-4288D01*
G01X817737Y6095D02*
X817427Y6287D01*
X817220Y6517D01*
X817117Y6785D01*
X817220Y7092D01*
X817427Y7322D01*
X817737Y7552D01*
X818150Y7629D01*
X820217D01*
G01X817117Y9962D02*
X817169Y10230D01*
X817324Y10537D01*
X817582Y10729D01*
X817944Y10805D01*
X818305Y10729D01*
X818615Y10499D01*
X818770Y10154D01*
Y9770D01*
X818874Y9540D01*
X819132Y9349D01*
X819494Y9272D01*
X819855Y9387D01*
X820114Y9655D01*
X820217Y9962D01*
X820114Y10269D01*
X819855Y10537D01*
X819494Y10652D01*
X819132Y10575D01*
X818874Y10384D01*
X818770Y10154D01*
Y9770D01*
X818615Y9425D01*
X818305Y9195D01*
X817944Y9119D01*
X817582Y9195D01*
X817324Y9387D01*
X817169Y9694D01*
X817117Y9962D01*
G01X820217Y13062D02*
X820114Y12755D01*
X819855Y12525D01*
X819545Y12372D01*
X819132Y12257D01*
X818667Y12219D01*
X818202Y12257D01*
X817789Y12372D01*
X817479Y12525D01*
X817220Y12755D01*
X817117Y13062D01*
X817220Y13369D01*
X817479Y13599D01*
X817789Y13752D01*
X818202Y13867D01*
X818667Y13905D01*
X819132Y13867D01*
X819545Y13752D01*
X819855Y13599D01*
X820114Y13369D01*
X820217Y13062D01*
G01X822720Y144062D02*
X819520D01*
G01X822720Y137862D02*
Y144062D01*
G01X819520Y137862D02*
X822720D01*
G01X819520Y144062D02*
Y137862D01*
G01X822175Y283792D02*
Y263692D01*
G01D02*
X837975D01*
G01X827825Y283792D02*
X822175D01*
G01X821471Y286463D02*
X827671D01*
G01Y289663D02*
X821471D01*
G01D02*
Y286463D01*
G01X816099Y314238D02*
Y294138D01*
G01D02*
X831899D01*
G01Y314238D02*
X826249D01*
G01D02*
X823999Y311988D01*
G01D02*
X821749Y314238D01*
G01D02*
X816099D01*
G01X831692Y318788D02*
Y316566D01*
X831539Y316101D01*
X831232Y315791D01*
X830849Y315688D01*
X830466Y315791D01*
X830159Y316101D01*
X830006Y316566D01*
Y318788D01*
G01X828477Y318271D02*
X828247Y318581D01*
X827979Y318736D01*
X827672Y318788D01*
X827289Y318685D01*
X827021Y318426D01*
X826944Y318116D01*
X826982Y317806D01*
X827136Y317548D01*
X827902Y317031D01*
X828247Y316670D01*
X828477Y316153D01*
X828554Y315688D01*
X826944D01*
G01X825377Y318271D02*
X825147Y318581D01*
X824879Y318736D01*
X824572Y318788D01*
X824189Y318685D01*
X823921Y318426D01*
X823844Y318116D01*
X823882Y317806D01*
X824036Y317548D01*
X824802Y317031D01*
X825147Y316670D01*
X825377Y316153D01*
X825454Y315688D01*
X823844D01*
G01X822277Y318271D02*
X822047Y318581D01*
X821779Y318736D01*
X821472Y318788D01*
X821089Y318685D01*
X820821Y318426D01*
X820744Y318116D01*
X820782Y317806D01*
X820936Y317548D01*
X821702Y317031D01*
X822047Y316670D01*
X822277Y316153D01*
X822354Y315688D01*
X820744D01*
G01X818744Y474559D02*
X824944D01*
G01D02*
Y477759D01*
G01D02*
X818744D01*
G01D02*
Y474559D01*
G01X818000Y755504D02*
Y761504D01*
G01X814995Y762165D02*
Y765365D01*
G01Y766065D02*
Y769265D01*
G01X815814Y1485276D02*
Y1488476D01*
G01X823814Y1485276D02*
Y1488476D01*
G01X817614Y1485276D02*
X823814D01*
G01X817614Y1488476D02*
Y1485276D01*
G01X823814Y1488476D02*
X817614D01*
G01X815814Y1489276D02*
Y1492476D01*
G01X817614Y1489276D02*
X823814D01*
G01D02*
Y1492476D01*
G01X817614D02*
Y1489276D01*
G01X815814Y1495276D02*
Y1498476D01*
G01Y1499276D02*
Y1502476D01*
G01X823814Y1495276D02*
Y1498476D01*
G01X817614Y1495276D02*
X823814D01*
G01X817614Y1498476D02*
Y1495276D01*
G01X823814Y1498476D02*
X817614D01*
G01X823814Y1492476D02*
X817614D01*
G01X823814Y1499276D02*
Y1502476D01*
G01X817614Y1499276D02*
X823814D01*
G01X817614Y1502476D02*
Y1499276D01*
G01X823814Y1502476D02*
X817614D01*
G01X815814Y1504684D02*
Y1507884D01*
G01X817614Y1504684D02*
X823814D01*
G01D02*
Y1507884D01*
G01X817614D02*
Y1504684D01*
G01X815814Y1514684D02*
Y1517884D01*
G01Y1508684D02*
Y1511884D01*
G01X823814Y1514684D02*
Y1517884D01*
G01X817614Y1514684D02*
X823814D01*
G01X817614Y1517884D02*
Y1514684D01*
G01X823814Y1517884D02*
X817614D01*
G01X823814Y1507884D02*
X817614D01*
G01X823814Y1508684D02*
Y1511884D01*
G01X817614Y1508684D02*
X823814D01*
G01X817614Y1511884D02*
Y1508684D01*
G01X823814Y1511884D02*
X817614D01*
G01X815814Y1518684D02*
Y1521884D01*
G01X817614Y1518684D02*
X823814D01*
G01D02*
Y1521884D01*
G01X817614D02*
Y1518684D01*
G01X823814Y1521884D02*
X817614D01*
G01X823814Y1528684D02*
Y1531884D01*
G01X817614Y1528684D02*
X823814D01*
G01X817614Y1531884D02*
Y1528684D01*
G01X823814Y1531884D02*
X817614D01*
G01X823814Y1524684D02*
Y1527884D01*
G01X817614Y1524684D02*
X823814D01*
G01X817614Y1527884D02*
Y1524684D01*
G01X823814Y1527884D02*
X817614D01*
G01X841302Y-38151D02*
Y-21871D01*
X831702D01*
Y-38151D01*
X841302D01*
G01Y-18151D02*
Y-1871D01*
X831702D01*
Y-18151D01*
X841302D01*
G01Y1849D02*
Y18129D01*
X831702D01*
Y1849D01*
X841302D01*
G01X841120Y218762D02*
X847320D01*
G01X841120Y221962D02*
Y218762D01*
G01X847320Y221962D02*
X841120D01*
G01X839100Y221552D02*
Y227752D01*
G01X835900Y221552D02*
X839100D01*
G01X835900Y227752D02*
Y221552D01*
G01X843320Y217462D02*
X840120D01*
G01Y211262D02*
X843320D01*
G01X840120Y217462D02*
Y211262D01*
G01X831845Y221618D02*
X835045D01*
G01X831845Y227818D02*
Y221618D01*
G01X835045D02*
Y227818D01*
G01X839100Y227752D02*
X835900D01*
G01X835045Y227818D02*
X831845D01*
G01X837975Y263692D02*
Y283792D01*
G01X837768Y288342D02*
Y286120D01*
X837615Y285655D01*
X837308Y285345D01*
X836925Y285242D01*
X836542Y285345D01*
X836235Y285655D01*
X836082Y286120D01*
Y288342D01*
G01X833902Y285242D02*
X833825Y285914D01*
X833710Y286482D01*
X833557Y286999D01*
X833365Y287567D01*
X833058Y288342D01*
X834592D01*
G01X837975Y283792D02*
X832325D01*
G01D02*
X830075Y281542D01*
G01D02*
X827825Y283792D01*
G01X827671Y286463D02*
Y289663D01*
G01X831899Y294138D02*
Y314238D01*
G01X842679Y1282924D02*
X836479D01*
Y1279724D01*
X842679D01*
Y1282924D01*
G01X833665Y1278923D02*
Y1274323D01*
G01D02*
X843665D01*
G01X833665Y1274423D02*
Y1274323D01*
G01X843665Y1278923D02*
X833665D01*
G01X836607Y1283872D02*
X842807D01*
G01X836607Y1287072D02*
Y1283872D01*
G01X842807Y1287072D02*
X836607D01*
G01X837913Y1290172D02*
X844113D01*
G01X837913Y1293372D02*
Y1290172D01*
G01X844113Y1293372D02*
X837913D01*
G01X837909Y1294468D02*
X844109D01*
G01X837909Y1297668D02*
Y1294468D01*
G01X844109Y1297668D02*
X837909D01*
G01X854320Y207762D02*
Y210962D01*
G01X848120Y207762D02*
X854320D01*
G01X848120Y210962D02*
Y207762D01*
G01X854320Y210962D02*
X848120D01*
G01X854220Y217962D02*
X848020D01*
G01X854220Y214762D02*
Y217962D01*
G01X848020Y214762D02*
X854220D01*
G01X848020Y217962D02*
Y214762D01*
G01X847320Y218762D02*
Y221962D01*
G01X843320Y211262D02*
Y217462D01*
G01X853403Y271957D02*
X859603D01*
G01Y275157D02*
X853403D01*
G01D02*
Y271957D01*
G01X845382Y289959D02*
X851582D01*
G01D02*
Y293159D01*
G01D02*
X845382D01*
G01D02*
Y289959D01*
G01X851609Y289202D02*
X845409D01*
G01D02*
Y286002D01*
G01D02*
X851609D01*
G01D02*
Y289202D01*
G01X848131Y299942D02*
X854331D01*
G01D02*
Y303142D01*
G01D02*
X848131D01*
G01D02*
Y299942D01*
G01X848290Y307252D02*
X854490D01*
G01D02*
Y310452D01*
G01D02*
X848290D01*
G01D02*
Y307252D01*
G01X853850Y1268185D02*
Y1271385D01*
G01X847650Y1268185D02*
X853850D01*
G01X847650Y1271385D02*
Y1268185D01*
G01X847781Y1275571D02*
Y1272371D01*
G01X853981Y1275571D02*
X847781D01*
G01X853981Y1272371D02*
Y1275571D01*
G01X847781Y1272371D02*
X853981D01*
G01X853850Y1271385D02*
X847650D01*
G01X847695Y1276539D02*
X853895D01*
Y1279739D01*
X847695D01*
Y1276539D01*
G01X843665Y1278923D02*
Y1274323D01*
G01X842807Y1283872D02*
Y1287072D01*
G01X847856Y1293068D02*
Y1289868D01*
G01X854056Y1293068D02*
X847856D01*
G01X854056Y1289868D02*
Y1293068D01*
G01X847856Y1289868D02*
X854056D01*
G01X847820Y1297581D02*
Y1294381D01*
G01X854020Y1297581D02*
X847820D01*
G01X854020Y1294381D02*
Y1297581D01*
G01X847820Y1294381D02*
X854020D01*
G01X844113Y1290172D02*
Y1293372D01*
G01X844109Y1294468D02*
Y1297668D01*
G01X853994Y1285838D02*
Y1289038D01*
G01X847794Y1285838D02*
X853994D01*
G01X847794Y1289038D02*
Y1285838D01*
G01X853994Y1289038D02*
X847794D01*
G01X849050Y1588708D02*
X845850D01*
G01Y1582508D02*
X849050D01*
G01X845850Y1588708D02*
Y1582508D01*
G01X849050D02*
Y1588708D01*
G01X856928Y269482D02*
Y263282D01*
G01D02*
X860128D01*
G01D02*
Y269482D01*
G01D02*
X856928D01*
G01X864128Y263282D02*
Y269482D01*
G01D02*
X860928D01*
G01D02*
Y263282D01*
G01D02*
X864128D01*
G01X859603Y271957D02*
Y275157D01*
G01X875255Y1272730D02*
Y1270508D01*
X875102Y1270043D01*
X874795Y1269733D01*
X874412Y1269630D01*
X874029Y1269733D01*
X873722Y1270043D01*
X873569Y1270508D01*
Y1272730D01*
G01X872155Y1270095D02*
X871925Y1269837D01*
X871657Y1269682D01*
X871312Y1269630D01*
X870967Y1269733D01*
X870699Y1269940D01*
X870507Y1270302D01*
X870469Y1270715D01*
X870545Y1271128D01*
X870737Y1271387D01*
X871005Y1271593D01*
X871274Y1271645D01*
X871542Y1271593D01*
X871887Y1271387D01*
X871772Y1272730D01*
X870737D01*
G01X868212Y1269630D02*
Y1272730D01*
X868672Y1272110D01*
G01Y1269630D02*
X867752D01*
G01X868265Y1275529D02*
Y1295607D01*
G01X871584Y1275529D02*
X868265D01*
G01X875623Y1279568D02*
X871584Y1275529D01*
G01X868265Y1295607D02*
X882981D01*
G01X882823Y1237920D02*
X888823D01*
G01X882823Y1249920D02*
Y1237920D01*
G01X888823Y1249920D02*
X882823D01*
G01X879662Y1275529D02*
X875623Y1279568D01*
G01X882981Y1275529D02*
X879662D01*
G01X882981Y1295607D02*
Y1275529D01*
G01X890601Y1305250D02*
Y1303028D01*
X890448Y1302563D01*
X890141Y1302253D01*
X889758Y1302150D01*
X889375Y1302253D01*
X889068Y1302563D01*
X888915Y1303028D01*
Y1305250D01*
G01X887386Y1303442D02*
X887118Y1303803D01*
X886888Y1304010D01*
X886581Y1304113D01*
X886313Y1304010D01*
X886121Y1303803D01*
X885968Y1303493D01*
X885930Y1303132D01*
X885968Y1302822D01*
X886121Y1302512D01*
X886351Y1302253D01*
X886620Y1302150D01*
X886926Y1302253D01*
X887195Y1302563D01*
X887348Y1303028D01*
X887386Y1303545D01*
X887310Y1304217D01*
X887195Y1304578D01*
X887003Y1304940D01*
X886735Y1305198D01*
X886466Y1305250D01*
X886198Y1305147D01*
X886006Y1304888D01*
G01X883558Y1305250D02*
X883865Y1305147D01*
X884095Y1304888D01*
X884248Y1304578D01*
X884363Y1304165D01*
X884401Y1303700D01*
X884363Y1303235D01*
X884248Y1302822D01*
X884095Y1302512D01*
X883865Y1302253D01*
X883558Y1302150D01*
X883251Y1302253D01*
X883021Y1302512D01*
X882868Y1302822D01*
X882753Y1303235D01*
X882715Y1303700D01*
X882753Y1304165D01*
X882868Y1304578D01*
X883021Y1304888D01*
X883251Y1305147D01*
X883558Y1305250D01*
G01X881186Y1304733D02*
X880956Y1305043D01*
X880688Y1305198D01*
X880381Y1305250D01*
X879998Y1305147D01*
X879730Y1304888D01*
X879653Y1304578D01*
X879691Y1304268D01*
X879845Y1304010D01*
X880611Y1303493D01*
X880956Y1303132D01*
X881186Y1302615D01*
X881263Y1302150D01*
X879653D01*
G01X877358Y1305250D02*
X877665Y1305147D01*
X877895Y1304888D01*
X878048Y1304578D01*
X878163Y1304165D01*
X878201Y1303700D01*
X878163Y1303235D01*
X878048Y1302822D01*
X877895Y1302512D01*
X877665Y1302253D01*
X877358Y1302150D01*
X877051Y1302253D01*
X876821Y1302512D01*
X876668Y1302822D01*
X876553Y1303235D01*
X876515Y1303700D01*
X876553Y1304165D01*
X876668Y1304578D01*
X876821Y1304888D01*
X877051Y1305147D01*
X877358Y1305250D01*
G01X888162Y1310615D02*
X883111Y1315666D01*
G01X875811Y1310615D02*
Y1341717D01*
G01X878060Y1310615D02*
X875811D01*
G01X883111Y1315666D02*
X878060Y1310615D01*
G01X875811Y1341717D02*
X890411D01*
G01X895352Y186644D02*
Y189744D01*
G01X893742D02*
Y186644D01*
G01Y188194D02*
X895352D01*
G01X891524Y186644D02*
X891447Y187316D01*
X891332Y187884D01*
X891179Y188401D01*
X890987Y188969D01*
X890680Y189744D01*
X892214D01*
G01X888424Y186644D02*
X888347Y187316D01*
X888232Y187884D01*
X888079Y188401D01*
X887887Y188969D01*
X887580Y189744D01*
X889114D01*
G01X960236Y321654D02*
G03I-31496J0D01*
G01X900900Y854600D02*
Y851400D01*
G01X907100Y854600D02*
X900900D01*
G01Y851400D02*
X907100D01*
G01X898549Y874558D02*
X896327D01*
X895862Y874711D01*
X895552Y875018D01*
X895449Y875401D01*
X895552Y875784D01*
X895862Y876091D01*
X896327Y876244D01*
X898549D01*
G01X898032Y877773D02*
X898342Y878003D01*
X898497Y878271D01*
X898549Y878578D01*
X898446Y878961D01*
X898187Y879229D01*
X897877Y879306D01*
X897567Y879268D01*
X897309Y879114D01*
X896792Y878348D01*
X896431Y878003D01*
X895914Y877773D01*
X895449Y877696D01*
Y879306D01*
G01X899400Y910900D02*
X902600D01*
G01X899400Y917100D02*
Y910900D01*
G01X902600Y917100D02*
X899400D01*
G01X898869Y921610D02*
X896647D01*
X896182Y921763D01*
X895872Y922070D01*
X895769Y922453D01*
X895872Y922836D01*
X896182Y923143D01*
X896647Y923296D01*
X898869D01*
G01X898352Y924825D02*
X898662Y925055D01*
X898817Y925323D01*
X898869Y925630D01*
X898766Y926013D01*
X898507Y926281D01*
X898197Y926358D01*
X897887Y926320D01*
X897629Y926166D01*
X897112Y925400D01*
X896751Y925055D01*
X896234Y924825D01*
X895769Y924748D01*
Y926358D01*
G01Y928653D02*
X898869D01*
X898249Y928193D01*
G01X895769D02*
Y929113D01*
G01X896389Y930910D02*
X896027Y931140D01*
X895821Y931446D01*
X895769Y931791D01*
X895821Y932098D01*
X896079Y932405D01*
X896389Y932596D01*
X896699Y932635D01*
X897061Y932558D01*
X897319Y932290D01*
X897422Y932021D01*
Y931676D01*
G01Y932021D02*
X897577Y932251D01*
X897836Y932443D01*
X898146Y932520D01*
X898456Y932443D01*
X898714Y932251D01*
X898869Y931906D01*
X898817Y931561D01*
X898611Y931216D01*
G01X894307Y1139458D02*
Y1142658D01*
G01X888107Y1139458D02*
X894307D01*
G01X888107Y1142658D02*
Y1139458D01*
G01X894307Y1142658D02*
X888107D01*
G01X901307Y1141158D02*
X898107D01*
G01X901307Y1134958D02*
Y1141158D01*
G01X898107Y1134958D02*
X901307D01*
G01X898107Y1141158D02*
Y1134958D01*
G01X888107Y1146658D02*
Y1143458D01*
G01X894307Y1146658D02*
X888107D01*
G01X894307Y1143458D02*
Y1146658D01*
G01X888107Y1143458D02*
X894307D01*
G01X896048Y1142353D02*
X902248D01*
G01X896048Y1145553D02*
Y1142353D01*
G01X902248Y1145553D02*
X896048D01*
G01X897923Y1237920D02*
X903923D01*
G01X897923Y1249920D02*
Y1237920D01*
G01X895823D02*
Y1249920D01*
G01X889823Y1237920D02*
X895823D01*
G01X889823Y1249920D02*
Y1237920D01*
G01X888823D02*
Y1249920D01*
G01X903923D02*
X897923D01*
G01X895823D02*
X889823D01*
G01X896483Y1270020D02*
Y1266820D01*
G01D02*
X902683D01*
G01X896527Y1274292D02*
Y1271092D01*
G01X902727Y1274292D02*
X896527D01*
G01Y1271092D02*
X902727D01*
G01X902683Y1270020D02*
X896483D01*
G01X896402Y1282803D02*
Y1279603D01*
G01X902602Y1282803D02*
X896402D01*
G01Y1279603D02*
X902602D01*
G01X896450Y1278568D02*
Y1275368D01*
G01X902650Y1278568D02*
X896450D01*
G01Y1275368D02*
X902650D01*
G01X896193Y1299627D02*
Y1296427D01*
G01D02*
X902393D01*
G01X896154Y1295453D02*
Y1292253D01*
G01X902354Y1295453D02*
X896154D01*
G01Y1292253D02*
X902354D01*
G01X896426Y1291230D02*
Y1288030D01*
G01X902626Y1291230D02*
X896426D01*
G01Y1288030D02*
X902626D01*
G01X896448Y1287020D02*
Y1283820D01*
G01X902648Y1287020D02*
X896448D01*
G01Y1283820D02*
X902648D01*
G01X902393Y1299627D02*
X896193D01*
G01X890411Y1310615D02*
X888162D01*
G01X890411Y1341717D02*
Y1310615D01*
G01X891050Y1588708D02*
X887850D01*
G01Y1582508D02*
X891050D01*
G01X887850Y1588708D02*
Y1582508D01*
G01X891050D02*
Y1588708D01*
G01X963867Y1673000D02*
Y1680500D01*
X961627D01*
X960880Y1680125D01*
X960320Y1679250D01*
X960133Y1678250D01*
X960320Y1677250D01*
X960787Y1676500D01*
X961627Y1676125D01*
X963867D01*
G01X956367Y1673000D02*
Y1680500D01*
X954033D01*
X953287Y1680125D01*
X952820Y1679625D01*
X952633Y1678625D01*
X952820Y1677625D01*
X953380Y1677000D01*
X954033Y1676625D01*
X956367D01*
G01X954033D02*
X952633Y1673000D01*
G01X945133D02*
X948867D01*
Y1680500D01*
X945133D01*
G01X946627Y1676875D02*
X948867D01*
G01X941460Y1674000D02*
X940713Y1673375D01*
X939873Y1673000D01*
X939127D01*
X938380Y1673375D01*
X937820Y1674000D01*
X937540Y1674875D01*
X937727Y1675750D01*
X938193Y1676500D01*
X939033Y1677000D01*
X940153Y1677250D01*
X940807Y1677750D01*
X941087Y1678625D01*
X940900Y1679500D01*
X940433Y1680125D01*
X939780Y1680500D01*
X939127D01*
X938473Y1680250D01*
X937913Y1679625D01*
G01X933960Y1674000D02*
X933213Y1673375D01*
X932373Y1673000D01*
X931627D01*
X930880Y1673375D01*
X930320Y1674000D01*
X930040Y1674875D01*
X930227Y1675750D01*
X930693Y1676500D01*
X931533Y1677000D01*
X932653Y1677250D01*
X933307Y1677750D01*
X933587Y1678625D01*
X933400Y1679500D01*
X932933Y1680125D01*
X932280Y1680500D01*
X931627D01*
X930973Y1680250D01*
X930413Y1679625D01*
G01X925713Y1675500D02*
X923287D01*
G01X918773Y1673000D02*
Y1680500D01*
X915227D01*
G01X916533Y1676875D02*
X918773D01*
G01X910620Y1680500D02*
X908380D01*
G01X909500D02*
Y1673000D01*
G01X910620D02*
X908380D01*
G01X902000Y1680500D02*
Y1673000D01*
G01X904147Y1680500D02*
X899853D01*
G01X917100Y861600D02*
X913900D01*
G01Y855400D02*
X917100D01*
G01X913900Y861600D02*
Y855400D01*
G01X907100Y851400D02*
Y854600D01*
G01Y855400D02*
Y861600D01*
G01D02*
X903900D01*
G01Y855400D02*
X907100D01*
G01X903900Y861600D02*
Y855400D01*
G01X908900Y861600D02*
Y855400D01*
G01X912100Y861600D02*
X908900D01*
G01X912100Y855400D02*
Y861600D01*
G01X908900Y855400D02*
X912100D01*
G01X915600Y851400D02*
Y854600D01*
G01X909400Y851400D02*
X915600D01*
G01X909400Y854600D02*
Y851400D01*
G01X915600Y854600D02*
X909400D01*
G01X911075Y878118D02*
X914177Y881118D01*
G01Y875016D02*
X911075Y878118D01*
G01X914177Y872356D02*
Y875016D01*
G01X901973Y872356D02*
X914177D01*
G01X901973Y883880D02*
Y872356D01*
G01X915777Y880354D02*
X918977D01*
G01X915777Y886554D02*
Y880354D01*
G01X914177Y881118D02*
Y883880D01*
G01D02*
X901973D01*
G01X918977Y886554D02*
X915777D01*
G01X905443Y895102D02*
Y901302D01*
G01X902243Y895102D02*
X905443D01*
G01X902243Y901302D02*
Y895102D01*
G01X905443Y901302D02*
X902243D01*
G01X916400Y920400D02*
X919600D01*
G01X916400Y926600D02*
Y920400D01*
G01X910600Y917100D02*
X907400D01*
G01X910600Y910900D02*
Y917100D01*
G01X907400Y910900D02*
X910600D01*
G01X907400Y917100D02*
Y910900D01*
G01X914600Y917100D02*
X911400D01*
G01X914600Y910900D02*
Y917100D01*
G01X911400Y910900D02*
X914600D01*
G01X911400Y917100D02*
Y910900D01*
G01X915400Y917100D02*
Y910900D01*
G01D02*
X918600D01*
G01Y917100D02*
X915400D01*
G01X902600Y910900D02*
Y917100D01*
G01X906600D02*
X903400D01*
G01X906600Y910900D02*
Y917100D01*
G01X903400Y910900D02*
X906600D01*
G01X903400Y917100D02*
Y910900D01*
G01X906007Y936439D02*
Y922413D01*
G01X913981D02*
Y929426D01*
G01X906007Y922413D02*
X913981D01*
G01X919600Y926600D02*
X916400D01*
G01X913981Y936439D02*
X906007D01*
G01X913981Y929426D02*
Y936439D01*
G01X910900Y946600D02*
Y943400D01*
G01X917100Y946600D02*
X910900D01*
G01Y943400D02*
X917100D01*
G01X908600D02*
Y946600D01*
G01X902400Y943400D02*
X908600D01*
G01X902400Y946600D02*
Y943400D01*
G01X908600Y946600D02*
X902400D01*
G01X914100Y954550D02*
Y960750D01*
X910900D01*
Y954550D01*
X914100D01*
G01X909100D02*
Y960750D01*
X905900D01*
Y954550D01*
X909100D01*
G01X910900Y957600D02*
Y951400D01*
X914100D01*
Y957600D01*
X910900D01*
G01X905900D02*
Y951400D01*
X909100D01*
Y957600D01*
X905900D01*
G01X912693Y973418D02*
X920833D01*
G01X912693Y983532D02*
Y973418D01*
G01X920833Y983532D02*
X912693D01*
G01X915163Y985257D02*
X918363D01*
G01X915163Y991457D02*
Y985257D01*
G01X918363Y991457D02*
X915163D01*
G01X902248Y1142353D02*
Y1145553D01*
G01X903887Y1136797D02*
X907087D01*
G01X903887Y1142997D02*
Y1136797D01*
G01X907087Y1142997D02*
X903887D01*
G01X907087Y1136797D02*
Y1142997D01*
G01X913023Y1237920D02*
X919023D01*
G01X913023Y1249920D02*
Y1237920D01*
G01X912023D02*
Y1249920D01*
G01X906023Y1237920D02*
X912023D01*
G01X906023Y1249920D02*
Y1237920D01*
G01X903923D02*
Y1249920D01*
G01X919023D02*
X913023D01*
G01X912023D02*
X906023D01*
G01X902683Y1266820D02*
Y1270020D01*
G01X909948Y1265233D02*
X916148D01*
Y1268433D01*
X909948D01*
Y1265233D01*
G01X912998Y1268433D02*
X906798D01*
Y1265233D01*
X912998D01*
Y1268433D01*
G01X902727Y1271092D02*
Y1274292D01*
G01X902602Y1279603D02*
Y1282803D01*
G01X902650Y1275368D02*
Y1278568D01*
G01X910062Y1269425D02*
X916262D01*
Y1272625D01*
X910062D01*
Y1269425D01*
G01X913112Y1272625D02*
X906912D01*
Y1269425D01*
X913112D01*
Y1272625D01*
G01X912834Y1285375D02*
X906634D01*
Y1282175D01*
X912834D01*
Y1285375D01*
G01X909784Y1282175D02*
X915984D01*
Y1285375D01*
X909784D01*
Y1282175D01*
G01X912874Y1281051D02*
X906674D01*
Y1277851D01*
X912874D01*
Y1281051D01*
G01X909824Y1277851D02*
X916024D01*
Y1281051D01*
X909824D01*
Y1277851D01*
G01X912843Y1276851D02*
X906643D01*
Y1273651D01*
X912843D01*
Y1276851D01*
G01X909793Y1273651D02*
X915993D01*
Y1276851D01*
X909793D01*
Y1273651D01*
G01X902393Y1296427D02*
Y1299627D01*
G01X902354Y1292253D02*
Y1295453D01*
G01X902626Y1288030D02*
Y1291230D01*
G01X902648Y1283820D02*
Y1287020D01*
G01X912663Y1298313D02*
X906463D01*
Y1295113D01*
X912663D01*
Y1298313D01*
G01X909613Y1295113D02*
X915813D01*
Y1298313D01*
X909613D01*
Y1295113D01*
G01X912683Y1293930D02*
X906483D01*
Y1290730D01*
X912683D01*
Y1293930D01*
G01X909633Y1290730D02*
X915833D01*
Y1293930D01*
X909633D01*
Y1290730D01*
G01X912750Y1289835D02*
X906550D01*
Y1286635D01*
X912750D01*
Y1289835D01*
G01X909700Y1286635D02*
X915900D01*
Y1289835D01*
X909700D01*
Y1286635D01*
G01X934895Y194986D02*
X928695D01*
G01D02*
Y191786D01*
G01D02*
X934895D01*
G01X934695Y190986D02*
X928495D01*
G01D02*
Y187786D01*
G01D02*
X934695D01*
G01X926825Y196012D02*
X933025D01*
G01Y199212D02*
X926825D01*
G01D02*
Y196012D01*
G01X933025Y203212D02*
X926825D01*
G01D02*
Y200012D01*
G01D02*
X933025D01*
G01X919287Y838001D02*
X925487D01*
Y841201D01*
X919287D01*
Y838001D01*
G01X919400Y845591D02*
X925600D01*
Y848791D01*
X919400D01*
Y845591D01*
G01X928637Y841201D02*
X922437D01*
Y838001D01*
X928637D01*
Y841201D01*
G01X928750Y848791D02*
X922550D01*
Y845591D01*
X928750D01*
Y848791D01*
G01X917100Y855400D02*
Y861600D01*
G01X930701Y871602D02*
X928479D01*
X928014Y871755D01*
X927704Y872062D01*
X927601Y872445D01*
X927704Y872828D01*
X928014Y873135D01*
X928479Y873288D01*
X930701D01*
G01X928066Y874702D02*
X927808Y874932D01*
X927653Y875200D01*
X927601Y875545D01*
X927704Y875890D01*
X927911Y876158D01*
X928273Y876350D01*
X928686Y876388D01*
X929099Y876312D01*
X929358Y876120D01*
X929564Y875852D01*
X929616Y875583D01*
X929564Y875315D01*
X929358Y874970D01*
X930701Y875085D01*
Y876120D01*
G01X918977Y880354D02*
Y886554D01*
G01X928003Y880821D02*
X931203D01*
G01X928003Y887021D02*
Y880821D01*
G01X931203D02*
Y887021D01*
G01D02*
X928003D01*
G01X923100Y894600D02*
X916900D01*
Y891400D01*
X923100D01*
Y894600D01*
G01X920050Y891400D02*
X926250D01*
Y894600D01*
X920050D01*
Y891400D01*
G01X923900Y908900D02*
X927100D01*
G01X923900Y915100D02*
Y908900D01*
G01X927100D02*
Y915100D01*
G01X923100Y899600D02*
X916900D01*
Y896400D01*
X923100D01*
Y899600D01*
G01X920050Y896400D02*
X926250D01*
Y899600D01*
X920050D01*
Y896400D01*
G01X919600Y920400D02*
Y926600D01*
G01X918600Y910900D02*
Y917100D01*
G01X927100Y915100D02*
X923900D01*
G01X927900Y918400D02*
X931100D01*
G01X927900Y924600D02*
Y918400D01*
G01X931100Y924600D02*
X927900D01*
G01X931100Y918400D02*
Y924600D01*
G01X927100D02*
X923900D01*
G01X927100Y918400D02*
Y924600D01*
G01X923900Y918400D02*
X927100D01*
G01X923900Y924600D02*
Y918400D01*
G01X930138Y931221D02*
X927916D01*
X927451Y931374D01*
X927141Y931681D01*
X927038Y932064D01*
X927141Y932447D01*
X927451Y932754D01*
X927916Y932907D01*
X930138D01*
G01X928330Y934436D02*
X928691Y934704D01*
X928898Y934934D01*
X929001Y935241D01*
X928898Y935509D01*
X928691Y935701D01*
X928381Y935854D01*
X928020Y935892D01*
X927710Y935854D01*
X927400Y935701D01*
X927141Y935471D01*
X927038Y935202D01*
X927141Y934896D01*
X927451Y934627D01*
X927916Y934474D01*
X928433Y934436D01*
X929105Y934512D01*
X929466Y934627D01*
X929828Y934819D01*
X930086Y935087D01*
X930138Y935356D01*
X930035Y935624D01*
X929776Y935816D01*
G01X930900Y943400D02*
X934100D01*
G01X930900Y949600D02*
Y943400D01*
G01X934100Y949600D02*
X930900D01*
G01X917100Y943400D02*
Y946600D01*
G01X917900Y943400D02*
X921100D01*
G01X917900Y949600D02*
Y943400D01*
G01X921100Y949600D02*
X917900D01*
G01X921100Y943400D02*
Y949600D01*
G01X921900Y952750D02*
Y946550D01*
X925100D01*
Y952750D01*
X921900D01*
G01X926900D02*
Y946550D01*
X930100D01*
Y952750D01*
X926900D01*
G01X930100Y943400D02*
Y949600D01*
X926900D01*
Y943400D01*
X930100D01*
G01X925100D02*
Y949600D01*
X921900D01*
Y943400D01*
X925100D01*
G01X920833Y973418D02*
Y983532D01*
G01X918363Y985257D02*
Y991457D01*
G01X929250Y980900D02*
X935450D01*
Y984100D01*
X929250D01*
Y980900D01*
G01Y975900D02*
X935450D01*
Y979100D01*
X929250D01*
Y975900D01*
G01X925396Y991585D02*
Y989363D01*
X925243Y988898D01*
X924936Y988588D01*
X924553Y988485D01*
X924170Y988588D01*
X923863Y988898D01*
X923710Y989363D01*
Y991585D01*
G01X920993Y988485D02*
Y991585D01*
X922411Y989363D01*
X920495D01*
G01X919023Y1237920D02*
Y1249920D01*
G01X921254Y1267947D02*
Y1264747D01*
G01X927454Y1267947D02*
X921254D01*
G01X927454Y1264747D02*
Y1267947D01*
G01X921254Y1264747D02*
X927454D01*
G01X921330Y1284648D02*
Y1281448D01*
G01X927530D02*
Y1284648D01*
G01X921330Y1281448D02*
X927530D01*
G01X921482Y1280313D02*
Y1277113D01*
G01X927682Y1280313D02*
X921482D01*
G01X927682Y1277113D02*
Y1280313D01*
G01X921482Y1277113D02*
X927682D01*
G01X921355Y1276191D02*
Y1272991D01*
G01X927555Y1276191D02*
X921355D01*
G01X927555Y1272991D02*
Y1276191D01*
G01X921355Y1272991D02*
X927555D01*
G01X921404Y1272008D02*
Y1268808D01*
G01X927604Y1272008D02*
X921404D01*
G01X927604Y1268808D02*
Y1272008D01*
G01X921404Y1268808D02*
X927604D01*
G01X921486Y1297557D02*
Y1294357D01*
G01X927686Y1297557D02*
X921486D01*
G01X927686Y1294357D02*
Y1297557D01*
G01X921486Y1294357D02*
X927686D01*
G01X921409Y1293276D02*
Y1290076D01*
G01X927609Y1293276D02*
X921409D01*
G01X927609Y1290076D02*
Y1293276D01*
G01X921409Y1290076D02*
X927609D01*
G01X921431Y1288793D02*
Y1285593D01*
G01X927631Y1288793D02*
X921431D01*
G01X927631Y1285593D02*
Y1288793D01*
G01X921431Y1285593D02*
X927631D01*
G01X927530Y1284648D02*
X921330D01*
G01X916900Y1303600D02*
Y1300400D01*
G01X923100Y1303600D02*
X916900D01*
G01X923100Y1300400D02*
Y1303600D01*
G01X916900Y1300400D02*
X923100D01*
G01X916900Y1307600D02*
Y1304400D01*
G01X923100Y1307600D02*
X916900D01*
G01X923100Y1304400D02*
Y1307600D01*
G01X916900Y1304400D02*
X923100D01*
G01X920380Y1667862D02*
X917180D01*
G01X920380Y1661662D02*
Y1667862D01*
G01X917180Y1661662D02*
X920380D01*
G01X917180Y1667862D02*
Y1661662D01*
G01X933398Y1667862D02*
X930198D01*
G01Y1661662D02*
X933398D01*
G01X930198Y1667862D02*
Y1661662D01*
G01X922198Y1667862D02*
Y1661662D01*
G01D02*
X925398D01*
G01D02*
Y1667862D01*
G01D02*
X922198D01*
G01X926198D02*
Y1661662D01*
G01D02*
X929398D01*
G01Y1667862D02*
X926198D01*
G01X929398Y1661662D02*
Y1667862D01*
G01X943727Y166433D02*
Y169533D01*
G01X942117D02*
Y166433D01*
G01Y167983D02*
X943727D01*
G01X939899Y166433D02*
X939822Y167105D01*
X939707Y167673D01*
X939554Y168190D01*
X939362Y168758D01*
X939055Y169533D01*
X940589D01*
G01X937450Y167725D02*
X937182Y168086D01*
X936952Y168293D01*
X936645Y168396D01*
X936377Y168293D01*
X936185Y168086D01*
X936032Y167776D01*
X935994Y167415D01*
X936032Y167105D01*
X936185Y166795D01*
X936415Y166536D01*
X936684Y166433D01*
X936990Y166536D01*
X937259Y166846D01*
X937412Y167311D01*
X937450Y167828D01*
X937374Y168500D01*
X937259Y168861D01*
X937067Y169223D01*
X936799Y169481D01*
X936530Y169533D01*
X936262Y169430D01*
X936070Y169171D01*
G01X934895Y191786D02*
Y194986D01*
G01X934695Y187786D02*
Y190986D01*
G01X933025Y196012D02*
Y199212D01*
G01Y200012D02*
Y203212D01*
G01X933400Y852100D02*
Y848900D01*
G01X939600D02*
Y852100D01*
G01X933400Y848900D02*
X939600D01*
G01X941400D02*
X947600D01*
G01X941400Y852100D02*
Y848900D01*
G01X935600Y865600D02*
X932400D01*
G01X935600Y859400D02*
Y865600D01*
G01X932400Y859400D02*
X935600D01*
G01X932400Y865600D02*
Y859400D01*
G01X941400Y860100D02*
Y853900D01*
G01X944600Y860100D02*
X941400D01*
G01X944600Y853900D02*
Y860100D01*
G01X941400Y853900D02*
X944600D01*
G01X936400Y860100D02*
Y853900D01*
G01X939600Y860100D02*
X936400D01*
G01X939600Y853900D02*
Y860100D01*
G01X936400Y853900D02*
X939600D01*
G01Y852100D02*
X933400D01*
G01X947600D02*
X941400D01*
G01X933821Y875355D02*
Y872593D01*
G01X936923Y878355D02*
X933821Y875355D01*
G01Y881457D02*
X936923Y878355D01*
G01X946025Y872593D02*
Y884117D01*
G01X933821Y872593D02*
X946025D01*
G01X933821Y884117D02*
Y881457D01*
G01X946025Y884117D02*
X933821D01*
G01X940400Y896100D02*
Y892900D01*
G01D02*
X946600D01*
G01X933400Y896100D02*
Y892900D01*
G01X939600D02*
Y896100D01*
G01X933400Y892900D02*
X939600D01*
G01X946600Y896100D02*
X940400D01*
G01X939600D02*
X933400D01*
G01X944900Y908900D02*
X948100D01*
G01X944900Y915100D02*
Y908900D01*
G01X936900D02*
X940100D01*
G01X936900Y915100D02*
Y908900D01*
G01X940100D02*
Y915100D01*
G01X948100Y924600D02*
X944900D01*
G01Y918400D02*
X948100D01*
G01X944900Y924600D02*
Y918400D01*
G01X948100Y915100D02*
X944900D01*
G01X944100Y924600D02*
X940900D01*
G01Y918400D02*
X944100D01*
G01X940900Y924600D02*
Y918400D01*
G01X944100D02*
Y924600D01*
G01X940100Y915100D02*
X936900D01*
G01X936100Y918400D02*
Y924600D01*
G01X932900Y918400D02*
X936100D01*
G01X932900Y924600D02*
Y918400D01*
G01X936100Y924600D02*
X932900D01*
G01X940100D02*
X936900D01*
G01X940100Y918400D02*
Y924600D01*
G01X936900Y918400D02*
X940100D01*
G01X936900Y924600D02*
Y918400D01*
G01X944701Y938049D02*
X934587D01*
G01Y929909D02*
X944701D01*
G01X934587Y938049D02*
Y929909D01*
G01X944701D02*
Y938049D01*
G01X934100Y943400D02*
Y949600D01*
G01X938600Y971900D02*
Y975100D01*
G01X932400Y971900D02*
X938600D01*
G01X932400Y975100D02*
Y971900D01*
G01X938600Y975100D02*
X932400D01*
G01X938600Y984900D02*
Y988100D01*
G01X932400Y984900D02*
X938600D01*
G01X932400Y988100D02*
Y984900D01*
G01X938600Y984100D02*
X932400D01*
Y980900D01*
X938600D01*
Y984100D01*
G01Y979100D02*
X932400D01*
Y975900D01*
X938600D01*
Y979100D01*
G01Y988100D02*
X932400D01*
G01X941332Y1139458D02*
Y1142658D01*
G01X935132Y1139458D02*
X941332D01*
G01X935132Y1142658D02*
Y1139458D01*
G01X941332Y1142658D02*
X935132D01*
G01X948332Y1141158D02*
X945132D01*
G01Y1134958D02*
X948332D01*
G01X945132Y1141158D02*
Y1134958D01*
G01X935132Y1146658D02*
Y1143458D01*
G01X941332Y1146658D02*
X935132D01*
G01X941332Y1143458D02*
Y1146658D01*
G01X935132Y1143458D02*
X941332D01*
G01X943073Y1142353D02*
X949273D01*
G01X943073Y1145553D02*
Y1142353D01*
G01X949273Y1145553D02*
X943073D01*
G01X941807Y1237920D02*
X947807D01*
G01X941807Y1249920D02*
Y1237920D01*
G01X947807Y1249920D02*
X941807D01*
G01X939701Y1268129D02*
Y1271329D01*
G01X933501Y1268129D02*
X939701D01*
G01X933501Y1271329D02*
Y1268129D01*
G01X939736Y1264036D02*
Y1267236D01*
G01X933536Y1264036D02*
X939736D01*
G01X933536Y1267236D02*
Y1264036D01*
G01X939736Y1267236D02*
X933536D01*
G01X939736Y1280515D02*
Y1283715D01*
G01X933536Y1280515D02*
X939736D01*
G01X933536Y1283715D02*
Y1280515D01*
G01X939783Y1276459D02*
Y1279659D01*
G01X933583Y1276459D02*
X939783D01*
G01X933583Y1279659D02*
Y1276459D01*
G01X939783Y1279659D02*
X933583D01*
G01X939701Y1271329D02*
X933501D01*
G01X939807Y1272358D02*
Y1275558D01*
G01X933607Y1272358D02*
X939807D01*
G01X933607Y1275558D02*
Y1272358D01*
G01X939807Y1275558D02*
X933607D01*
G01X939640Y1292591D02*
Y1295791D01*
G01X933440Y1292591D02*
X939640D01*
G01X933440Y1295791D02*
Y1292591D01*
G01X939640Y1295791D02*
X933440D01*
G01X939720Y1288552D02*
Y1291752D01*
G01X933520Y1288552D02*
X939720D01*
G01X933520Y1291752D02*
Y1288552D01*
G01X939720Y1291752D02*
X933520D01*
G01X939756Y1284556D02*
Y1287756D01*
G01X933556Y1284556D02*
X939756D01*
G01X933556Y1287756D02*
Y1284556D01*
G01X939756Y1287756D02*
X933556D01*
G01X939736Y1283715D02*
X933536D01*
G01X949398Y1667862D02*
X946198D01*
G01Y1661662D02*
X949398D01*
G01X946198Y1667862D02*
Y1661662D01*
G01X941398Y1667862D02*
X938198D01*
G01X941398Y1661662D02*
Y1667862D01*
G01X938198Y1661662D02*
X941398D01*
G01X938198Y1667862D02*
Y1661662D01*
G01X933398D02*
Y1667862D01*
G01X934198D02*
Y1661662D01*
G01D02*
X937398D01*
G01D02*
Y1667862D01*
G01D02*
X934198D01*
G01X942198Y1661662D02*
X945398D01*
G01X942198Y1667862D02*
Y1661662D01*
G01X945398Y1667862D02*
X942198D01*
G01X945398Y1661662D02*
Y1667862D01*
G01X946985Y293287D02*
Y290187D01*
G01X948595D02*
Y293287D01*
G01Y291737D02*
X946985D01*
G01X950890Y293287D02*
Y290187D01*
X950430Y290807D01*
G01Y293287D02*
X951350D01*
G01X953990D02*
Y290187D01*
X953530Y290807D01*
G01Y293287D02*
X954450D01*
G01X956247Y292822D02*
X956477Y293080D01*
X956745Y293235D01*
X957090Y293287D01*
X957435Y293184D01*
X957703Y292977D01*
X957895Y292615D01*
X957933Y292202D01*
X957857Y291789D01*
X957665Y291530D01*
X957397Y291324D01*
X957128Y291272D01*
X956860Y291324D01*
X956515Y291530D01*
X956630Y290187D01*
X957665D01*
G01X947600Y848900D02*
Y852100D01*
G01X946400Y853900D02*
X949600D01*
G01X946400Y860100D02*
Y853900D01*
G01X949600Y860100D02*
X946400D01*
G01X949600Y853900D02*
Y860100D01*
G01X952898Y881602D02*
X956000Y878500D01*
G01X952898Y875500D02*
Y872738D01*
G01X956000Y878500D02*
X952898Y875500D01*
G01Y872738D02*
X965102D01*
G01X947900Y871900D02*
X951100D01*
G01X947900Y878100D02*
Y871900D01*
G01X951100Y878100D02*
X947900D01*
G01X951100Y871900D02*
Y878100D01*
G01Y878900D02*
Y885100D01*
G01X947900Y878900D02*
X951100D01*
G01X947900Y885100D02*
Y878900D01*
G01X952898Y884262D02*
Y881602D01*
G01X965102Y884262D02*
X952898D01*
G01X951100Y885100D02*
X947900D01*
G01X946600Y892900D02*
Y896100D01*
G01X954900Y894900D02*
X958100D01*
G01X954900Y901100D02*
Y894900D01*
G01X958100D02*
Y901100D01*
G01X959900Y894900D02*
X963100D01*
G01X959900Y901100D02*
Y894900D01*
G01X958100Y901100D02*
X954900D01*
G01X952400Y905100D02*
Y901900D01*
G01X958600Y905100D02*
X952400D01*
G01X958600Y901900D02*
Y905100D01*
G01X952400Y901900D02*
X958600D01*
G01X952900Y908900D02*
X956100D01*
G01X952900Y915100D02*
Y908900D01*
G01X956100D02*
Y915100D01*
G01X948100Y908900D02*
Y915100D01*
G01X963100Y901100D02*
X959900D01*
G01X959400Y901900D02*
X965600D01*
G01X959400Y905100D02*
Y901900D01*
G01X965600Y905100D02*
X959400D01*
G01X956100Y924600D02*
X952900D01*
G01X956100Y918400D02*
Y924600D01*
G01X952900Y918400D02*
X956100D01*
G01X952900Y924600D02*
Y918400D01*
G01X948100D02*
Y924600D01*
G01X956100Y915100D02*
X952900D01*
G01X952100Y924600D02*
X948900D01*
G01Y918400D02*
X952100D01*
G01X948900Y924600D02*
Y918400D01*
G01X952100D02*
Y924600D01*
G01X950100Y935600D02*
X946900D01*
G01X950100Y929400D02*
Y935600D01*
G01X946900Y929400D02*
X950100D01*
G01X946900Y935600D02*
Y929400D01*
G01X948332Y1134958D02*
Y1141158D01*
G01X949273Y1142353D02*
Y1145553D01*
G01X950912Y1136797D02*
X954112D01*
G01X950912Y1142997D02*
Y1136797D01*
G01X954112Y1142997D02*
X950912D01*
G01X954112Y1136797D02*
Y1142997D01*
G01X954807Y1237920D02*
Y1249920D01*
G01X948807Y1237920D02*
X954807D01*
G01X948807Y1249920D02*
Y1237920D01*
G01X956907D02*
X962907D01*
G01X956907Y1249920D02*
Y1237920D01*
G01X947807D02*
Y1249920D01*
G01X954807D02*
X948807D01*
G01X962907D02*
X956907D01*
G01X956400Y1265400D02*
X962600D01*
G01X956400Y1268600D02*
Y1265400D01*
G01X962600Y1268600D02*
X956400D01*
G01Y1277400D02*
X962600D01*
G01X956400Y1280600D02*
Y1277400D01*
G01X962600Y1280600D02*
X956400D01*
G01Y1273400D02*
X962600D01*
G01X956400Y1276600D02*
Y1273400D01*
G01X962600Y1276600D02*
X956400D01*
G01Y1269400D02*
X962600D01*
G01X956400Y1272600D02*
Y1269400D01*
G01X962600Y1272600D02*
X956400D01*
G01Y1284600D02*
Y1281400D01*
G01D02*
X962600D01*
G01Y1284600D02*
X956400D01*
G01Y1288600D02*
Y1285400D01*
G01X962600Y1288600D02*
X956400D01*
G01Y1285400D02*
X962600D01*
G01X959000Y1289500D02*
X965000D01*
G01X959000Y1301500D02*
Y1289500D01*
G01X958000Y1289700D02*
Y1294300D01*
G01X948000Y1289700D02*
Y1294300D01*
G01X958000D02*
X948000D01*
G01X958000Y1294200D02*
Y1294300D01*
G01X948000Y1289700D02*
X958000D01*
G01X965000Y1301500D02*
X959000D01*
G01X959423Y1504523D02*
X962623D01*
G01X959423Y1510723D02*
Y1504523D01*
G01X952423Y1507377D02*
Y1504177D01*
G01X958623D02*
Y1507377D01*
G01X952423Y1504177D02*
X958623D01*
G01X962623Y1510723D02*
X959423D01*
G01X958623Y1507377D02*
X952423D01*
G01Y1511377D02*
Y1508177D01*
G01X958623Y1511377D02*
X952423D01*
G01X958623Y1508177D02*
Y1511377D01*
G01X952423Y1508177D02*
X958623D01*
G01X950198Y1653620D02*
X953398D01*
G01X950198Y1659820D02*
Y1653620D01*
G01X953398D02*
Y1659820D01*
G01X949398Y1661662D02*
Y1667862D01*
G01X950198D02*
Y1661662D01*
G01D02*
X953398D01*
G01Y1667862D02*
X950198D01*
G01X953398Y1661662D02*
Y1667862D01*
G01Y1659820D02*
X950198D01*
G01X965580Y218299D02*
Y206299D01*
G01D02*
X971580D01*
G01D02*
Y218299D01*
G01D02*
X965580D01*
G01X961900Y855900D02*
X965100D01*
G01X961900Y862100D02*
Y855900D01*
G01X965100Y862100D02*
X961900D01*
G01X965100Y855900D02*
Y862100D01*
G01X972573Y874104D02*
X970351D01*
X969886Y874257D01*
X969576Y874564D01*
X969473Y874947D01*
X969576Y875330D01*
X969886Y875637D01*
X970351Y875790D01*
X972573D01*
G01X969835Y877395D02*
X969576Y877664D01*
X969473Y877970D01*
X969576Y878277D01*
X969886Y878545D01*
X970351Y878737D01*
X970816Y878814D01*
X971385D01*
X971850Y878737D01*
X972263Y878545D01*
X972470Y878315D01*
X972573Y878047D01*
X972470Y877740D01*
X972263Y877510D01*
X971953Y877357D01*
X971540Y877280D01*
X971178Y877357D01*
X970816Y877549D01*
X970610Y877779D01*
X970558Y878047D01*
X970661Y878354D01*
X970920Y878584D01*
X971385Y878814D01*
G01X970765Y880419D02*
X971126Y880687D01*
X971333Y880917D01*
X971436Y881224D01*
X971333Y881492D01*
X971126Y881684D01*
X970816Y881837D01*
X970455Y881875D01*
X970145Y881837D01*
X969835Y881684D01*
X969576Y881454D01*
X969473Y881185D01*
X969576Y880879D01*
X969886Y880610D01*
X970351Y880457D01*
X970868Y880419D01*
X971540Y880495D01*
X971901Y880610D01*
X972263Y880802D01*
X972521Y881070D01*
X972573Y881339D01*
X972470Y881607D01*
X972211Y881799D01*
G01X965102Y872738D02*
Y884262D01*
G01X963100Y894900D02*
Y901100D01*
G01X965600Y901900D02*
Y905100D01*
G01X971007Y1237920D02*
Y1249920D01*
G01X965007Y1237920D02*
X971007D01*
G01X965007Y1249920D02*
Y1237920D01*
G01X972007D02*
X978007D01*
G01X972007Y1249920D02*
Y1237920D01*
G01X962907D02*
Y1249920D01*
G01X971007D02*
X965007D01*
G01X978007D02*
X972007D01*
G01X962600Y1265400D02*
Y1268600D01*
G01Y1277400D02*
Y1280600D01*
G01Y1273400D02*
Y1276600D01*
G01Y1269400D02*
Y1272600D01*
G01Y1281400D02*
Y1284600D01*
G01X965900Y1292900D02*
X969100D01*
G01X965900Y1299100D02*
Y1292900D01*
G01X969100D02*
Y1299100D01*
G01X962600Y1285400D02*
Y1288600D01*
G01X965000Y1289500D02*
Y1301500D01*
G01X969100Y1299100D02*
X965900D01*
G01X979868Y1305797D02*
Y1303575D01*
X979715Y1303110D01*
X979408Y1302800D01*
X979025Y1302697D01*
X978642Y1302800D01*
X978335Y1303110D01*
X978182Y1303575D01*
Y1305797D01*
G01X976653Y1305280D02*
X976423Y1305590D01*
X976155Y1305745D01*
X975848Y1305797D01*
X975465Y1305694D01*
X975197Y1305435D01*
X975120Y1305125D01*
X975158Y1304815D01*
X975312Y1304557D01*
X976078Y1304040D01*
X976423Y1303679D01*
X976653Y1303162D01*
X976730Y1302697D01*
X975120D01*
G01X973553Y1305280D02*
X973323Y1305590D01*
X973055Y1305745D01*
X972748Y1305797D01*
X972365Y1305694D01*
X972097Y1305435D01*
X972020Y1305125D01*
X972058Y1304815D01*
X972212Y1304557D01*
X972978Y1304040D01*
X973323Y1303679D01*
X973553Y1303162D01*
X973630Y1302697D01*
X972020D01*
G01X978534Y1310615D02*
X973483Y1315666D01*
G01X966183Y1310615D02*
Y1341717D01*
G01X968432Y1310615D02*
X966183D01*
G01X973483Y1315666D02*
X968432Y1310615D01*
G01X966183Y1341717D02*
X980783D01*
G01X962623Y1504523D02*
Y1510723D01*
G01X986155Y175883D02*
Y182083D01*
G01X982955Y175883D02*
X986155D01*
G01X982955Y182083D02*
Y175883D01*
G01X986155Y182083D02*
X982955D01*
G01X978007Y1237920D02*
Y1249920D01*
G01X977122Y1272140D02*
Y1291746D01*
G01X990630Y1272140D02*
X977122D01*
G01X990630Y1291746D02*
Y1272140D01*
G01X990061Y1297986D02*
Y1295764D01*
X989908Y1295299D01*
X989601Y1294989D01*
X989218Y1294886D01*
X988835Y1294989D01*
X988528Y1295299D01*
X988375Y1295764D01*
Y1297986D01*
G01X986961Y1295351D02*
X986731Y1295093D01*
X986463Y1294938D01*
X986118Y1294886D01*
X985773Y1294989D01*
X985505Y1295196D01*
X985313Y1295558D01*
X985275Y1295971D01*
X985351Y1296384D01*
X985543Y1296643D01*
X985811Y1296849D01*
X986080Y1296901D01*
X986348Y1296849D01*
X986693Y1296643D01*
X986578Y1297986D01*
X985543D01*
G01X983018D02*
X983325Y1297883D01*
X983555Y1297624D01*
X983708Y1297314D01*
X983823Y1296901D01*
X983861Y1296436D01*
X983823Y1295971D01*
X983708Y1295558D01*
X983555Y1295248D01*
X983325Y1294989D01*
X983018Y1294886D01*
X982711Y1294989D01*
X982481Y1295248D01*
X982328Y1295558D01*
X982213Y1295971D01*
X982175Y1296436D01*
X982213Y1296901D01*
X982328Y1297314D01*
X982481Y1297624D01*
X982711Y1297883D01*
X983018Y1297986D01*
G01X979573Y1291746D02*
X983876Y1287443D01*
G01X977122Y1291746D02*
X979573D01*
G01X988179D02*
X990630D01*
G01X983876Y1287443D02*
X988179Y1291746D01*
G01X980783Y1310615D02*
X978534D01*
G01X980783Y1341717D02*
Y1310615D01*
G01X1047736Y1420331D02*
G02I-31496J0D01*
G01X992769Y1268726D02*
Y1265526D01*
G01X998969D02*
Y1268726D01*
G01X992769Y1265526D02*
X998969D01*
G01X1003740Y1277368D02*
Y1274168D01*
G01X1009940Y1277368D02*
X1003740D01*
G01Y1274168D02*
X1009940D01*
G01X1003819Y1281351D02*
Y1278151D01*
G01X1010019Y1281351D02*
X1003819D01*
G01Y1278151D02*
X1010019D01*
G01X998969Y1268726D02*
X992769D01*
G01X1003769Y1273343D02*
Y1270143D01*
G01X1009969Y1273343D02*
X1003769D01*
G01Y1270143D02*
X1009969D01*
G01X1023511Y204728D02*
X1020311D01*
G01D02*
Y198528D01*
G01D02*
X1023511D01*
G01X1014967Y212228D02*
Y206028D01*
G01D02*
X1018167D01*
G01D02*
Y212228D01*
G01D02*
X1014967D01*
G01X1014906Y519046D02*
Y525246D01*
G01X1011706D02*
Y519046D01*
G01D02*
X1014906D01*
G01Y525246D02*
X1011706D01*
G01X1009940Y1274168D02*
Y1277368D01*
G01X1010019Y1278151D02*
Y1281351D01*
G01X1009969Y1270143D02*
Y1273343D01*
G01X1008644Y1281787D02*
X1020644D01*
G01X1008644Y1287787D02*
Y1281787D01*
G01X1020644D02*
Y1287787D01*
G01X1009627Y1291696D02*
Y1288496D01*
G01X1015827Y1291696D02*
X1009627D01*
G01X1015827Y1288496D02*
Y1291696D01*
G01X1009627Y1288496D02*
X1015827D01*
G01X1012677Y1292668D02*
Y1295868D01*
G01X1006477Y1292668D02*
X1012677D01*
G01X1006477Y1295868D02*
Y1292668D01*
G01X1012677Y1295868D02*
X1006477D01*
G01X1020644Y1287787D02*
X1008644D01*
G01X1089155Y204724D02*
G02I-31496J0D01*
G01X1023511Y198528D02*
Y204728D01*
G01X1042201Y752865D02*
Y749665D01*
G01X1048401Y752865D02*
X1042201D01*
G01X1048401Y749665D02*
Y752865D01*
G01X1042201Y749665D02*
X1048401D01*
G01X1039465Y755504D02*
X1051465D01*
G01X1039465Y761504D02*
Y755504D01*
G01X1051465Y761504D02*
X1039465D01*
G01X1045340Y762165D02*
X1051540D01*
G01X1045340Y765365D02*
Y762165D01*
G01X1051540Y765365D02*
X1045340D01*
G01Y768865D02*
Y765665D01*
G01X1051540Y768865D02*
X1045340D01*
G01Y765665D02*
X1051540D01*
G01X1067607Y761504D02*
X1055607D01*
G01Y755504D02*
X1067607D01*
G01X1055607Y761504D02*
Y755504D01*
G01X1051465D02*
Y761504D01*
G01X1061732Y762165D02*
Y765365D01*
G01X1055532Y762165D02*
X1061732D01*
G01X1055532Y765365D02*
Y762165D01*
G01X1061732Y765365D02*
X1055532D01*
G01Y768899D02*
Y765699D01*
G01X1061732Y768899D02*
X1055532D01*
G01X1061732Y765699D02*
Y768899D01*
G01X1055532Y765699D02*
X1061732D01*
G01X1051540Y762165D02*
Y765365D01*
G01Y765665D02*
Y768865D01*
G01X1055532Y769499D02*
X1061732D01*
Y772699D01*
X1055532D01*
Y769499D01*
G01X1062432Y962565D02*
Y959365D01*
G01X1068632Y962565D02*
X1062432D01*
G01Y959365D02*
X1068632D01*
G01X1062368Y1328109D02*
X1065568D01*
G01X1062368Y1334309D02*
Y1328109D01*
G01X1065568D02*
Y1334309D01*
G01D02*
X1062368D01*
G01X1116976Y605378D02*
G02I-22900J0D01*
G01X1072701Y753365D02*
Y750165D01*
G01X1078901Y753365D02*
X1072701D01*
G01X1078901Y750165D02*
Y753365D01*
G01X1072701Y750165D02*
X1078901D01*
G01X1069166Y755504D02*
X1081166D01*
G01X1069166Y761504D02*
Y755504D01*
G01X1081166Y761504D02*
X1069166D01*
G01X1067607Y755504D02*
Y761504D01*
G01X1075041Y762165D02*
X1081241D01*
G01X1075041Y765365D02*
Y762165D01*
G01X1081241Y765365D02*
X1075041D01*
G01Y768865D02*
Y765665D01*
G01X1081241Y768865D02*
X1075041D01*
G01Y765665D02*
X1081241D01*
G01X1068632Y959365D02*
Y962565D01*
G01X1082209Y1314016D02*
X1084449D01*
G01X1083236Y1312391D02*
Y1315641D01*
G01X1074674Y1320184D02*
X1092390D01*
G01X1074674Y1355880D02*
Y1320184D01*
G01X1072732Y1324632D02*
Y1336632D01*
G01X1066732Y1324632D02*
X1072732D01*
G01X1066732Y1336632D02*
Y1324632D01*
G01X1072732Y1336632D02*
X1066732D01*
G01X1083232Y1358719D02*
Y1361145D01*
G01X1092390Y1355880D02*
X1074674D01*
G01X1073641Y1366095D02*
X1076841D01*
G01X1073641Y1372295D02*
Y1366095D01*
G01X1076841Y1372295D02*
X1073641D01*
G01X1076841Y1366095D02*
Y1372295D01*
G01X1071524Y1372418D02*
Y1378618D01*
G01X1068324Y1372418D02*
X1071524D01*
G01X1068324Y1378618D02*
Y1372418D01*
G01X1071524Y1378618D02*
X1068324D01*
G01X1069156Y1407996D02*
X1068926Y1407634D01*
X1068620Y1407428D01*
X1068275Y1407376D01*
X1067968Y1407428D01*
X1067661Y1407686D01*
X1067470Y1407996D01*
X1067431Y1408306D01*
X1067508Y1408668D01*
X1067776Y1408926D01*
X1068045Y1409029D01*
X1068390D01*
G01X1068045D02*
X1067815Y1409184D01*
X1067623Y1409443D01*
X1067546Y1409753D01*
X1067623Y1410063D01*
X1067815Y1410321D01*
X1068160Y1410476D01*
X1068505Y1410424D01*
X1068850Y1410218D01*
G01X1068363Y1427676D02*
Y1430776D01*
X1068823Y1430156D01*
G01Y1427676D02*
X1067903D01*
G01X1077263Y1639778D02*
X1077033Y1639416D01*
X1076727Y1639210D01*
X1076382Y1639158D01*
X1076075Y1639210D01*
X1075768Y1639468D01*
X1075577Y1639778D01*
X1075538Y1640088D01*
X1075615Y1640450D01*
X1075883Y1640708D01*
X1076152Y1640811D01*
X1076497D01*
G01X1076152D02*
X1075922Y1640966D01*
X1075730Y1641225D01*
X1075653Y1641535D01*
X1075730Y1641845D01*
X1075922Y1642103D01*
X1076267Y1642258D01*
X1076612Y1642206D01*
X1076957Y1642000D01*
G01X1076470Y1659458D02*
Y1662558D01*
X1076930Y1661938D01*
G01Y1659458D02*
X1076010D01*
G01X1097308Y761504D02*
X1085308D01*
G01Y755504D02*
X1097308D01*
G01X1085308Y761504D02*
Y755504D01*
G01X1081166D02*
Y761504D01*
G01X1091433Y762165D02*
Y765365D01*
G01X1085233Y762165D02*
X1091433D01*
G01X1085233Y765365D02*
Y762165D01*
G01X1091433Y765365D02*
X1085233D01*
G01Y768899D02*
Y765699D01*
G01X1091433Y768899D02*
X1085233D01*
G01X1091433Y765699D02*
Y768899D01*
G01X1085233Y765699D02*
X1091433D01*
G01X1081241Y762165D02*
Y765365D01*
G01Y765665D02*
Y768865D01*
G01X1085233Y769499D02*
X1091433D01*
Y772699D01*
X1085233D01*
Y769499D01*
G01X1092133Y962565D02*
Y959365D01*
G01X1098333Y962565D02*
X1092133D01*
G01Y959365D02*
X1098333D01*
G01X1085396Y1301221D02*
X1088496D01*
Y1302141D01*
X1088341Y1302448D01*
X1087979Y1302678D01*
X1087566Y1302755D01*
X1087153Y1302678D01*
X1086843Y1302486D01*
X1086688Y1302141D01*
Y1301221D01*
G01X1088238Y1305931D02*
X1088393Y1305701D01*
X1088496Y1305433D01*
Y1305126D01*
X1088341Y1304781D01*
X1088083Y1304513D01*
X1087773Y1304321D01*
X1087256Y1304168D01*
X1086791Y1304130D01*
X1086326Y1304206D01*
X1086016Y1304321D01*
X1085706Y1304551D01*
X1085499Y1304820D01*
X1085396Y1305088D01*
Y1305356D01*
X1085499Y1305625D01*
X1085654Y1305855D01*
X1085861Y1306046D01*
G01X1085396Y1308188D02*
X1088496D01*
X1087876Y1307728D01*
G01X1085396D02*
Y1308648D01*
G01X1086688Y1310560D02*
X1087049Y1310828D01*
X1087256Y1311058D01*
X1087359Y1311365D01*
X1087256Y1311633D01*
X1087049Y1311825D01*
X1086739Y1311978D01*
X1086378Y1312016D01*
X1086068Y1311978D01*
X1085758Y1311825D01*
X1085499Y1311595D01*
X1085396Y1311326D01*
X1085499Y1311020D01*
X1085809Y1310751D01*
X1086274Y1310598D01*
X1086791Y1310560D01*
X1087463Y1310636D01*
X1087824Y1310751D01*
X1088186Y1310943D01*
X1088444Y1311211D01*
X1088496Y1311480D01*
X1088393Y1311748D01*
X1088134Y1311940D01*
G01X1088496Y1314388D02*
X1088393Y1314081D01*
X1088134Y1313851D01*
X1087824Y1313698D01*
X1087411Y1313583D01*
X1086946Y1313545D01*
X1086481Y1313583D01*
X1086068Y1313698D01*
X1085758Y1313851D01*
X1085499Y1314081D01*
X1085396Y1314388D01*
X1085499Y1314695D01*
X1085758Y1314925D01*
X1086068Y1315078D01*
X1086481Y1315193D01*
X1086946Y1315231D01*
X1087411Y1315193D01*
X1087824Y1315078D01*
X1088134Y1314925D01*
X1088393Y1314695D01*
X1088496Y1314388D01*
G01X1092390Y1320184D02*
Y1355880D01*
G01X1094296Y1324649D02*
X1100296D01*
G01X1094296Y1336649D02*
Y1324649D01*
G01X1100296Y1336649D02*
X1094296D01*
G01X1094133Y1371292D02*
Y1359292D01*
G01X1100133Y1371292D02*
X1094133D01*
G01Y1359292D02*
X1100133D01*
G01X1085755Y1371292D02*
Y1359292D01*
G01X1091755Y1371292D02*
X1085755D01*
G01X1091755Y1359292D02*
Y1371292D01*
G01X1085755Y1359292D02*
X1091755D01*
G01Y1374535D02*
Y1386535D01*
G01X1085755Y1374535D02*
X1091755D01*
G01X1085755Y1386535D02*
Y1374535D01*
G01X1091755Y1386535D02*
X1085755D01*
G01X1086083Y1787213D02*
Y1668906D01*
G01X1101201Y753365D02*
Y750165D01*
G01X1107401Y753365D02*
X1101201D01*
G01X1107401Y750165D02*
Y753365D01*
G01X1101201Y750165D02*
X1107401D01*
G01X1098867Y755504D02*
X1110867D01*
G01X1098867Y761504D02*
Y755504D01*
G01X1110867Y761504D02*
X1098867D01*
G01X1097308Y755504D02*
Y761504D01*
G01X1104741Y762165D02*
X1110941D01*
G01X1104741Y765365D02*
Y762165D01*
G01X1110941Y765365D02*
X1104741D01*
G01Y768865D02*
Y765665D01*
G01X1110941Y768865D02*
X1104741D01*
G01Y765665D02*
X1110941D01*
G01X1098333Y959365D02*
Y962565D01*
G01X1108732Y1324732D02*
Y1336732D01*
G01X1102732Y1324732D02*
X1108732D01*
G01X1102732Y1336732D02*
Y1324732D01*
G01X1100296Y1324649D02*
Y1336649D01*
G01X1108732Y1336732D02*
X1102732D01*
G01X1114976Y1358320D02*
Y1360746D01*
G01X1100924Y1372418D02*
X1104124D01*
G01X1100924Y1378618D02*
Y1372418D01*
G01X1104124D02*
Y1378618D01*
G01X1106241Y1366095D02*
X1109441D01*
G01X1106241Y1372295D02*
Y1366095D01*
G01X1109441Y1372295D02*
X1106241D01*
G01X1109441Y1366095D02*
Y1372295D01*
G01X1100133Y1359292D02*
Y1371292D01*
G01X1104124Y1378618D02*
X1100924D01*
G01X1127009Y761504D02*
X1115009D01*
G01Y755504D02*
X1127009D01*
G01X1115009Y761504D02*
Y755504D01*
G01X1110867D02*
Y761504D01*
G01X1121134Y762165D02*
Y765365D01*
G01X1114934Y762165D02*
X1121134D01*
G01X1114934Y765365D02*
Y762165D01*
G01X1121134Y765365D02*
X1114934D01*
G01Y768899D02*
Y765699D01*
G01X1121134Y768899D02*
X1114934D01*
G01X1121134Y765699D02*
Y768899D01*
G01X1114934Y765699D02*
X1121134D01*
G01X1110941Y762165D02*
Y765365D01*
G01Y765665D02*
Y768865D01*
G01X1114934Y769499D02*
X1121134D01*
Y772699D01*
X1114934D01*
Y769499D01*
G01X1121833Y962565D02*
Y959365D01*
G01X1128033Y962565D02*
X1121833D01*
G01Y959365D02*
X1128033D01*
G01X1114596Y1301251D02*
X1117696D01*
Y1302171D01*
X1117541Y1302478D01*
X1117179Y1302708D01*
X1116766Y1302785D01*
X1116353Y1302708D01*
X1116043Y1302516D01*
X1115888Y1302171D01*
Y1301251D01*
G01X1117438Y1305961D02*
X1117593Y1305731D01*
X1117696Y1305463D01*
Y1305156D01*
X1117541Y1304811D01*
X1117283Y1304543D01*
X1116973Y1304351D01*
X1116456Y1304198D01*
X1115991Y1304160D01*
X1115526Y1304236D01*
X1115216Y1304351D01*
X1114906Y1304581D01*
X1114699Y1304850D01*
X1114596Y1305118D01*
Y1305386D01*
X1114699Y1305655D01*
X1114854Y1305885D01*
X1115061Y1306076D01*
G01X1114596Y1308218D02*
X1117696D01*
X1117076Y1307758D01*
G01X1114596D02*
Y1308678D01*
G01X1115888Y1310590D02*
X1116249Y1310858D01*
X1116456Y1311088D01*
X1116559Y1311395D01*
X1116456Y1311663D01*
X1116249Y1311855D01*
X1115939Y1312008D01*
X1115578Y1312046D01*
X1115268Y1312008D01*
X1114958Y1311855D01*
X1114699Y1311625D01*
X1114596Y1311356D01*
X1114699Y1311050D01*
X1115009Y1310781D01*
X1115474Y1310628D01*
X1115991Y1310590D01*
X1116663Y1310666D01*
X1117024Y1310781D01*
X1117386Y1310973D01*
X1117644Y1311241D01*
X1117696Y1311510D01*
X1117593Y1311778D01*
X1117334Y1311970D01*
G01X1115061Y1313575D02*
X1114803Y1313805D01*
X1114648Y1314073D01*
X1114596Y1314418D01*
X1114699Y1314763D01*
X1114906Y1315031D01*
X1115268Y1315223D01*
X1115681Y1315261D01*
X1116094Y1315185D01*
X1116353Y1314993D01*
X1116559Y1314725D01*
X1116611Y1314456D01*
X1116559Y1314188D01*
X1116353Y1313843D01*
X1117696Y1313958D01*
Y1314993D01*
G01X1118309Y1314216D02*
X1120549D01*
G01X1119336Y1312591D02*
Y1315841D01*
G01X1110774Y1320384D02*
X1128490D01*
G01X1110774Y1356080D02*
Y1320384D01*
G01X1128490Y1356080D02*
X1110774D01*
G01X1118355Y1371292D02*
Y1359292D01*
G01X1124355Y1371292D02*
X1118355D01*
G01X1124355Y1359292D02*
Y1371292D01*
G01X1118355Y1359292D02*
X1124355D01*
G01Y1374535D02*
Y1386535D01*
G01X1118355Y1374535D02*
X1124355D01*
G01X1118355Y1386535D02*
Y1374535D01*
G01X1124355Y1386535D02*
X1118355D01*
G01X1121365Y1635703D02*
X1124565D01*
G01X1121365Y1641903D02*
Y1635703D01*
G01X1124565D02*
Y1641903D01*
G01X1124828Y1651823D02*
Y1658023D01*
G01X1121628Y1651823D02*
X1124828D01*
G01X1121628Y1658023D02*
Y1651823D01*
G01X1124565Y1641903D02*
X1121365D01*
G01X1120002Y1652378D02*
Y1658578D01*
G01X1116802Y1652378D02*
X1120002D01*
G01X1116802Y1658578D02*
Y1652378D01*
G01X1113614Y1651113D02*
Y1647913D01*
G01X1119814Y1651113D02*
X1113614D01*
G01X1119814Y1647913D02*
Y1651113D01*
G01X1113614Y1647913D02*
X1119814D01*
G01X1124828Y1658023D02*
X1121628D01*
G01X1120002Y1658578D02*
X1116802D01*
G01X1127600Y1680100D02*
X1124400D01*
G01D02*
Y1673900D01*
G01D02*
X1127600D01*
G01X1130701Y753365D02*
Y750165D01*
G01X1136901Y753365D02*
X1130701D01*
G01X1136901Y750165D02*
Y753365D01*
G01X1130701Y750165D02*
X1136901D01*
G01X1128568Y755504D02*
X1140568D01*
G01X1128568Y761504D02*
Y755504D01*
G01X1140568Y761504D02*
X1128568D01*
G01X1127009Y755504D02*
Y761504D01*
G01X1134442Y762165D02*
X1140642D01*
G01X1134442Y765365D02*
Y762165D01*
G01X1140642Y765365D02*
X1134442D01*
G01Y768865D02*
Y765665D01*
G01X1140642Y768865D02*
X1134442D01*
G01Y765665D02*
X1140642D01*
G01X1128033Y959365D02*
Y962565D01*
G01X1128490Y1320384D02*
Y1356080D01*
G01X1138304Y1324649D02*
X1144304D01*
G01X1138304Y1336649D02*
Y1324649D01*
G01X1136596D02*
Y1336649D01*
G01X1130596Y1324649D02*
X1136596D01*
G01X1130596Y1336649D02*
Y1324649D01*
G01X1144304Y1336649D02*
X1138304D01*
G01X1136596D02*
X1130596D01*
G01X1133624Y1372418D02*
X1136824D01*
G01X1133624Y1378618D02*
Y1372418D01*
G01X1136824D02*
Y1378618D01*
G01X1138941Y1366095D02*
X1142141D01*
G01X1138941Y1372295D02*
Y1366095D01*
G01X1142141Y1372295D02*
X1138941D01*
G01X1132733Y1359292D02*
Y1371292D01*
G01X1126733D02*
Y1359292D01*
G01X1132733Y1371292D02*
X1126733D01*
G01Y1359292D02*
X1132733D01*
G01X1136824Y1378618D02*
X1133624D01*
G01X1127900Y1633900D02*
X1131100D01*
G01X1127900Y1640100D02*
Y1633900D01*
G01X1131100Y1640100D02*
X1127900D01*
G01X1131100Y1633900D02*
Y1640100D01*
G01X1136907Y1648175D02*
Y1651375D01*
G01X1130707Y1648175D02*
X1136907D01*
G01X1130707Y1651375D02*
Y1648175D01*
G01X1136907Y1651375D02*
X1130707D01*
G01X1136249Y1651945D02*
Y1658145D01*
G01X1133049Y1651945D02*
X1136249D01*
G01X1133049Y1658145D02*
Y1651945D01*
G01X1136249Y1658145D02*
X1133049D01*
G01X1134864Y1680918D02*
X1141064D01*
G01X1134864Y1684118D02*
Y1680918D01*
G01X1141064Y1684118D02*
X1134864D01*
G01X1133609Y1684165D02*
X1127409D01*
G01D02*
Y1680965D01*
G01D02*
X1133609D01*
G01D02*
Y1684165D01*
G01X1127409Y1687665D02*
Y1684465D01*
G01D02*
X1133609D01*
G01D02*
Y1687665D01*
G01X1138996Y1675537D02*
Y1672337D01*
G01X1145196Y1675537D02*
X1138996D01*
G01Y1672337D02*
X1145196D01*
G01X1127600Y1673900D02*
Y1680100D01*
G01X1131900Y1677400D02*
X1138100D01*
G01D02*
Y1680600D01*
G01D02*
X1131900D01*
G01D02*
Y1677400D01*
G01X1144600Y1680600D02*
X1138400D01*
G01D02*
Y1677400D01*
G01D02*
X1144600D01*
G01X1127900Y1680100D02*
Y1673900D01*
G01D02*
X1131100D01*
G01Y1680100D02*
X1127900D01*
G01X1131100Y1673900D02*
Y1680100D01*
G01X1133609Y1687665D02*
X1127409D01*
G01X1156710Y761504D02*
X1144710D01*
G01Y755504D02*
X1156710D01*
G01X1144710Y761504D02*
Y755504D01*
G01X1140568D02*
Y761504D01*
G01X1150835Y762165D02*
Y765365D01*
G01X1144635Y762165D02*
X1150835D01*
G01X1144635Y765365D02*
Y762165D01*
G01X1150835Y765365D02*
X1144635D01*
G01Y768899D02*
Y765699D01*
G01X1150835Y768899D02*
X1144635D01*
G01X1150835Y765699D02*
Y768899D01*
G01X1144635Y765699D02*
X1150835D01*
G01X1140642Y762165D02*
Y765365D01*
G01Y765665D02*
Y768865D01*
G01X1144635Y769499D02*
X1150835D01*
Y772699D01*
X1144635D01*
Y769499D01*
G01X1151534Y962565D02*
Y959365D01*
G01X1157734Y962565D02*
X1151534D01*
G01Y959365D02*
X1157734D01*
G01X1152012Y1324649D02*
Y1336649D01*
G01X1146012Y1324649D02*
X1152012D01*
G01X1146012Y1336649D02*
Y1324649D01*
G01X1153720D02*
X1159720D01*
G01X1153720Y1336649D02*
Y1324649D01*
G01X1144304D02*
Y1336649D01*
G01X1152012D02*
X1146012D01*
G01X1159720D02*
X1153720D01*
G01X1142141Y1366095D02*
Y1372295D01*
G01X1151055Y1371292D02*
Y1359292D01*
G01X1157055Y1371292D02*
X1151055D01*
G01Y1359292D02*
X1157055D01*
G01X1151055Y1374535D02*
X1157055D01*
G01X1151055Y1386535D02*
Y1374535D01*
G01X1157055Y1386535D02*
X1151055D01*
G01X1141420Y1383580D02*
X1147420D01*
Y1395580D01*
X1141420D01*
Y1383580D01*
G01X1141064Y1680918D02*
Y1684118D01*
G01X1145196Y1672337D02*
Y1675537D01*
G01X1146347Y1674305D02*
X1149547D01*
G01X1146347Y1680505D02*
Y1674305D01*
G01X1149547Y1680505D02*
X1146347D01*
G01X1149547Y1674305D02*
Y1680505D01*
G01X1153600Y1674400D02*
Y1680600D01*
G01D02*
X1150400D01*
G01D02*
Y1674400D01*
G01D02*
X1153600D01*
G01X1144600Y1677400D02*
Y1680600D01*
G01X1160201Y753365D02*
Y750165D01*
G01X1166401Y753365D02*
X1160201D01*
G01X1166401Y750165D02*
Y753365D01*
G01X1160201Y750165D02*
X1166401D01*
G01X1158268Y755504D02*
X1170268D01*
G01X1158268Y761504D02*
Y755504D01*
G01X1170268Y761504D02*
X1158268D01*
G01X1156710Y755504D02*
Y761504D01*
G01X1164143Y762165D02*
X1170343D01*
G01X1164143Y765365D02*
Y762165D01*
G01X1170343Y765365D02*
X1164143D01*
G01Y768865D02*
Y765665D01*
G01X1170343Y768865D02*
X1164143D01*
G01Y765665D02*
X1170343D01*
G01X1157734Y959365D02*
Y962565D01*
G01X1169232Y1324632D02*
Y1336632D01*
G01X1163232Y1324632D02*
X1169232D01*
G01X1163232Y1336632D02*
Y1324632D01*
G01X1159720Y1324649D02*
Y1336649D01*
G01X1169232Y1336632D02*
X1163232D01*
G01X1171952Y1357860D02*
Y1360286D01*
G01X1166524Y1372418D02*
X1169724D01*
G01X1166524Y1378618D02*
Y1372418D01*
G01X1169724D02*
Y1378618D01*
G01X1159433Y1371292D02*
Y1359292D01*
G01X1165433Y1371292D02*
X1159433D01*
G01X1165433Y1359292D02*
Y1371292D01*
G01X1159433Y1359292D02*
X1165433D01*
G01X1157055D02*
Y1371292D01*
G01X1169724Y1378618D02*
X1166524D01*
G01X1157055Y1374535D02*
Y1386535D01*
G01X1178422Y-21871D02*
Y-38151D01*
X1188022D01*
Y-21871D01*
X1178422D01*
G01Y-1871D02*
Y-18151D01*
X1188022D01*
Y-1871D01*
X1178422D01*
G01Y18129D02*
Y1849D01*
X1188022D01*
Y18129D01*
X1178422D01*
G01X1179201Y749665D02*
X1185401D01*
G01X1179201Y752865D02*
Y749665D01*
G01X1185401Y752865D02*
X1179201D01*
G01X1172201D02*
Y749665D01*
G01X1178401Y752865D02*
X1172201D01*
G01X1178401Y749665D02*
Y752865D01*
G01X1172201Y749665D02*
X1178401D01*
G01X1186410Y761504D02*
X1174410D01*
G01Y755504D02*
X1186410D01*
G01X1174410Y761504D02*
Y755504D01*
G01X1170268D02*
Y761504D01*
G01X1180535Y762165D02*
Y765365D01*
G01X1174335Y762165D02*
X1180535D01*
G01X1174335Y765365D02*
Y762165D01*
G01X1180535Y765365D02*
X1174335D01*
G01Y768899D02*
Y765699D01*
G01X1180535Y768899D02*
X1174335D01*
G01X1180535Y765699D02*
Y768899D01*
G01X1174335Y765699D02*
X1180535D01*
G01X1170343Y762165D02*
Y765365D01*
G01Y765665D02*
Y768865D01*
G01X1174335Y769499D02*
X1180535D01*
Y772699D01*
X1174335D01*
Y769499D01*
G01X1181235Y962565D02*
Y959365D01*
G01X1187435Y962565D02*
X1181235D01*
G01Y959365D02*
X1187435D01*
G01X1183266Y1300641D02*
X1186366D01*
Y1301561D01*
X1186211Y1301868D01*
X1185849Y1302098D01*
X1185436Y1302175D01*
X1185023Y1302098D01*
X1184713Y1301906D01*
X1184558Y1301561D01*
Y1300641D01*
G01X1186108Y1305351D02*
X1186263Y1305121D01*
X1186366Y1304853D01*
Y1304546D01*
X1186211Y1304201D01*
X1185953Y1303933D01*
X1185643Y1303741D01*
X1185126Y1303588D01*
X1184661Y1303550D01*
X1184196Y1303626D01*
X1183886Y1303741D01*
X1183576Y1303971D01*
X1183369Y1304240D01*
X1183266Y1304508D01*
Y1304776D01*
X1183369Y1305045D01*
X1183524Y1305275D01*
X1183731Y1305466D01*
G01X1183266Y1307608D02*
X1186366D01*
X1185746Y1307148D01*
G01X1183266D02*
Y1308068D01*
G01X1184558Y1309980D02*
X1184919Y1310248D01*
X1185126Y1310478D01*
X1185229Y1310785D01*
X1185126Y1311053D01*
X1184919Y1311245D01*
X1184609Y1311398D01*
X1184248Y1311436D01*
X1183938Y1311398D01*
X1183628Y1311245D01*
X1183369Y1311015D01*
X1183266Y1310746D01*
X1183369Y1310440D01*
X1183679Y1310171D01*
X1184144Y1310018D01*
X1184661Y1309980D01*
X1185333Y1310056D01*
X1185694Y1310171D01*
X1186056Y1310363D01*
X1186314Y1310631D01*
X1186366Y1310900D01*
X1186263Y1311168D01*
X1186004Y1311360D01*
G01X1185849Y1313080D02*
X1186159Y1313310D01*
X1186314Y1313578D01*
X1186366Y1313885D01*
X1186263Y1314268D01*
X1186004Y1314536D01*
X1185694Y1314613D01*
X1185384Y1314575D01*
X1185126Y1314421D01*
X1184609Y1313655D01*
X1184248Y1313310D01*
X1183731Y1313080D01*
X1183266Y1313003D01*
Y1314613D01*
G01X1179409Y1314116D02*
X1181649D01*
G01X1180436Y1312491D02*
Y1315741D01*
G01X1171874Y1320284D02*
X1189590D01*
G01X1171874Y1355980D02*
Y1320284D01*
G01X1189590Y1355980D02*
X1171874D01*
G01X1175041Y1366095D02*
Y1372295D01*
G01X1171841Y1366095D02*
X1175041D01*
G01X1171841Y1372295D02*
Y1366095D01*
G01X1175041Y1372295D02*
X1171841D01*
G01X1183955Y1371292D02*
Y1359292D01*
G01X1189955Y1371292D02*
X1183955D01*
G01Y1359292D02*
X1189955D01*
G01X1183955Y1374535D02*
X1189955D01*
G01X1183955Y1386535D02*
Y1374535D01*
G01X1189955Y1386535D02*
X1183955D01*
G01X1181252Y1536247D02*
Y1530247D01*
X1193252D01*
Y1536247D01*
X1181252D01*
G01X1179524Y1669309D02*
Y1679423D01*
G01X1171384Y1669309D02*
X1179524D01*
G01X1171384Y1679423D02*
Y1669309D01*
G01X1179524Y1679423D02*
X1171384D01*
G01X1179743Y1692100D02*
Y1689878D01*
X1179590Y1689413D01*
X1179283Y1689103D01*
X1178900Y1689000D01*
X1178517Y1689103D01*
X1178210Y1689413D01*
X1178057Y1689878D01*
Y1692100D01*
G01X1175340Y1689000D02*
Y1692100D01*
X1176758Y1689878D01*
X1174842D01*
G01X1173352Y1689362D02*
X1173083Y1689103D01*
X1172777Y1689000D01*
X1172470Y1689103D01*
X1172202Y1689413D01*
X1172010Y1689878D01*
X1171933Y1690343D01*
Y1690912D01*
X1172010Y1691377D01*
X1172202Y1691790D01*
X1172432Y1691997D01*
X1172700Y1692100D01*
X1173007Y1691997D01*
X1173237Y1691790D01*
X1173390Y1691480D01*
X1173467Y1691067D01*
X1173390Y1690705D01*
X1173198Y1690343D01*
X1172968Y1690137D01*
X1172700Y1690085D01*
X1172393Y1690188D01*
X1172163Y1690447D01*
X1171933Y1690912D01*
G01X1199947Y-34242D02*
X1199637Y-34050D01*
X1199430Y-33820D01*
X1199327Y-33552D01*
X1199430Y-33245D01*
X1199637Y-33015D01*
X1199947Y-32785D01*
X1200360Y-32708D01*
X1202427D01*
G01X1199327Y-30375D02*
X1199379Y-30107D01*
X1199534Y-29800D01*
X1199792Y-29608D01*
X1200154Y-29532D01*
X1200515Y-29608D01*
X1200825Y-29838D01*
X1200980Y-30183D01*
Y-30567D01*
X1201084Y-30797D01*
X1201342Y-30988D01*
X1201704Y-31065D01*
X1202065Y-30950D01*
X1202324Y-30682D01*
X1202427Y-30375D01*
X1202324Y-30068D01*
X1202065Y-29800D01*
X1201704Y-29685D01*
X1201342Y-29762D01*
X1201084Y-29953D01*
X1200980Y-30183D01*
Y-30567D01*
X1200825Y-30912D01*
X1200515Y-31142D01*
X1200154Y-31218D01*
X1199792Y-31142D01*
X1199534Y-30950D01*
X1199379Y-30643D01*
X1199327Y-30375D01*
G01X1201910Y-28003D02*
X1202220Y-27773D01*
X1202375Y-27505D01*
X1202427Y-27198D01*
X1202324Y-26815D01*
X1202065Y-26547D01*
X1201755Y-26470D01*
X1201445Y-26508D01*
X1201187Y-26662D01*
X1200670Y-27428D01*
X1200309Y-27773D01*
X1199792Y-28003D01*
X1199327Y-28080D01*
Y-26470D01*
G01X1199719Y-15501D02*
X1199409Y-15309D01*
X1199202Y-15079D01*
X1199099Y-14811D01*
X1199202Y-14504D01*
X1199409Y-14274D01*
X1199719Y-14044D01*
X1200132Y-13967D01*
X1202199D01*
G01X1199099Y-11634D02*
X1202199D01*
X1201579Y-12094D01*
G01X1199099D02*
Y-11174D01*
G01Y-8534D02*
X1202199D01*
X1201579Y-8994D01*
G01X1199099D02*
Y-8074D01*
G01X1199461Y-6086D02*
X1199202Y-5817D01*
X1199099Y-5511D01*
X1199202Y-5204D01*
X1199512Y-4936D01*
X1199977Y-4744D01*
X1200442Y-4667D01*
X1201011D01*
X1201476Y-4744D01*
X1201889Y-4936D01*
X1202096Y-5166D01*
X1202199Y-5434D01*
X1202096Y-5741D01*
X1201889Y-5971D01*
X1201579Y-6124D01*
X1201166Y-6201D01*
X1200804Y-6124D01*
X1200442Y-5932D01*
X1200236Y-5702D01*
X1200184Y-5434D01*
X1200287Y-5127D01*
X1200546Y-4897D01*
X1201011Y-4667D01*
G01X1200290Y5980D02*
X1199980Y6172D01*
X1199773Y6402D01*
X1199670Y6670D01*
X1199773Y6977D01*
X1199980Y7207D01*
X1200290Y7437D01*
X1200703Y7514D01*
X1202770D01*
G01X1199670Y9847D02*
X1199722Y10115D01*
X1199877Y10422D01*
X1200135Y10614D01*
X1200497Y10690D01*
X1200858Y10614D01*
X1201168Y10384D01*
X1201323Y10039D01*
Y9655D01*
X1201427Y9425D01*
X1201685Y9234D01*
X1202047Y9157D01*
X1202408Y9272D01*
X1202667Y9540D01*
X1202770Y9847D01*
X1202667Y10154D01*
X1202408Y10422D01*
X1202047Y10537D01*
X1201685Y10460D01*
X1201427Y10269D01*
X1201323Y10039D01*
Y9655D01*
X1201168Y9310D01*
X1200858Y9080D01*
X1200497Y9004D01*
X1200135Y9080D01*
X1199877Y9272D01*
X1199722Y9579D01*
X1199670Y9847D01*
G01X1200962Y12219D02*
X1201323Y12487D01*
X1201530Y12717D01*
X1201633Y13024D01*
X1201530Y13292D01*
X1201323Y13484D01*
X1201013Y13637D01*
X1200652Y13675D01*
X1200342Y13637D01*
X1200032Y13484D01*
X1199773Y13254D01*
X1199670Y12985D01*
X1199773Y12679D01*
X1200083Y12410D01*
X1200548Y12257D01*
X1201065Y12219D01*
X1201737Y12295D01*
X1202098Y12410D01*
X1202460Y12602D01*
X1202718Y12870D01*
X1202770Y13139D01*
X1202667Y13407D01*
X1202408Y13599D01*
G01X1185401Y749665D02*
Y752865D01*
G01X1187969Y755504D02*
X1199969D01*
G01X1187969Y761504D02*
Y755504D01*
G01X1199969Y761504D02*
X1187969D01*
G01X1186410Y755504D02*
Y761504D01*
G01X1193844Y762165D02*
X1200044D01*
G01X1193844Y765365D02*
Y762165D01*
G01X1200044Y765365D02*
X1193844D01*
G01Y768865D02*
Y765665D01*
G01X1200044Y768865D02*
X1193844D01*
G01Y765665D02*
X1200044D01*
G01X1187435Y959365D02*
Y962565D01*
G01X1189590Y1320284D02*
Y1355980D01*
G01X1198732Y1325032D02*
X1204732D01*
G01X1198732Y1337032D02*
Y1325032D01*
G01X1204732Y1337032D02*
X1198732D01*
G01X1199324Y1372418D02*
X1202524D01*
G01X1199324Y1378618D02*
Y1372418D01*
G01X1192333Y1371292D02*
Y1359292D01*
G01X1198333Y1371292D02*
X1192333D01*
G01X1198333Y1359292D02*
Y1371292D01*
G01X1192333Y1359292D02*
X1198333D01*
G01X1189955D02*
Y1371292D01*
G01X1202524Y1378618D02*
X1199324D01*
G01X1189955Y1374535D02*
Y1386535D01*
G01X1186400Y1394900D02*
X1192600D01*
G01D02*
Y1398100D01*
G01D02*
X1186400D01*
G01D02*
Y1394900D01*
G01Y1399400D02*
X1192600D01*
G01D02*
Y1402600D01*
G01D02*
X1186400D01*
G01D02*
Y1399400D01*
G01X1195400D02*
X1201600D01*
G01Y1402600D02*
X1195400D01*
G01D02*
Y1399400D01*
G01X1203730Y1395254D02*
Y1392154D01*
G01X1204612Y1395254D02*
X1202848D01*
G01X1201397Y1392154D02*
Y1395254D01*
X1200477D01*
X1200170Y1395099D01*
X1199940Y1394737D01*
X1199863Y1394324D01*
X1199940Y1393911D01*
X1200132Y1393601D01*
X1200477Y1393446D01*
X1201397D01*
G01X1198258D02*
X1197990Y1393807D01*
X1197760Y1394014D01*
X1197453Y1394117D01*
X1197185Y1394014D01*
X1196993Y1393807D01*
X1196840Y1393497D01*
X1196802Y1393136D01*
X1196840Y1392826D01*
X1196993Y1392516D01*
X1197223Y1392257D01*
X1197492Y1392154D01*
X1197798Y1392257D01*
X1198067Y1392567D01*
X1198220Y1393032D01*
X1198258Y1393549D01*
X1198182Y1394221D01*
X1198067Y1394582D01*
X1197875Y1394944D01*
X1197607Y1395202D01*
X1197338Y1395254D01*
X1197070Y1395151D01*
X1196878Y1394892D01*
G01X1186400Y1412900D02*
X1192600D01*
G01D02*
Y1416100D01*
G01D02*
X1186400D01*
G01D02*
Y1412900D01*
G01X1192600Y1403900D02*
Y1407100D01*
G01D02*
X1186400D01*
G01D02*
Y1403900D01*
G01D02*
X1192600D01*
G01X1186400Y1408400D02*
X1192600D01*
G01D02*
Y1411600D01*
G01D02*
X1186400D01*
G01D02*
Y1408400D01*
G01X1195400D02*
X1201600D01*
G01Y1411600D02*
X1195400D01*
G01D02*
Y1408400D01*
G01Y1417400D02*
X1201600D01*
G01X1195400Y1420600D02*
Y1417400D01*
G01Y1412900D02*
X1201600D01*
G01Y1416100D02*
X1195400D01*
G01D02*
Y1412900D01*
G01X1201600Y1420600D02*
X1195400D01*
G01Y1422400D02*
X1201600D01*
G01Y1425600D02*
X1195400D01*
G01D02*
Y1422400D01*
G01X1199290Y1521943D02*
X1201530D01*
G01X1200317Y1520318D02*
Y1523568D01*
G01X1196685Y1524980D02*
X1232425D01*
Y1541910D01*
X1196685D01*
Y1524980D01*
G01X1195485Y1524978D02*
X1196685D01*
G01X1195485D02*
X1195491Y1541961D01*
G01X1196085Y1524978D02*
X1196081Y1541953D01*
G01X1196685Y1524978D02*
X1196682Y1541918D01*
G01X1195535Y1541911D02*
X1197044Y1541907D01*
G01X1196052Y1573738D02*
X1192852D01*
G01X1196052Y1567538D02*
Y1573738D01*
G01X1192852Y1567538D02*
X1196052D01*
G01X1192852Y1573738D02*
Y1567538D01*
G01X1189294Y1570612D02*
X1192494D01*
G01X1189294Y1576812D02*
Y1570612D01*
G01X1192494Y1576812D02*
X1189294D01*
G01X1192494Y1570612D02*
Y1576812D01*
G01X1197577Y1573738D02*
Y1567538D01*
X1200777D01*
Y1573738D01*
X1197577D01*
G01X1212494Y265733D02*
Y259533D01*
G01D02*
X1215694D01*
G01Y265733D02*
X1212494D01*
G01X1217366Y295074D02*
X1217673Y295126D01*
X1217941Y295332D01*
X1218171Y295642D01*
X1218324Y296004D01*
X1218401Y296417D01*
Y296831D01*
X1218324Y297244D01*
X1218171Y297606D01*
X1217941Y297916D01*
X1217673Y298122D01*
X1217366Y298174D01*
X1217059Y298122D01*
X1216791Y297916D01*
X1216561Y297606D01*
X1216408Y297244D01*
X1216331Y296831D01*
Y296417D01*
X1216408Y296004D01*
X1216561Y295642D01*
X1216791Y295332D01*
X1217059Y295126D01*
X1217366Y295074D01*
G01X1217059Y295901D02*
X1216599Y295074D01*
G01X1214994Y296366D02*
X1214726Y296727D01*
X1214496Y296934D01*
X1214189Y297037D01*
X1213921Y296934D01*
X1213729Y296727D01*
X1213576Y296417D01*
X1213538Y296056D01*
X1213576Y295746D01*
X1213729Y295436D01*
X1213959Y295177D01*
X1214228Y295074D01*
X1214534Y295177D01*
X1214803Y295487D01*
X1214956Y295952D01*
X1214994Y296469D01*
X1214918Y297141D01*
X1214803Y297502D01*
X1214611Y297864D01*
X1214343Y298122D01*
X1214074Y298174D01*
X1213806Y298071D01*
X1213614Y297812D01*
G01X1211166Y298174D02*
X1211473Y298071D01*
X1211703Y297812D01*
X1211856Y297502D01*
X1211971Y297089D01*
X1212009Y296624D01*
X1211971Y296159D01*
X1211856Y295746D01*
X1211703Y295436D01*
X1211473Y295177D01*
X1211166Y295074D01*
X1210859Y295177D01*
X1210629Y295436D01*
X1210476Y295746D01*
X1210361Y296159D01*
X1210323Y296624D01*
X1210361Y297089D01*
X1210476Y297502D01*
X1210629Y297812D01*
X1210859Y298071D01*
X1211166Y298174D01*
G01X1208066D02*
X1208373Y298071D01*
X1208603Y297812D01*
X1208756Y297502D01*
X1208871Y297089D01*
X1208909Y296624D01*
X1208871Y296159D01*
X1208756Y295746D01*
X1208603Y295436D01*
X1208373Y295177D01*
X1208066Y295074D01*
X1207759Y295177D01*
X1207529Y295436D01*
X1207376Y295746D01*
X1207261Y296159D01*
X1207223Y296624D01*
X1207261Y297089D01*
X1207376Y297502D01*
X1207529Y297812D01*
X1207759Y298071D01*
X1208066Y298174D01*
G01X1204966D02*
X1205273Y298071D01*
X1205503Y297812D01*
X1205656Y297502D01*
X1205771Y297089D01*
X1205809Y296624D01*
X1205771Y296159D01*
X1205656Y295746D01*
X1205503Y295436D01*
X1205273Y295177D01*
X1204966Y295074D01*
X1204659Y295177D01*
X1204429Y295436D01*
X1204276Y295746D01*
X1204161Y296159D01*
X1204123Y296624D01*
X1204161Y297089D01*
X1204276Y297502D01*
X1204429Y297812D01*
X1204659Y298071D01*
X1204966Y298174D01*
G01X1214816Y293838D02*
X1212916Y291638D01*
G01D02*
X1211016Y293838D01*
G01D02*
X1207669D01*
G01D02*
Y285176D01*
G01D02*
X1218163D01*
G01X1216111Y761504D02*
X1204111D01*
G01Y755504D02*
X1216111D01*
G01X1204111Y761504D02*
Y755504D01*
G01X1199969D02*
Y761504D01*
G01X1213105Y762165D02*
Y765365D01*
G01X1206905Y762165D02*
X1213105D01*
G01X1206905Y765365D02*
Y762165D01*
G01X1213105Y765365D02*
X1206905D01*
G01Y769265D02*
Y766065D01*
G01X1213105Y769265D02*
X1206905D01*
G01X1213105Y766065D02*
Y769265D01*
G01X1206905Y766065D02*
X1213105D01*
G01X1200044Y762165D02*
Y765365D01*
G01Y765665D02*
Y768865D01*
G01X1206905Y769865D02*
X1213105D01*
Y773065D01*
X1206905D01*
Y769865D01*
G01X1208357Y959365D02*
Y962565D01*
G01X1202157Y959365D02*
X1208357D01*
G01X1202157Y962565D02*
Y959365D01*
G01X1208357Y962565D02*
X1202157D01*
G01X1213632Y1325032D02*
Y1337032D01*
G01X1207632Y1325032D02*
X1213632D01*
G01X1207632Y1337032D02*
Y1325032D01*
G01X1204732D02*
Y1337032D01*
G01X1213632D02*
X1207632D01*
G01X1204641Y1366095D02*
X1207841D01*
G01X1204641Y1372295D02*
Y1366095D01*
G01X1207841Y1372295D02*
X1204641D01*
G01X1207841Y1366095D02*
Y1372295D01*
G01X1202524Y1372418D02*
Y1378618D01*
G01X1201600Y1399400D02*
Y1402600D01*
G01Y1408400D02*
Y1411600D01*
G01Y1417400D02*
Y1420600D01*
G01Y1412900D02*
Y1416100D01*
G01Y1422400D02*
Y1425600D01*
G01X1219412Y1523434D02*
X1219642Y1523589D01*
X1219910Y1523692D01*
X1220217D01*
X1220562Y1523537D01*
X1220830Y1523279D01*
X1221022Y1522969D01*
X1221175Y1522452D01*
X1221213Y1521987D01*
X1221137Y1521522D01*
X1221022Y1521212D01*
X1220792Y1520902D01*
X1220523Y1520695D01*
X1220255Y1520592D01*
X1219987D01*
X1219718Y1520695D01*
X1219488Y1520850D01*
X1219297Y1521057D01*
G01X1217232Y1520592D02*
X1217155Y1521264D01*
X1217040Y1521832D01*
X1216887Y1522349D01*
X1216695Y1522917D01*
X1216388Y1523692D01*
X1217922D01*
G01X1214055D02*
X1214362Y1523589D01*
X1214592Y1523330D01*
X1214745Y1523020D01*
X1214860Y1522607D01*
X1214898Y1522142D01*
X1214860Y1521677D01*
X1214745Y1521264D01*
X1214592Y1520954D01*
X1214362Y1520695D01*
X1214055Y1520592D01*
X1213748Y1520695D01*
X1213518Y1520954D01*
X1213365Y1521264D01*
X1213250Y1521677D01*
X1213212Y1522142D01*
X1213250Y1522607D01*
X1213365Y1523020D01*
X1213518Y1523330D01*
X1213748Y1523589D01*
X1214055Y1523692D01*
G01X1210955D02*
X1211262Y1523589D01*
X1211492Y1523330D01*
X1211645Y1523020D01*
X1211760Y1522607D01*
X1211798Y1522142D01*
X1211760Y1521677D01*
X1211645Y1521264D01*
X1211492Y1520954D01*
X1211262Y1520695D01*
X1210955Y1520592D01*
X1210648Y1520695D01*
X1210418Y1520954D01*
X1210265Y1521264D01*
X1210150Y1521677D01*
X1210112Y1522142D01*
X1210150Y1522607D01*
X1210265Y1523020D01*
X1210418Y1523330D01*
X1210648Y1523589D01*
X1210955Y1523692D01*
G01X1207855Y1520592D02*
X1207587Y1520644D01*
X1207280Y1520799D01*
X1207088Y1521057D01*
X1207012Y1521419D01*
X1207088Y1521780D01*
X1207318Y1522090D01*
X1207663Y1522245D01*
X1208047D01*
X1208277Y1522349D01*
X1208468Y1522607D01*
X1208545Y1522969D01*
X1208430Y1523330D01*
X1208162Y1523589D01*
X1207855Y1523692D01*
X1207548Y1523589D01*
X1207280Y1523330D01*
X1207165Y1522969D01*
X1207242Y1522607D01*
X1207433Y1522349D01*
X1207663Y1522245D01*
X1208047D01*
X1208392Y1522090D01*
X1208622Y1521780D01*
X1208698Y1521419D01*
X1208622Y1521057D01*
X1208430Y1520799D01*
X1208123Y1520644D01*
X1207855Y1520592D01*
G01X1205502Y1573738D02*
X1202302D01*
G01X1205502Y1567538D02*
Y1573738D01*
G01X1202302Y1567538D02*
X1205502D01*
G01X1202302Y1573738D02*
Y1567538D01*
G01X1207026Y1573738D02*
Y1567538D01*
X1210226D01*
Y1573738D01*
X1207026D01*
G01X1211751D02*
Y1567538D01*
X1214951D01*
Y1573738D01*
X1211751D01*
G01X1221431Y-34354D02*
X1221121Y-34162D01*
X1220914Y-33932D01*
X1220811Y-33664D01*
X1220914Y-33357D01*
X1221121Y-33127D01*
X1221431Y-32897D01*
X1221844Y-32820D01*
X1223911D01*
G01X1220811Y-30487D02*
X1223911D01*
X1223291Y-30947D01*
G01X1220811D02*
Y-30027D01*
G01Y-27387D02*
X1223911D01*
X1223291Y-27847D01*
G01X1220811D02*
Y-26927D01*
G01Y-23827D02*
X1223911D01*
X1221689Y-25245D01*
Y-23329D01*
G01X1221317Y-13330D02*
X1221007Y-13138D01*
X1220800Y-12908D01*
X1220697Y-12640D01*
X1220800Y-12333D01*
X1221007Y-12103D01*
X1221317Y-11873D01*
X1221730Y-11796D01*
X1223797D01*
G01X1220697Y-9540D02*
X1221369Y-9463D01*
X1221937Y-9348D01*
X1222454Y-9195D01*
X1223022Y-9003D01*
X1223797Y-8696D01*
Y-10230D01*
G01Y-6363D02*
X1223694Y-6670D01*
X1223435Y-6900D01*
X1223125Y-7053D01*
X1222712Y-7168D01*
X1222247Y-7206D01*
X1221782Y-7168D01*
X1221369Y-7053D01*
X1221059Y-6900D01*
X1220800Y-6670D01*
X1220697Y-6363D01*
X1220800Y-6056D01*
X1221059Y-5826D01*
X1221369Y-5673D01*
X1221782Y-5558D01*
X1222247Y-5520D01*
X1222712Y-5558D01*
X1223125Y-5673D01*
X1223435Y-5826D01*
X1223694Y-6056D01*
X1223797Y-6363D01*
G01X1221087Y4265D02*
X1220777Y4457D01*
X1220570Y4687D01*
X1220467Y4955D01*
X1220570Y5262D01*
X1220777Y5492D01*
X1221087Y5722D01*
X1221500Y5799D01*
X1223567D01*
G01X1220467Y8132D02*
X1223567D01*
X1222947Y7672D01*
G01X1220467D02*
Y8592D01*
G01Y11232D02*
X1223567D01*
X1222947Y10772D01*
G01X1220467D02*
Y11692D01*
G01X1220932Y13489D02*
X1220674Y13719D01*
X1220519Y13987D01*
X1220467Y14332D01*
X1220570Y14677D01*
X1220777Y14945D01*
X1221139Y15137D01*
X1221552Y15175D01*
X1221965Y15099D01*
X1222224Y14907D01*
X1222430Y14639D01*
X1222482Y14370D01*
X1222430Y14102D01*
X1222224Y13757D01*
X1223567Y13872D01*
Y14907D01*
G01X1228494Y265733D02*
Y259533D01*
G01D02*
X1231694D01*
G01Y265733D02*
X1228494D01*
G01X1220494D02*
Y259533D01*
G01D02*
X1223694D01*
G01D02*
Y265733D01*
G01D02*
X1220494D01*
G01X1215694Y259533D02*
Y265733D01*
G01X1232323Y277737D02*
X1232630Y277789D01*
X1232898Y277995D01*
X1233128Y278305D01*
X1233281Y278667D01*
X1233358Y279080D01*
Y279494D01*
X1233281Y279907D01*
X1233128Y280269D01*
X1232898Y280579D01*
X1232630Y280785D01*
X1232323Y280837D01*
X1232016Y280785D01*
X1231748Y280579D01*
X1231518Y280269D01*
X1231365Y279907D01*
X1231288Y279494D01*
Y279080D01*
X1231365Y278667D01*
X1231518Y278305D01*
X1231748Y277995D01*
X1232016Y277789D01*
X1232323Y277737D01*
G01X1232016Y278564D02*
X1231556Y277737D01*
G01X1229223D02*
X1228955Y277789D01*
X1228648Y277944D01*
X1228456Y278202D01*
X1228380Y278564D01*
X1228456Y278925D01*
X1228686Y279235D01*
X1229031Y279390D01*
X1229415D01*
X1229645Y279494D01*
X1229836Y279752D01*
X1229913Y280114D01*
X1229798Y280475D01*
X1229530Y280734D01*
X1229223Y280837D01*
X1228916Y280734D01*
X1228648Y280475D01*
X1228533Y280114D01*
X1228610Y279752D01*
X1228801Y279494D01*
X1229031Y279390D01*
X1229415D01*
X1229760Y279235D01*
X1229990Y278925D01*
X1230066Y278564D01*
X1229990Y278202D01*
X1229798Y277944D01*
X1229491Y277789D01*
X1229223Y277737D01*
G01X1226200D02*
X1226123Y278409D01*
X1226008Y278977D01*
X1225855Y279494D01*
X1225663Y280062D01*
X1225356Y280837D01*
X1226890D01*
G01X1223694Y298041D02*
Y304241D01*
G01X1220494D02*
Y298041D01*
G01D02*
X1223694D01*
G01X1227694D02*
Y304241D01*
G01X1224494D02*
Y298041D01*
G01D02*
X1227694D01*
G01X1230816Y293838D02*
X1228916Y291638D01*
G01D02*
X1227016Y293838D01*
G01D02*
X1223669D01*
G01D02*
Y285176D01*
G01D02*
X1234163D01*
G01X1218163Y293838D02*
X1214816D01*
G01X1218163Y285176D02*
Y293838D01*
G01X1220494Y313241D02*
Y307041D01*
G01D02*
X1223694D01*
G01D02*
Y313241D01*
G01D02*
X1220494D01*
G01X1227694Y307041D02*
Y313241D01*
G01D02*
X1224494D01*
G01D02*
Y307041D01*
G01D02*
X1227694D01*
G01X1223694Y304241D02*
X1220494D01*
G01X1227694D02*
X1224494D01*
G01X1216111Y755504D02*
Y761504D01*
G01X1224334Y775782D02*
X1227534D01*
G01X1224334Y781982D02*
Y775782D01*
G01X1227534D02*
Y781982D01*
G01X1228334Y775782D02*
X1231534D01*
G01X1228334Y781982D02*
Y775782D01*
G01X1227534Y781982D02*
X1224334D01*
G01X1231534D02*
X1228334D01*
G01X1220740Y997559D02*
X1232945Y985748D01*
G01X1220740Y1040867D02*
Y997559D01*
G01X1232945Y1052678D02*
X1220740Y1040867D01*
G01X1224296Y1325032D02*
X1230296D01*
G01X1224296Y1337032D02*
Y1325032D01*
G01X1221796Y1325049D02*
Y1337049D01*
G01X1215796Y1325049D02*
X1221796D01*
G01X1215796Y1337049D02*
Y1325049D01*
G01X1230296Y1337032D02*
X1224296D01*
G01X1221796Y1337049D02*
X1215796D01*
G01X1225133Y1371292D02*
Y1359292D01*
G01X1231133Y1371292D02*
X1225133D01*
G01Y1359292D02*
X1231133D01*
G01X1222755D02*
Y1371292D01*
G01X1216755D02*
Y1359292D01*
G01X1222755Y1371292D02*
X1216755D01*
G01Y1359292D02*
X1222755D01*
G01Y1374535D02*
Y1386535D01*
G01X1216755Y1374535D02*
X1222755D01*
G01X1216755Y1386535D02*
Y1374535D01*
G01X1222755Y1386535D02*
X1216755D01*
G01X1229400Y1406900D02*
X1232600D01*
G01Y1413100D02*
X1229400D01*
G01D02*
Y1406900D01*
G01X1227100D02*
Y1413100D01*
G01D02*
X1223900D01*
G01D02*
Y1406900D01*
G01D02*
X1227100D01*
G01X1227400Y1418600D02*
Y1415400D01*
G01D02*
X1233600D01*
G01Y1418600D02*
X1227400D01*
G01X1227833Y1523818D02*
X1230259D01*
G01X1224399Y1573738D02*
X1221199D01*
G01X1224399Y1567538D02*
Y1573738D01*
G01X1221199Y1567538D02*
X1224399D01*
G01X1221199Y1573738D02*
Y1567538D01*
G01X1219675Y1573738D02*
X1216475D01*
G01X1219675Y1567538D02*
Y1573738D01*
G01X1216475Y1567538D02*
X1219675D01*
G01X1216475Y1573738D02*
Y1567538D01*
G01X1229124Y1573738D02*
X1225924D01*
G01X1229124Y1567538D02*
Y1573738D01*
G01X1225924Y1567538D02*
X1229124D01*
G01X1225924Y1573738D02*
Y1567538D01*
G01X1222046Y1646023D02*
Y1781456D01*
G01X1224800Y1646023D02*
X1222046D01*
G01X1230700Y1736067D02*
X1223200D01*
Y1733827D01*
X1223575Y1733080D01*
X1224450Y1732520D01*
X1225450Y1732333D01*
X1226450Y1732520D01*
X1227200Y1732987D01*
X1227575Y1733827D01*
Y1736067D01*
G01X1230700Y1728567D02*
X1223200D01*
Y1726233D01*
X1223575Y1725487D01*
X1224075Y1725020D01*
X1225075Y1724833D01*
X1226075Y1725020D01*
X1226700Y1725580D01*
X1227075Y1726233D01*
Y1728567D01*
G01Y1726233D02*
X1230700Y1724833D01*
G01Y1717333D02*
Y1721067D01*
X1223200D01*
Y1717333D01*
G01X1226825Y1718827D02*
Y1721067D01*
G01X1229700Y1713660D02*
X1230325Y1712913D01*
X1230700Y1712073D01*
Y1711327D01*
X1230325Y1710580D01*
X1229700Y1710020D01*
X1228825Y1709740D01*
X1227950Y1709927D01*
X1227200Y1710393D01*
X1226700Y1711233D01*
X1226450Y1712353D01*
X1225950Y1713007D01*
X1225075Y1713287D01*
X1224200Y1713100D01*
X1223575Y1712633D01*
X1223200Y1711980D01*
Y1711327D01*
X1223450Y1710673D01*
X1224075Y1710113D01*
G01X1229700Y1706160D02*
X1230325Y1705413D01*
X1230700Y1704573D01*
Y1703827D01*
X1230325Y1703080D01*
X1229700Y1702520D01*
X1228825Y1702240D01*
X1227950Y1702427D01*
X1227200Y1702893D01*
X1226700Y1703733D01*
X1226450Y1704853D01*
X1225950Y1705507D01*
X1225075Y1705787D01*
X1224200Y1705600D01*
X1223575Y1705133D01*
X1223200Y1704480D01*
Y1703827D01*
X1223450Y1703173D01*
X1224075Y1702613D01*
G01X1228200Y1697913D02*
Y1695487D01*
G01X1230700Y1690973D02*
X1223200D01*
Y1687427D01*
G01X1226825Y1688733D02*
Y1690973D01*
G01X1223200Y1682820D02*
Y1680580D01*
G01Y1681700D02*
X1230700D01*
G01Y1682820D02*
Y1680580D01*
G01X1223200Y1674200D02*
X1230700D01*
G01X1223200Y1676347D02*
Y1672053D01*
G01X1222046Y1781456D02*
X1312203D01*
G01X1244822Y-38151D02*
Y-21871D01*
X1235222D01*
Y-38151D01*
X1244822D01*
G01Y-18151D02*
Y-1871D01*
X1235222D01*
Y-18151D01*
X1244822D01*
G01Y1849D02*
Y18129D01*
X1235222D01*
Y1849D01*
X1244822D01*
G01X1244061Y155710D02*
Y161910D01*
X1240861D01*
Y155710D01*
X1244061D01*
G01X1240861Y165060D02*
Y158860D01*
X1244061D01*
Y165060D01*
X1240861D01*
G01X1244494Y265733D02*
Y259533D01*
G01D02*
X1247694D01*
G01Y265733D02*
X1244494D01*
G01X1236494D02*
Y259533D01*
G01D02*
X1239694D01*
G01D02*
Y265733D01*
G01D02*
X1236494D01*
G01X1231694Y259533D02*
Y265733D01*
G01X1234338Y298385D02*
X1237685D01*
G01D02*
X1239585Y300585D01*
G01D02*
X1241485Y298385D01*
G01D02*
X1244832D01*
G01X1234338Y307047D02*
Y298385D01*
G01X1234163Y293838D02*
X1230816D01*
G01X1234163Y285176D02*
Y293838D01*
G01X1243965Y309171D02*
X1244272Y309223D01*
X1244540Y309429D01*
X1244770Y309739D01*
X1244923Y310101D01*
X1245000Y310514D01*
Y310928D01*
X1244923Y311341D01*
X1244770Y311703D01*
X1244540Y312013D01*
X1244272Y312219D01*
X1243965Y312271D01*
X1243658Y312219D01*
X1243390Y312013D01*
X1243160Y311703D01*
X1243007Y311341D01*
X1242930Y310928D01*
Y310514D01*
X1243007Y310101D01*
X1243160Y309739D01*
X1243390Y309429D01*
X1243658Y309223D01*
X1243965Y309171D01*
G01X1243658Y309998D02*
X1243198Y309171D01*
G01X1240865D02*
Y312271D01*
X1241325Y311651D01*
G01Y309171D02*
X1240405D01*
G01X1237305D02*
Y312271D01*
X1238723Y310049D01*
X1236807D01*
G01X1234205Y309171D02*
Y312271D01*
X1235623Y310049D01*
X1233707D01*
G01X1244832Y307047D02*
X1234338D01*
G01X1231534Y775782D02*
Y781982D01*
G01X1241777Y798088D02*
X1238577D01*
G01X1241777Y791888D02*
Y798088D01*
G01X1238577Y791888D02*
X1241777D01*
G01X1238577Y798088D02*
Y791888D01*
G01X1236777Y798088D02*
X1233577D01*
G01X1236777Y791888D02*
Y798088D01*
G01X1233577Y791888D02*
X1236777D01*
G01X1233577Y798088D02*
Y791888D01*
G01X1232945Y820394D02*
G03X1242787Y810552I9842J0D01*
G01X1232945Y985748D02*
Y820394D01*
G01X1312638Y810552D02*
X1242787D01*
G01X1232945Y1211700D02*
Y1052678D01*
G01X1242787Y1227874D02*
G03X1233187Y1220200I0J-9842D01*
G01X1312638Y1227874D02*
X1242787D01*
G01X1243344Y1312653D02*
Y1315079D01*
G01X1242632Y1319949D02*
X1245832D01*
G01X1242632Y1326149D02*
Y1319949D01*
G01X1245832Y1326149D02*
X1242632D01*
G01X1240515Y1326272D02*
Y1332472D01*
G01X1237315Y1326272D02*
X1240515D01*
G01X1237315Y1332472D02*
Y1326272D01*
G01X1230296Y1325032D02*
Y1337032D01*
G01X1240515Y1332472D02*
X1237315D01*
G01X1231133Y1359292D02*
Y1371292D01*
G01X1232600Y1406900D02*
Y1413100D01*
G01X1233600Y1415400D02*
Y1418600D01*
G01X1238013Y1523192D02*
X1235587D01*
G01X1269711Y1541910D02*
X1233971D01*
Y1524980D01*
X1269711D01*
Y1541910D01*
G01X1233848Y1573738D02*
X1230648D01*
G01X1233848Y1567538D02*
Y1573738D01*
G01X1230648Y1567538D02*
X1233848D01*
G01X1230648Y1573738D02*
Y1567538D01*
G01X1235373Y1573738D02*
Y1567538D01*
X1238573D01*
Y1573738D01*
X1235373D01*
G01X1249000Y1646023D02*
X1243400D01*
G01X1236800D02*
X1231400D01*
G01X1240411Y1668212D02*
X1237311D01*
X1237931Y1668672D01*
G01X1240411D02*
Y1667752D01*
G01X1235658Y1673177D02*
X1232558D01*
X1235658Y1671413D01*
X1232558D01*
G01X1235658Y1678016D02*
X1232558D01*
X1235141Y1677019D01*
X1232558Y1676022D01*
X1235658D01*
G01X1232558Y1682510D02*
X1235658D01*
Y1680976D01*
G01Y1687311D02*
X1232558D01*
G01Y1685855D02*
X1234470Y1687311D01*
G01X1235658Y1685625D02*
X1233591Y1686660D01*
G01X1235038Y1691959D02*
X1235348Y1691767D01*
X1235555Y1691537D01*
X1235658Y1691269D01*
X1235555Y1690962D01*
X1235348Y1690732D01*
X1235038Y1690502D01*
X1234625Y1690425D01*
X1232558D01*
G01Y1696377D02*
Y1695457D01*
G01Y1695917D02*
X1235658D01*
G01Y1696377D02*
Y1695457D01*
G01X1235652Y1701017D02*
X1232552D01*
G01Y1699407D02*
X1235652D01*
G01X1234102D02*
Y1701017D01*
G01X1234002Y1704782D02*
Y1704015D01*
X1234932D01*
X1235242Y1704245D01*
X1235449Y1704514D01*
X1235552Y1704897D01*
X1235449Y1705280D01*
X1235242Y1705549D01*
X1234932Y1705779D01*
X1234570Y1705932D01*
X1234157Y1706009D01*
X1233795D01*
X1233485Y1705932D01*
X1233124Y1705779D01*
X1232814Y1705549D01*
X1232607Y1705319D01*
X1232452Y1705012D01*
Y1704744D01*
X1232555Y1704437D01*
X1232762Y1704207D01*
G01X1235658Y1710818D02*
X1232558D01*
Y1709362D01*
G01X1234056Y1709898D02*
Y1710818D01*
G01X1235658Y1714047D02*
Y1715581D01*
X1232558D01*
Y1714047D01*
G01X1234056Y1714661D02*
Y1715581D01*
G01X1235658Y1720382D02*
X1232558D01*
Y1719616D01*
X1232713Y1719309D01*
X1232920Y1719079D01*
X1233230Y1718887D01*
X1233591Y1718734D01*
X1234108Y1718696D01*
X1234625Y1718734D01*
X1234986Y1718887D01*
X1235296Y1719079D01*
X1235503Y1719309D01*
X1235658Y1719616D01*
Y1720382D01*
G01X1232816Y1723420D02*
X1232661Y1723650D01*
X1232558Y1723918D01*
Y1724225D01*
X1232713Y1724570D01*
X1232971Y1724838D01*
X1233281Y1725030D01*
X1233798Y1725183D01*
X1234263Y1725221D01*
X1234728Y1725145D01*
X1235038Y1725030D01*
X1235348Y1724800D01*
X1235555Y1724531D01*
X1235658Y1724263D01*
Y1723995D01*
X1235555Y1723726D01*
X1235400Y1723496D01*
X1235193Y1723305D01*
G01X1234005Y1728681D02*
X1233850Y1728528D01*
X1233591Y1728413D01*
X1233230Y1728336D01*
X1232920Y1728413D01*
X1232713Y1728566D01*
X1232558Y1728835D01*
Y1729870D01*
X1235658D01*
Y1728605D01*
X1235451Y1728336D01*
X1235141Y1728183D01*
X1234780Y1728106D01*
X1234418Y1728183D01*
X1234108Y1728413D01*
X1234005Y1728681D01*
Y1729870D01*
G01X1235452Y1735170D02*
X1232352Y1734212D01*
X1235452Y1733254D01*
G01X1234367Y1733599D02*
Y1734825D01*
G01X1252494Y265733D02*
Y259533D01*
G01D02*
X1255694D01*
G01D02*
Y265733D01*
G01D02*
X1252494D01*
G01X1247694Y259533D02*
Y265733D01*
G01X1246185Y304832D02*
Y298632D01*
G01D02*
X1249385D01*
G01D02*
Y304832D01*
G01X1265366Y295074D02*
X1265673Y295126D01*
X1265941Y295332D01*
X1266171Y295642D01*
X1266324Y296004D01*
X1266401Y296417D01*
Y296831D01*
X1266324Y297244D01*
X1266171Y297606D01*
X1265941Y297916D01*
X1265673Y298122D01*
X1265366Y298174D01*
X1265059Y298122D01*
X1264791Y297916D01*
X1264561Y297606D01*
X1264408Y297244D01*
X1264331Y296831D01*
Y296417D01*
X1264408Y296004D01*
X1264561Y295642D01*
X1264791Y295332D01*
X1265059Y295126D01*
X1265366Y295074D01*
G01X1265059Y295901D02*
X1264599Y295074D01*
G01X1262343D02*
X1262266Y295746D01*
X1262151Y296314D01*
X1261998Y296831D01*
X1261806Y297399D01*
X1261499Y298174D01*
X1263033D01*
G01X1259166Y295074D02*
X1258898Y295126D01*
X1258591Y295281D01*
X1258399Y295539D01*
X1258323Y295901D01*
X1258399Y296262D01*
X1258629Y296572D01*
X1258974Y296727D01*
X1259358D01*
X1259588Y296831D01*
X1259779Y297089D01*
X1259856Y297451D01*
X1259741Y297812D01*
X1259473Y298071D01*
X1259166Y298174D01*
X1258859Y298071D01*
X1258591Y297812D01*
X1258476Y297451D01*
X1258553Y297089D01*
X1258744Y296831D01*
X1258974Y296727D01*
X1259358D01*
X1259703Y296572D01*
X1259933Y296262D01*
X1260009Y295901D01*
X1259933Y295539D01*
X1259741Y295281D01*
X1259434Y295126D01*
X1259166Y295074D01*
G01X1260916Y291638D02*
X1259016Y293838D01*
G01D02*
X1255669D01*
G01D02*
Y285176D01*
G01D02*
X1266163D01*
G01X1244832Y298385D02*
Y307047D01*
G01X1249385Y304832D02*
X1246185D01*
G01X1253897Y785797D02*
Y788997D01*
G01X1247697Y785797D02*
X1253897D01*
G01X1247697Y788997D02*
Y785797D01*
G01X1253897Y788997D02*
X1247697D01*
G01X1255577Y799724D02*
X1258777D01*
G01X1255577Y805924D02*
Y799724D01*
G01X1258777Y805924D02*
X1255577D01*
G01X1258777Y799724D02*
Y805924D01*
G01X1251577Y799724D02*
X1254777D01*
G01X1251577Y805924D02*
Y799724D01*
G01X1254777Y805924D02*
X1251577D01*
G01X1254777Y799724D02*
Y805924D01*
G01X1262277D02*
X1259077D01*
G01Y799724D02*
X1262277D01*
G01X1259077Y805924D02*
Y799724D01*
G01X1253534Y1255305D02*
X1256634D01*
Y1256225D01*
X1256479Y1256532D01*
X1256117Y1256762D01*
X1255704Y1256839D01*
X1255291Y1256762D01*
X1254981Y1256570D01*
X1254826Y1256225D01*
Y1255305D01*
G01X1256376Y1260015D02*
X1256531Y1259785D01*
X1256634Y1259517D01*
Y1259210D01*
X1256479Y1258865D01*
X1256221Y1258597D01*
X1255911Y1258405D01*
X1255394Y1258252D01*
X1254929Y1258214D01*
X1254464Y1258290D01*
X1254154Y1258405D01*
X1253844Y1258635D01*
X1253637Y1258904D01*
X1253534Y1259172D01*
Y1259440D01*
X1253637Y1259709D01*
X1253792Y1259939D01*
X1253999Y1260130D01*
G01X1253896Y1261620D02*
X1253637Y1261889D01*
X1253534Y1262195D01*
X1253637Y1262502D01*
X1253947Y1262770D01*
X1254412Y1262962D01*
X1254877Y1263039D01*
X1255446D01*
X1255911Y1262962D01*
X1256324Y1262770D01*
X1256531Y1262540D01*
X1256634Y1262272D01*
X1256531Y1261965D01*
X1256324Y1261735D01*
X1256014Y1261582D01*
X1255601Y1261505D01*
X1255239Y1261582D01*
X1254877Y1261774D01*
X1254671Y1262004D01*
X1254619Y1262272D01*
X1254722Y1262579D01*
X1254981Y1262809D01*
X1255446Y1263039D01*
G01X1253534Y1265295D02*
X1254206Y1265372D01*
X1254774Y1265487D01*
X1255291Y1265640D01*
X1255859Y1265832D01*
X1256634Y1266139D01*
Y1264605D01*
G01X1252367Y1268270D02*
X1254607D01*
G01X1253394Y1266645D02*
Y1269895D01*
G01X1244832Y1274438D02*
X1262548D01*
G01X1244832Y1310134D02*
Y1274438D01*
G01X1262548Y1310134D02*
X1244832D01*
G01X1254746Y1325146D02*
Y1313146D01*
G01D02*
X1260746D01*
G01X1245832Y1319949D02*
Y1326149D01*
G01X1260746Y1325146D02*
X1254746D01*
G01Y1328389D02*
X1260746D01*
G01X1254746Y1340389D02*
Y1328389D01*
G01X1260746Y1340389D02*
X1254746D01*
G01X1263598Y1522564D02*
X1263828Y1522719D01*
X1264096Y1522822D01*
X1264403D01*
X1264748Y1522667D01*
X1265016Y1522409D01*
X1265208Y1522099D01*
X1265361Y1521582D01*
X1265399Y1521117D01*
X1265323Y1520652D01*
X1265208Y1520342D01*
X1264978Y1520032D01*
X1264709Y1519825D01*
X1264441Y1519722D01*
X1264173D01*
X1263904Y1519825D01*
X1263674Y1519980D01*
X1263483Y1520187D01*
G01X1261418Y1519722D02*
X1261341Y1520394D01*
X1261226Y1520962D01*
X1261073Y1521479D01*
X1260881Y1522047D01*
X1260574Y1522822D01*
X1262108D01*
G01X1258241D02*
X1258548Y1522719D01*
X1258778Y1522460D01*
X1258931Y1522150D01*
X1259046Y1521737D01*
X1259084Y1521272D01*
X1259046Y1520807D01*
X1258931Y1520394D01*
X1258778Y1520084D01*
X1258548Y1519825D01*
X1258241Y1519722D01*
X1257934Y1519825D01*
X1257704Y1520084D01*
X1257551Y1520394D01*
X1257436Y1520807D01*
X1257398Y1521272D01*
X1257436Y1521737D01*
X1257551Y1522150D01*
X1257704Y1522460D01*
X1257934Y1522719D01*
X1258241Y1522822D01*
G01X1255141D02*
X1255448Y1522719D01*
X1255678Y1522460D01*
X1255831Y1522150D01*
X1255946Y1521737D01*
X1255984Y1521272D01*
X1255946Y1520807D01*
X1255831Y1520394D01*
X1255678Y1520084D01*
X1255448Y1519825D01*
X1255141Y1519722D01*
X1254834Y1519825D01*
X1254604Y1520084D01*
X1254451Y1520394D01*
X1254336Y1520807D01*
X1254298Y1521272D01*
X1254336Y1521737D01*
X1254451Y1522150D01*
X1254604Y1522460D01*
X1254834Y1522719D01*
X1255141Y1522822D01*
G01X1252693Y1520084D02*
X1252424Y1519825D01*
X1252118Y1519722D01*
X1251811Y1519825D01*
X1251543Y1520135D01*
X1251351Y1520600D01*
X1251274Y1521065D01*
Y1521634D01*
X1251351Y1522099D01*
X1251543Y1522512D01*
X1251773Y1522719D01*
X1252041Y1522822D01*
X1252348Y1522719D01*
X1252578Y1522512D01*
X1252731Y1522202D01*
X1252808Y1521789D01*
X1252731Y1521427D01*
X1252539Y1521065D01*
X1252309Y1520859D01*
X1252041Y1520807D01*
X1251734Y1520910D01*
X1251504Y1521169D01*
X1251274Y1521634D01*
G01X1252746Y1573738D02*
X1249546D01*
G01X1252746Y1567538D02*
Y1573738D01*
G01X1249546Y1567538D02*
X1252746D01*
G01X1249546Y1573738D02*
Y1567538D01*
G01X1248021Y1573738D02*
X1244821D01*
G01X1248021Y1567538D02*
Y1573738D01*
G01X1244821Y1567538D02*
X1248021D01*
G01X1244821Y1573738D02*
Y1567538D01*
G01X1258995Y1573738D02*
Y1567538D01*
X1262195D01*
Y1573738D01*
X1258995D01*
G01X1254270D02*
Y1567538D01*
X1257470D01*
Y1573738D01*
X1254270D01*
G01X1261100Y1646023D02*
X1255100D01*
G01X1255539Y1669055D02*
X1255901Y1668825D01*
X1256107Y1668519D01*
X1256159Y1668174D01*
X1256107Y1667867D01*
X1255849Y1667560D01*
X1255539Y1667369D01*
X1255229Y1667330D01*
X1254867Y1667407D01*
X1254609Y1667675D01*
X1254506Y1667944D01*
Y1668289D01*
G01Y1667944D02*
X1254351Y1667714D01*
X1254092Y1667522D01*
X1253782Y1667445D01*
X1253472Y1667522D01*
X1253214Y1667714D01*
X1253059Y1668059D01*
X1253111Y1668404D01*
X1253317Y1668749D01*
G01X1245702Y1668940D02*
X1245392Y1668710D01*
X1245237Y1668442D01*
X1245185Y1668135D01*
X1245288Y1667752D01*
X1245547Y1667484D01*
X1245857Y1667407D01*
X1246167Y1667445D01*
X1246425Y1667599D01*
X1246942Y1668365D01*
X1247303Y1668710D01*
X1247820Y1668940D01*
X1248285Y1669017D01*
Y1667407D01*
G01X1260494Y265733D02*
Y259533D01*
G01D02*
X1263694D01*
G01D02*
Y265733D01*
G01D02*
X1260494D01*
G01X1268494D02*
Y259533D01*
G01D02*
X1271694D01*
G01D02*
Y265733D01*
G01D02*
X1268494D01*
G01X1281366Y295074D02*
X1281673Y295126D01*
X1281941Y295332D01*
X1282171Y295642D01*
X1282324Y296004D01*
X1282401Y296417D01*
Y296831D01*
X1282324Y297244D01*
X1282171Y297606D01*
X1281941Y297916D01*
X1281673Y298122D01*
X1281366Y298174D01*
X1281059Y298122D01*
X1280791Y297916D01*
X1280561Y297606D01*
X1280408Y297244D01*
X1280331Y296831D01*
Y296417D01*
X1280408Y296004D01*
X1280561Y295642D01*
X1280791Y295332D01*
X1281059Y295126D01*
X1281366Y295074D01*
G01X1281059Y295901D02*
X1280599Y295074D01*
G01X1278343D02*
X1278266Y295746D01*
X1278151Y296314D01*
X1277998Y296831D01*
X1277806Y297399D01*
X1277499Y298174D01*
X1279033D01*
G01X1275818Y295436D02*
X1275549Y295177D01*
X1275243Y295074D01*
X1274936Y295177D01*
X1274668Y295487D01*
X1274476Y295952D01*
X1274399Y296417D01*
Y296986D01*
X1274476Y297451D01*
X1274668Y297864D01*
X1274898Y298071D01*
X1275166Y298174D01*
X1275473Y298071D01*
X1275703Y297864D01*
X1275856Y297554D01*
X1275933Y297141D01*
X1275856Y296779D01*
X1275664Y296417D01*
X1275434Y296211D01*
X1275166Y296159D01*
X1274859Y296262D01*
X1274629Y296521D01*
X1274399Y296986D01*
G01X1275016Y293838D02*
X1271669D01*
G01D02*
Y285176D01*
G01D02*
X1282163D01*
G01X1266163Y293838D02*
X1262816D01*
G01D02*
X1260916Y291638D01*
G01X1266163Y285176D02*
Y293838D01*
G01X1274277Y772724D02*
Y775924D01*
G01X1268077Y772724D02*
X1274277D01*
G01X1268077Y775924D02*
Y772724D01*
G01X1274277Y775924D02*
X1268077D01*
G01X1274277Y768724D02*
Y771924D01*
G01X1268077Y768724D02*
X1274277D01*
G01X1268077Y771924D02*
Y768724D01*
G01X1274277Y771924D02*
X1268077D01*
G01X1266277Y776224D02*
Y779424D01*
G01X1260077Y776224D02*
X1266277D01*
G01X1260077Y779424D02*
Y776224D01*
G01X1270077Y781724D02*
X1276277D01*
G01X1270077Y784924D02*
Y781724D01*
G01X1276277Y784924D02*
X1270077D01*
G01Y785724D02*
X1276277D01*
G01X1270077Y788924D02*
Y785724D01*
G01X1276277Y788924D02*
X1270077D01*
G01X1266277Y779424D02*
X1260077D01*
G01X1266277Y780224D02*
Y783424D01*
G01X1260077Y780224D02*
X1266277D01*
G01X1260077Y783424D02*
Y780224D01*
G01X1266277Y783424D02*
X1260077D01*
G01X1262577Y799724D02*
X1265777D01*
G01X1262577Y805924D02*
Y799724D01*
G01X1265777Y805924D02*
X1262577D01*
G01X1265777Y799724D02*
Y805924D01*
G01X1271577Y799724D02*
X1274777D01*
G01X1271577Y805924D02*
Y799724D01*
G01X1274777Y805924D02*
X1271577D01*
G01X1270777D02*
X1267577D01*
G01X1270777Y799724D02*
Y805924D01*
G01X1267577Y799724D02*
X1270777D01*
G01X1267577Y805924D02*
Y799724D01*
G01X1262277D02*
Y805924D01*
G01X1274254Y1274438D02*
X1291970D01*
G01X1274254Y1310134D02*
Y1274438D01*
G01X1262548D02*
Y1310134D01*
G01X1272350Y1278359D02*
Y1290359D01*
G01X1266350Y1278359D02*
X1272350D01*
G01X1266350Y1290359D02*
Y1278359D01*
G01X1272350Y1290359D02*
X1266350D01*
G01X1291970Y1310134D02*
X1274254D01*
G01X1269124Y1313146D02*
Y1325146D01*
G01X1263124D02*
Y1313146D01*
G01D02*
X1269124D01*
G01X1260746D02*
Y1325146D01*
G01X1270211Y1326244D02*
X1273411D01*
G01X1270211Y1332444D02*
Y1326244D01*
G01X1273411D02*
Y1332444D01*
G01X1269124Y1325146D02*
X1263124D01*
G01X1273411Y1332444D02*
X1270211D01*
G01X1260746Y1328389D02*
Y1340389D01*
G01X1274536Y1533897D02*
X1272296D01*
G01X1273509Y1535522D02*
Y1532272D01*
G01X1270861Y1524979D02*
X1269352Y1524983D01*
G01X1270911Y1541912D02*
X1270905Y1524929D01*
G01X1270311Y1541912D02*
X1270315Y1524937D01*
G01X1269711Y1541912D02*
X1269714Y1524972D01*
G01X1270911Y1541912D02*
X1269711D01*
G01X1263719Y1573738D02*
Y1567538D01*
X1266919D01*
Y1573738D01*
X1263719D01*
G01X1269050D02*
Y1567538D01*
X1272250D01*
Y1573738D01*
X1269050D01*
G01X1272900Y1646023D02*
X1267500D01*
G01X1271442Y1669055D02*
X1271700Y1668825D01*
X1271855Y1668557D01*
X1271907Y1668212D01*
X1271804Y1667867D01*
X1271597Y1667599D01*
X1271235Y1667407D01*
X1270822Y1667369D01*
X1270409Y1667445D01*
X1270150Y1667637D01*
X1269944Y1667905D01*
X1269892Y1668174D01*
X1269944Y1668442D01*
X1270150Y1668787D01*
X1268807Y1668672D01*
Y1667637D01*
G01X1264033Y1667752D02*
X1260933D01*
X1263155Y1669170D01*
Y1667254D01*
G01X1283628Y130173D02*
Y136373D01*
X1280428D01*
Y130173D01*
X1283628D01*
G01X1280428Y139523D02*
Y133323D01*
X1283628D01*
Y139523D01*
X1280428D01*
G01X1284494Y265733D02*
Y259533D01*
G01D02*
X1287694D01*
G01D02*
Y265733D01*
G01D02*
X1284494D01*
G01X1276494D02*
Y259533D01*
G01D02*
X1279694D01*
G01D02*
Y265733D01*
G01D02*
X1276494D01*
G01X1295541Y294900D02*
X1295848Y294952D01*
X1296116Y295158D01*
X1296346Y295468D01*
X1296499Y295830D01*
X1296576Y296243D01*
Y296657D01*
X1296499Y297070D01*
X1296346Y297432D01*
X1296116Y297742D01*
X1295848Y297948D01*
X1295541Y298000D01*
X1295234Y297948D01*
X1294966Y297742D01*
X1294736Y297432D01*
X1294583Y297070D01*
X1294506Y296657D01*
Y296243D01*
X1294583Y295830D01*
X1294736Y295468D01*
X1294966Y295158D01*
X1295234Y294952D01*
X1295541Y294900D01*
G01X1295234Y295727D02*
X1294774Y294900D01*
G01X1292441D02*
X1292173Y294952D01*
X1291866Y295107D01*
X1291674Y295365D01*
X1291598Y295727D01*
X1291674Y296088D01*
X1291904Y296398D01*
X1292249Y296553D01*
X1292633D01*
X1292863Y296657D01*
X1293054Y296915D01*
X1293131Y297277D01*
X1293016Y297638D01*
X1292748Y297897D01*
X1292441Y298000D01*
X1292134Y297897D01*
X1291866Y297638D01*
X1291751Y297277D01*
X1291828Y296915D01*
X1292019Y296657D01*
X1292249Y296553D01*
X1292633D01*
X1292978Y296398D01*
X1293208Y296088D01*
X1293284Y295727D01*
X1293208Y295365D01*
X1293016Y295107D01*
X1292709Y294952D01*
X1292441Y294900D01*
G01X1289341Y298000D02*
X1289648Y297897D01*
X1289878Y297638D01*
X1290031Y297328D01*
X1290146Y296915D01*
X1290184Y296450D01*
X1290146Y295985D01*
X1290031Y295572D01*
X1289878Y295262D01*
X1289648Y295003D01*
X1289341Y294900D01*
X1289034Y295003D01*
X1288804Y295262D01*
X1288651Y295572D01*
X1288536Y295985D01*
X1288498Y296450D01*
X1288536Y296915D01*
X1288651Y297328D01*
X1288804Y297638D01*
X1289034Y297897D01*
X1289341Y298000D01*
G01X1291016Y293838D02*
X1287669D01*
G01D02*
Y285176D01*
G01D02*
X1298163D01*
G01X1282163Y293838D02*
X1278816D01*
G01D02*
X1276916Y291638D01*
G01D02*
X1275016Y293838D01*
G01X1282163Y285176D02*
Y293838D01*
G01X1276277Y781724D02*
Y784924D01*
G01Y785724D02*
Y788924D01*
G01X1274777Y799724D02*
Y805924D01*
G01X1284277Y798824D02*
X1281077D01*
G01X1284277Y792624D02*
Y798824D01*
G01X1281077Y792624D02*
X1284277D01*
G01X1281077Y798824D02*
Y792624D01*
G01X1288277Y798824D02*
X1285077D01*
G01X1288277Y792624D02*
Y798824D01*
G01X1285077Y792624D02*
X1288277D01*
G01X1285077Y798824D02*
Y792624D01*
G01X1284277Y805924D02*
X1281077D01*
G01X1284277Y799724D02*
Y805924D01*
G01X1281077Y799724D02*
X1284277D01*
G01X1281077Y805924D02*
Y799724D01*
G01X1285152Y799699D02*
X1291352D01*
G01X1285152Y802899D02*
Y799699D01*
G01X1291352Y802899D02*
X1285152D01*
G01X1287000Y1252883D02*
X1290100D01*
Y1253803D01*
X1289945Y1254110D01*
X1289583Y1254340D01*
X1289170Y1254417D01*
X1288757Y1254340D01*
X1288447Y1254148D01*
X1288292Y1253803D01*
Y1252883D01*
G01X1289842Y1257593D02*
X1289997Y1257363D01*
X1290100Y1257095D01*
Y1256788D01*
X1289945Y1256443D01*
X1289687Y1256175D01*
X1289377Y1255983D01*
X1288860Y1255830D01*
X1288395Y1255792D01*
X1287930Y1255868D01*
X1287620Y1255983D01*
X1287310Y1256213D01*
X1287103Y1256482D01*
X1287000Y1256750D01*
Y1257018D01*
X1287103Y1257287D01*
X1287258Y1257517D01*
X1287465Y1257708D01*
G01X1287000Y1259850D02*
X1290100D01*
X1289480Y1259390D01*
G01X1287000D02*
Y1260310D01*
G01X1290100Y1262950D02*
X1289997Y1262643D01*
X1289738Y1262413D01*
X1289428Y1262260D01*
X1289015Y1262145D01*
X1288550Y1262107D01*
X1288085Y1262145D01*
X1287672Y1262260D01*
X1287362Y1262413D01*
X1287103Y1262643D01*
X1287000Y1262950D01*
X1287103Y1263257D01*
X1287362Y1263487D01*
X1287672Y1263640D01*
X1288085Y1263755D01*
X1288550Y1263793D01*
X1289015Y1263755D01*
X1289428Y1263640D01*
X1289738Y1263487D01*
X1289997Y1263257D01*
X1290100Y1262950D01*
G01X1289583Y1265322D02*
X1289893Y1265552D01*
X1290048Y1265820D01*
X1290100Y1266127D01*
X1289997Y1266510D01*
X1289738Y1266778D01*
X1289428Y1266855D01*
X1289118Y1266817D01*
X1288860Y1266663D01*
X1288343Y1265897D01*
X1287982Y1265552D01*
X1287465Y1265322D01*
X1287000Y1265245D01*
Y1266855D01*
G01X1284342Y1268380D02*
X1286582D01*
G01X1285369Y1266755D02*
Y1270005D01*
G01X1282812Y1312973D02*
Y1315399D01*
G01X1287642Y1325118D02*
Y1313118D01*
G01D02*
X1293642D01*
G01X1275528Y1319921D02*
X1278728D01*
G01X1275528Y1326121D02*
Y1319921D01*
G01X1278728Y1326121D02*
X1275528D01*
G01X1278728Y1319921D02*
Y1326121D01*
G01X1293642Y1325118D02*
X1287642D01*
G01Y1328361D02*
X1293642D01*
G01X1287642Y1340361D02*
Y1328361D01*
G01X1293642Y1340361D02*
X1287642D01*
G01X1282197Y1550953D02*
Y1562953D01*
G01X1276197Y1550953D02*
X1282197D01*
G01X1276197Y1562953D02*
Y1550953D01*
G01X1289005D02*
Y1562953D01*
G01X1283005Y1550953D02*
X1289005D01*
G01X1283005Y1562953D02*
Y1550953D01*
G01X1278017Y1550277D02*
Y1543877D01*
G01D02*
X1290897D01*
G01Y1550277D02*
X1278017D01*
G01X1282197Y1562953D02*
X1276197D01*
G01X1289005D02*
X1283005D01*
G01X1276919Y1565721D02*
X1288919D01*
G01X1276919Y1571721D02*
Y1565721D01*
G01X1288919D02*
Y1571721D01*
G01X1287877Y1583499D02*
Y1578899D01*
G01D02*
X1298077D01*
G01X1276919Y1572575D02*
X1288919D01*
G01X1276919Y1578575D02*
Y1572575D01*
G01X1288919Y1578575D02*
X1276919D01*
G01X1288919Y1572575D02*
Y1578575D01*
G01Y1571721D02*
X1276919D01*
G01X1298077Y1583499D02*
X1287877D01*
G01X1288976Y1648900D02*
Y1781456D01*
G01X1284200Y1646023D02*
X1279300D01*
G01X1287655Y1668289D02*
X1286983Y1668212D01*
X1286415Y1668097D01*
X1285898Y1667944D01*
X1285330Y1667752D01*
X1284555Y1667445D01*
Y1668979D01*
G01X1278489Y1668940D02*
X1278128Y1668672D01*
X1277921Y1668442D01*
X1277818Y1668135D01*
X1277921Y1667867D01*
X1278128Y1667675D01*
X1278438Y1667522D01*
X1278799Y1667484D01*
X1279109Y1667522D01*
X1279419Y1667675D01*
X1279678Y1667905D01*
X1279781Y1668174D01*
X1279678Y1668480D01*
X1279368Y1668749D01*
X1278903Y1668902D01*
X1278386Y1668940D01*
X1277714Y1668864D01*
X1277353Y1668749D01*
X1276991Y1668557D01*
X1276733Y1668289D01*
X1276681Y1668020D01*
X1276784Y1667752D01*
X1277043Y1667560D01*
G01X1288976Y1781456D02*
X1379133D01*
G01X1303939Y94312D02*
Y91212D01*
X1303479Y91832D01*
G01Y94312D02*
X1304399D01*
G01X1303146Y113992D02*
X1303376Y114354D01*
X1303682Y114560D01*
X1304027Y114612D01*
X1304334Y114560D01*
X1304641Y114302D01*
X1304832Y113992D01*
X1304871Y113682D01*
X1304794Y113320D01*
X1304526Y113062D01*
X1304257Y112959D01*
X1303912D01*
G01X1304257D02*
X1304487Y112804D01*
X1304679Y112545D01*
X1304756Y112235D01*
X1304679Y111925D01*
X1304487Y111667D01*
X1304142Y111512D01*
X1303797Y111564D01*
X1303452Y111770D01*
G01X1291875Y132809D02*
X1298075D01*
G01D02*
Y136009D01*
G01X1291875D02*
Y132809D01*
G01X1298075Y136009D02*
X1291875D01*
G01X1292494Y265733D02*
Y259533D01*
G01D02*
X1295694D01*
G01D02*
Y265733D01*
G01D02*
X1292494D01*
G01X1300494D02*
Y259533D01*
G01D02*
X1303694D01*
G01D02*
Y265733D01*
G01D02*
X1300494D01*
G01X1307016Y293838D02*
X1303669D01*
G01D02*
Y285176D01*
G01D02*
X1314163D01*
G01X1303087Y296294D02*
X1306434D01*
G01X1303087Y304956D02*
Y296294D01*
G01X1298163Y293838D02*
X1294816D01*
G01D02*
X1292916Y291638D01*
G01D02*
X1291016Y293838D01*
G01X1298163Y285176D02*
Y293838D01*
G01X1313581Y304956D02*
X1303087D01*
G01X1302566Y535703D02*
X1308766D01*
G01X1302566Y538903D02*
Y535703D01*
G01X1308766Y538903D02*
X1302566D01*
G01X1291352Y799699D02*
Y802899D01*
G01X1291970Y1274438D02*
Y1310134D01*
G01X1300960Y1278689D02*
X1306960D01*
G01X1300960Y1290689D02*
Y1278689D01*
G01X1300083Y1278675D02*
Y1290675D01*
G01X1294083Y1278675D02*
X1300083D01*
G01X1294083Y1290675D02*
Y1278675D01*
G01X1306960Y1290689D02*
X1300960D01*
G01X1300083Y1290675D02*
X1294083D01*
G01X1293642Y1313118D02*
Y1325118D01*
G01X1302020Y1313118D02*
Y1325118D01*
G01X1296020D02*
Y1313118D01*
G01D02*
X1302020D01*
G01X1303115Y1326187D02*
X1306315D01*
G01X1303115Y1332387D02*
Y1326187D01*
G01X1302020Y1325118D02*
X1296020D01*
G01X1306315Y1332387D02*
X1303115D01*
G01X1293642Y1328361D02*
Y1340361D01*
G01X1290897Y1550277D02*
Y1543877D01*
G01X1289944Y1552522D02*
X1293144D01*
G01X1289944Y1558722D02*
Y1552522D01*
G01X1293144Y1558722D02*
X1289944D01*
G01X1293144Y1552522D02*
Y1558722D01*
G01X1293944Y1552522D02*
X1297144D01*
G01X1293944Y1558722D02*
Y1552522D01*
G01X1297144Y1558722D02*
X1293944D01*
G01X1297144Y1552522D02*
Y1558722D01*
G01X1290159Y1573146D02*
Y1561146D01*
G01X1296159D02*
Y1573146D01*
G01X1290159Y1561146D02*
X1296159D01*
G01X1296915Y1560892D02*
X1308915D01*
G01X1296915Y1566892D02*
Y1560892D01*
G01X1298077Y1578899D02*
Y1583499D01*
G01X1293677D02*
Y1578899D01*
G01X1303877D02*
Y1583499D01*
G01X1293677Y1578899D02*
X1303877D01*
G01X1296159Y1573146D02*
X1290159D01*
G01X1308941Y1573746D02*
X1296941D01*
G01Y1567746D02*
X1308941D01*
G01X1296941Y1573746D02*
Y1567746D01*
G01X1308915Y1566892D02*
X1296915D01*
G01X1303877Y1583499D02*
X1293677D01*
G01X1309400Y1646023D02*
X1302900D01*
G01X1297400D02*
X1291600D01*
G01X1309400D02*
X1302900D01*
G01X1297400D02*
X1291600D01*
G01X1302588Y1673177D02*
X1299488D01*
X1302588Y1671413D01*
X1299488D01*
G01X1295529Y1668212D02*
X1295477Y1667944D01*
X1295322Y1667637D01*
X1295064Y1667445D01*
X1294702Y1667369D01*
X1294341Y1667445D01*
X1294031Y1667675D01*
X1293876Y1668020D01*
Y1668404D01*
X1293772Y1668634D01*
X1293514Y1668825D01*
X1293152Y1668902D01*
X1292791Y1668787D01*
X1292532Y1668519D01*
X1292429Y1668212D01*
X1292532Y1667905D01*
X1292791Y1667637D01*
X1293152Y1667522D01*
X1293514Y1667599D01*
X1293772Y1667790D01*
X1293876Y1668020D01*
Y1668404D01*
X1294031Y1668749D01*
X1294341Y1668979D01*
X1294702Y1669055D01*
X1295064Y1668979D01*
X1295322Y1668787D01*
X1295477Y1668480D01*
X1295529Y1668212D01*
G01X1302588Y1678016D02*
X1299488D01*
X1302071Y1677019D01*
X1299488Y1676022D01*
X1302588D01*
G01X1299488Y1682510D02*
X1302588D01*
Y1680976D01*
G01Y1687311D02*
X1299488D01*
G01Y1685855D02*
X1301400Y1687311D01*
G01X1302588Y1685625D02*
X1300521Y1686660D01*
G01X1301968Y1691959D02*
X1302278Y1691767D01*
X1302485Y1691537D01*
X1302588Y1691269D01*
X1302485Y1690962D01*
X1302278Y1690732D01*
X1301968Y1690502D01*
X1301555Y1690425D01*
X1299488D01*
G01Y1696377D02*
Y1695457D01*
G01Y1695917D02*
X1302588D01*
G01Y1696377D02*
Y1695457D01*
G01X1302582Y1701017D02*
X1299482D01*
G01Y1699407D02*
X1302582D01*
G01X1301032D02*
Y1701017D01*
G01X1300932Y1704782D02*
Y1704015D01*
X1301862D01*
X1302172Y1704245D01*
X1302379Y1704514D01*
X1302482Y1704897D01*
X1302379Y1705280D01*
X1302172Y1705549D01*
X1301862Y1705779D01*
X1301500Y1705932D01*
X1301087Y1706009D01*
X1300725D01*
X1300415Y1705932D01*
X1300054Y1705779D01*
X1299744Y1705549D01*
X1299537Y1705319D01*
X1299382Y1705012D01*
Y1704744D01*
X1299485Y1704437D01*
X1299692Y1704207D01*
G01X1302588Y1710818D02*
X1299488D01*
Y1709362D01*
G01X1300986Y1709898D02*
Y1710818D01*
G01X1302588Y1714047D02*
Y1715581D01*
X1299488D01*
Y1714047D01*
G01X1300986Y1714661D02*
Y1715581D01*
G01X1302588Y1720382D02*
X1299488D01*
Y1719616D01*
X1299643Y1719309D01*
X1299850Y1719079D01*
X1300160Y1718887D01*
X1300521Y1718734D01*
X1301038Y1718696D01*
X1301555Y1718734D01*
X1301916Y1718887D01*
X1302226Y1719079D01*
X1302433Y1719309D01*
X1302588Y1719616D01*
Y1720382D01*
G01X1299746Y1723420D02*
X1299591Y1723650D01*
X1299488Y1723918D01*
Y1724225D01*
X1299643Y1724570D01*
X1299901Y1724838D01*
X1300211Y1725030D01*
X1300728Y1725183D01*
X1301193Y1725221D01*
X1301658Y1725145D01*
X1301968Y1725030D01*
X1302278Y1724800D01*
X1302485Y1724531D01*
X1302588Y1724263D01*
Y1723995D01*
X1302485Y1723726D01*
X1302330Y1723496D01*
X1302123Y1723305D01*
G01X1300935Y1728681D02*
X1300780Y1728528D01*
X1300521Y1728413D01*
X1300160Y1728336D01*
X1299850Y1728413D01*
X1299643Y1728566D01*
X1299488Y1728835D01*
Y1729870D01*
X1302588D01*
Y1728605D01*
X1302381Y1728336D01*
X1302071Y1728183D01*
X1301710Y1728106D01*
X1301348Y1728183D01*
X1301038Y1728413D01*
X1300935Y1728681D01*
Y1729870D01*
G01X1302382Y1735170D02*
X1299282Y1734212D01*
X1302382Y1733254D01*
G01X1301297Y1733599D02*
Y1734825D01*
G01X1316494Y265733D02*
Y259533D01*
G01D02*
X1319694D01*
G01Y265733D02*
X1316494D01*
G01X1308494D02*
Y259533D01*
G01D02*
X1311694D01*
G01D02*
Y265733D01*
G01D02*
X1308494D01*
G01X1313616Y278684D02*
X1313923Y278736D01*
X1314191Y278942D01*
X1314421Y279252D01*
X1314574Y279614D01*
X1314651Y280027D01*
Y280441D01*
X1314574Y280854D01*
X1314421Y281216D01*
X1314191Y281526D01*
X1313923Y281732D01*
X1313616Y281784D01*
X1313309Y281732D01*
X1313041Y281526D01*
X1312811Y281216D01*
X1312658Y280854D01*
X1312581Y280441D01*
Y280027D01*
X1312658Y279614D01*
X1312811Y279252D01*
X1313041Y278942D01*
X1313309Y278736D01*
X1313616Y278684D01*
G01X1313309Y279511D02*
X1312849Y278684D01*
G01X1310516D02*
X1310248Y278736D01*
X1309941Y278891D01*
X1309749Y279149D01*
X1309673Y279511D01*
X1309749Y279872D01*
X1309979Y280182D01*
X1310324Y280337D01*
X1310708D01*
X1310938Y280441D01*
X1311129Y280699D01*
X1311206Y281061D01*
X1311091Y281422D01*
X1310823Y281681D01*
X1310516Y281784D01*
X1310209Y281681D01*
X1309941Y281422D01*
X1309826Y281061D01*
X1309903Y280699D01*
X1310094Y280441D01*
X1310324Y280337D01*
X1310708D01*
X1311053Y280182D01*
X1311283Y279872D01*
X1311359Y279511D01*
X1311283Y279149D01*
X1311091Y278891D01*
X1310784Y278736D01*
X1310516Y278684D01*
G01X1307416D02*
Y281784D01*
X1307876Y281164D01*
G01Y278684D02*
X1306956D01*
G01X1314163Y293838D02*
X1310816D01*
G01D02*
X1308916Y291638D01*
G01D02*
X1307016Y293838D01*
G01X1314163Y285176D02*
Y293838D01*
G01X1306434Y296294D02*
X1308334Y298494D01*
G01D02*
X1310234Y296294D01*
G01D02*
X1313581D01*
G01D02*
Y304956D01*
G01X1316016Y307982D02*
X1316323Y308034D01*
X1316591Y308240D01*
X1316821Y308550D01*
X1316974Y308912D01*
X1317051Y309325D01*
Y309739D01*
X1316974Y310152D01*
X1316821Y310514D01*
X1316591Y310824D01*
X1316323Y311030D01*
X1316016Y311082D01*
X1315709Y311030D01*
X1315441Y310824D01*
X1315211Y310514D01*
X1315058Y310152D01*
X1314981Y309739D01*
Y309325D01*
X1315058Y308912D01*
X1315211Y308550D01*
X1315441Y308240D01*
X1315709Y308034D01*
X1316016Y307982D01*
G01X1315709Y308809D02*
X1315249Y307982D01*
G01X1312916D02*
X1312648Y308034D01*
X1312341Y308189D01*
X1312149Y308447D01*
X1312073Y308809D01*
X1312149Y309170D01*
X1312379Y309480D01*
X1312724Y309635D01*
X1313108D01*
X1313338Y309739D01*
X1313529Y309997D01*
X1313606Y310359D01*
X1313491Y310720D01*
X1313223Y310979D01*
X1312916Y311082D01*
X1312609Y310979D01*
X1312341Y310720D01*
X1312226Y310359D01*
X1312303Y309997D01*
X1312494Y309739D01*
X1312724Y309635D01*
X1313108D01*
X1313453Y309480D01*
X1313683Y309170D01*
X1313759Y308809D01*
X1313683Y308447D01*
X1313491Y308189D01*
X1313184Y308034D01*
X1312916Y307982D01*
G01X1310659Y308602D02*
X1310429Y308240D01*
X1310123Y308034D01*
X1309778Y307982D01*
X1309471Y308034D01*
X1309164Y308292D01*
X1308973Y308602D01*
X1308934Y308912D01*
X1309011Y309274D01*
X1309279Y309532D01*
X1309548Y309635D01*
X1309893D01*
G01X1309548D02*
X1309318Y309790D01*
X1309126Y310049D01*
X1309049Y310359D01*
X1309126Y310669D01*
X1309318Y310927D01*
X1309663Y311082D01*
X1310008Y311030D01*
X1310353Y310824D01*
G01X1308766Y535703D02*
Y538903D01*
G01X1306224Y598111D02*
Y591911D01*
G01D02*
X1309424D01*
G01D02*
Y598111D01*
G01X1318334Y588761D02*
X1324334D01*
G01X1318334Y600761D02*
Y588761D01*
G01X1310234D02*
X1316234D01*
G01D02*
Y600761D01*
G01X1310234D02*
Y588761D01*
G01X1309424Y598111D02*
X1306224D01*
G01X1324334Y600761D02*
X1318334D01*
G01X1316234D02*
X1310234D01*
G01X1317936Y617409D02*
Y611409D01*
G01D02*
X1329936D01*
G01Y610309D02*
X1317936D01*
G01D02*
Y604309D01*
G01D02*
X1329936D01*
G01Y617409D02*
X1317936D01*
G01X1312638Y810552D02*
G03X1322386Y819024I1J9843D01*
G01Y1219402D02*
G03X1312638Y1227874I-9747J-1371D01*
G01X1320000Y1252883D02*
X1323100D01*
Y1253803D01*
X1322945Y1254110D01*
X1322583Y1254340D01*
X1322170Y1254417D01*
X1321757Y1254340D01*
X1321447Y1254148D01*
X1321292Y1253803D01*
Y1252883D01*
G01X1322842Y1257593D02*
X1322997Y1257363D01*
X1323100Y1257095D01*
Y1256788D01*
X1322945Y1256443D01*
X1322687Y1256175D01*
X1322377Y1255983D01*
X1321860Y1255830D01*
X1321395Y1255792D01*
X1320930Y1255868D01*
X1320620Y1255983D01*
X1320310Y1256213D01*
X1320103Y1256482D01*
X1320000Y1256750D01*
Y1257018D01*
X1320103Y1257287D01*
X1320258Y1257517D01*
X1320465Y1257708D01*
G01X1320000Y1259850D02*
X1323100D01*
X1322480Y1259390D01*
G01X1320000D02*
Y1260310D01*
G01X1323100Y1262950D02*
X1322997Y1262643D01*
X1322738Y1262413D01*
X1322428Y1262260D01*
X1322015Y1262145D01*
X1321550Y1262107D01*
X1321085Y1262145D01*
X1320672Y1262260D01*
X1320362Y1262413D01*
X1320103Y1262643D01*
X1320000Y1262950D01*
X1320103Y1263257D01*
X1320362Y1263487D01*
X1320672Y1263640D01*
X1321085Y1263755D01*
X1321550Y1263793D01*
X1322015Y1263755D01*
X1322428Y1263640D01*
X1322738Y1263487D01*
X1322997Y1263257D01*
X1323100Y1262950D01*
G01X1320620Y1265207D02*
X1320258Y1265437D01*
X1320052Y1265743D01*
X1320000Y1266088D01*
X1320052Y1266395D01*
X1320310Y1266702D01*
X1320620Y1266893D01*
X1320930Y1266932D01*
X1321292Y1266855D01*
X1321550Y1266587D01*
X1321653Y1266318D01*
Y1265973D01*
G01Y1266318D02*
X1321808Y1266548D01*
X1322067Y1266740D01*
X1322377Y1266817D01*
X1322687Y1266740D01*
X1322945Y1266548D01*
X1323100Y1266203D01*
X1323048Y1265858D01*
X1322842Y1265513D01*
G01X1317319Y1267953D02*
X1319559D01*
G01X1318346Y1266328D02*
Y1269578D01*
G01X1308847Y1274353D02*
X1326563D01*
G01X1308847Y1310049D02*
Y1274353D01*
G01X1306960Y1278689D02*
Y1290689D01*
G01X1317405Y1312888D02*
Y1315314D01*
G01X1326563Y1310049D02*
X1308847D01*
G01X1306315Y1326187D02*
Y1332387D01*
G01X1308432Y1319864D02*
X1311632D01*
G01X1308432Y1326064D02*
Y1319864D01*
G01X1311632Y1326064D02*
X1308432D01*
G01X1311632Y1319864D02*
Y1326064D01*
G01X1309352Y1538345D02*
Y1532345D01*
X1321352D01*
Y1538345D01*
X1309352D01*
G01X1308915Y1560892D02*
Y1566892D01*
G01X1317356Y1570612D02*
X1320556D01*
G01Y1576812D02*
X1317356D01*
G01D02*
Y1570612D01*
G01X1308941Y1567746D02*
Y1573746D01*
G01X1321500Y1646023D02*
X1314900D01*
G01X1312203Y1667360D02*
Y1648600D01*
G01X1312632Y1668940D02*
X1312322Y1668710D01*
X1312167Y1668442D01*
X1312115Y1668135D01*
X1312218Y1667752D01*
X1312477Y1667484D01*
X1312787Y1667407D01*
X1313097Y1667445D01*
X1313355Y1667599D01*
X1313872Y1668365D01*
X1314233Y1668710D01*
X1314750Y1668940D01*
X1315215Y1669017D01*
Y1667407D01*
G01X1307341Y1668212D02*
X1304241D01*
X1304861Y1668672D01*
G01X1307341D02*
Y1667752D01*
G01X1312203Y1781456D02*
Y1737290D01*
G01X1324494Y265733D02*
Y259533D01*
G01D02*
X1327694D01*
G01D02*
Y265733D01*
G01D02*
X1324494D01*
G01X1332494D02*
Y259533D01*
G01D02*
X1335694D01*
G01Y265733D02*
X1332494D01*
G01X1319694Y259533D02*
Y265733D01*
G01X1337366Y295074D02*
X1337673Y295126D01*
X1337941Y295332D01*
X1338171Y295642D01*
X1338324Y296004D01*
X1338401Y296417D01*
Y296831D01*
X1338324Y297244D01*
X1338171Y297606D01*
X1337941Y297916D01*
X1337673Y298122D01*
X1337366Y298174D01*
X1337059Y298122D01*
X1336791Y297916D01*
X1336561Y297606D01*
X1336408Y297244D01*
X1336331Y296831D01*
Y296417D01*
X1336408Y296004D01*
X1336561Y295642D01*
X1336791Y295332D01*
X1337059Y295126D01*
X1337366Y295074D01*
G01X1337059Y295901D02*
X1336599Y295074D01*
G01X1334266D02*
X1333998Y295126D01*
X1333691Y295281D01*
X1333499Y295539D01*
X1333423Y295901D01*
X1333499Y296262D01*
X1333729Y296572D01*
X1334074Y296727D01*
X1334458D01*
X1334688Y296831D01*
X1334879Y297089D01*
X1334956Y297451D01*
X1334841Y297812D01*
X1334573Y298071D01*
X1334266Y298174D01*
X1333959Y298071D01*
X1333691Y297812D01*
X1333576Y297451D01*
X1333653Y297089D01*
X1333844Y296831D01*
X1334074Y296727D01*
X1334458D01*
X1334803Y296572D01*
X1335033Y296262D01*
X1335109Y295901D01*
X1335033Y295539D01*
X1334841Y295281D01*
X1334534Y295126D01*
X1334266Y295074D01*
G01X1330706D02*
Y298174D01*
X1332124Y295952D01*
X1330208D01*
G01X1334816Y293838D02*
X1332916Y291638D01*
G01D02*
X1331016Y293838D01*
G01D02*
X1327669D01*
G01D02*
Y285176D01*
G01D02*
X1338163D01*
G01X1326376Y588743D02*
X1332376D01*
G01D02*
Y600743D01*
G01X1326376D02*
Y588743D01*
G01X1324334Y588761D02*
Y600761D01*
G01X1332376Y600743D02*
X1326376D01*
G01X1329936Y611409D02*
Y617409D01*
G01Y604309D02*
Y610309D01*
G01X1326642Y849323D02*
X1322386Y819024D01*
G01X1331277Y842888D02*
X1332500D01*
G01X1331277Y849088D02*
Y842888D01*
G01X1332800Y849088D02*
X1331277D01*
G01X1329517Y855000D02*
G03X1326642Y849323I6872J-7047D01*
G01Y1189103D02*
G03X1336390Y1180630I9747J1370D01*
G01X1326642Y1189103D02*
X1322386Y1219402D01*
G01X1332077Y1209588D02*
Y1206388D01*
G01D02*
X1338277D01*
G01X1332077Y1202388D02*
X1338277D01*
G01X1332077Y1205588D02*
Y1202388D01*
G01X1338277Y1205588D02*
X1332077D01*
G01X1338277Y1209588D02*
X1332077D01*
G01Y1213088D02*
Y1209888D01*
G01X1338277Y1213088D02*
X1332077D01*
G01Y1209888D02*
X1338277D01*
G01X1335577Y1220478D02*
X1332377D01*
G01Y1214278D02*
X1335577D01*
G01X1332377Y1220478D02*
Y1214278D01*
G01X1327877D02*
X1331077D01*
G01X1327877Y1220478D02*
Y1214278D01*
G01X1331077Y1220478D02*
X1327877D01*
G01X1331077Y1214278D02*
Y1220478D01*
G01X1332132Y1226959D02*
X1338332D01*
G01X1332132Y1230159D02*
Y1226959D01*
G01X1338332Y1230159D02*
X1332132D01*
G01X1326563Y1274353D02*
Y1310049D01*
G01X1328443Y1278808D02*
X1334443D01*
G01X1328443Y1290808D02*
Y1278808D01*
G01X1334443Y1290808D02*
X1328443D01*
G01X1328924Y1325061D02*
Y1313061D01*
G01D02*
X1334924D01*
G01X1320546Y1325061D02*
Y1313061D01*
G01X1326546D02*
Y1325061D01*
G01X1320546Y1313061D02*
X1326546D01*
G01X1334924Y1325061D02*
X1328924D01*
G01X1326546D02*
X1320546D01*
G01X1326546Y1328304D02*
Y1340304D01*
G01X1320546Y1328304D02*
X1326546D01*
G01X1320546Y1340304D02*
Y1328304D01*
G01X1326546Y1340304D02*
X1320546D01*
G01X1327352Y1522413D02*
X1329592D01*
G01X1328379Y1520788D02*
Y1524038D01*
G01X1324747Y1524980D02*
X1360487D01*
Y1541910D01*
X1324747D01*
Y1524980D01*
G01X1323547Y1524978D02*
X1324747D01*
G01X1323547D02*
X1323553Y1541961D01*
G01X1324147Y1524978D02*
X1324143Y1541953D01*
G01X1324747Y1524978D02*
X1324744Y1541918D01*
G01X1323597Y1541911D02*
X1325106Y1541907D01*
G01X1324114Y1573738D02*
X1320914D01*
G01X1324114Y1567538D02*
Y1573738D01*
G01X1320914Y1567538D02*
X1324114D01*
G01X1320914Y1573738D02*
Y1567538D01*
G01X1320556Y1570612D02*
Y1576812D01*
G01X1333564Y1573738D02*
X1330364D01*
G01X1333564Y1567538D02*
Y1573738D01*
G01X1330364Y1567538D02*
X1333564D01*
G01X1330364Y1573738D02*
Y1567538D01*
G01X1325639Y1573738D02*
Y1567538D01*
X1328839D01*
Y1573738D01*
X1325639D01*
G01X1333300Y1646023D02*
X1327000D01*
G01X1330963Y1667752D02*
X1327863D01*
X1330085Y1669170D01*
Y1667254D01*
G01X1322469Y1669055D02*
X1322831Y1668825D01*
X1323037Y1668519D01*
X1323089Y1668174D01*
X1323037Y1667867D01*
X1322779Y1667560D01*
X1322469Y1667369D01*
X1322159Y1667330D01*
X1321797Y1667407D01*
X1321539Y1667675D01*
X1321436Y1667944D01*
Y1668289D01*
G01Y1667944D02*
X1321281Y1667714D01*
X1321022Y1667522D01*
X1320712Y1667445D01*
X1320402Y1667522D01*
X1320144Y1667714D01*
X1319989Y1668059D01*
X1320041Y1668404D01*
X1320247Y1668749D01*
G01X1348494Y265733D02*
Y259533D01*
G01D02*
X1351694D01*
G01Y265733D02*
X1348494D01*
G01X1340494D02*
Y259533D01*
G01D02*
X1343694D01*
G01D02*
Y265733D01*
G01D02*
X1340494D01*
G01X1335694Y259533D02*
Y265733D01*
G01X1353366Y295074D02*
X1353673Y295126D01*
X1353941Y295332D01*
X1354171Y295642D01*
X1354324Y296004D01*
X1354401Y296417D01*
Y296831D01*
X1354324Y297244D01*
X1354171Y297606D01*
X1353941Y297916D01*
X1353673Y298122D01*
X1353366Y298174D01*
X1353059Y298122D01*
X1352791Y297916D01*
X1352561Y297606D01*
X1352408Y297244D01*
X1352331Y296831D01*
Y296417D01*
X1352408Y296004D01*
X1352561Y295642D01*
X1352791Y295332D01*
X1353059Y295126D01*
X1353366Y295074D01*
G01X1353059Y295901D02*
X1352599Y295074D01*
G01X1350266D02*
X1349998Y295126D01*
X1349691Y295281D01*
X1349499Y295539D01*
X1349423Y295901D01*
X1349499Y296262D01*
X1349729Y296572D01*
X1350074Y296727D01*
X1350458D01*
X1350688Y296831D01*
X1350879Y297089D01*
X1350956Y297451D01*
X1350841Y297812D01*
X1350573Y298071D01*
X1350266Y298174D01*
X1349959Y298071D01*
X1349691Y297812D01*
X1349576Y297451D01*
X1349653Y297089D01*
X1349844Y296831D01*
X1350074Y296727D01*
X1350458D01*
X1350803Y296572D01*
X1351033Y296262D01*
X1351109Y295901D01*
X1351033Y295539D01*
X1350841Y295281D01*
X1350534Y295126D01*
X1350266Y295074D01*
G01X1348009Y295539D02*
X1347779Y295281D01*
X1347511Y295126D01*
X1347166Y295074D01*
X1346821Y295177D01*
X1346553Y295384D01*
X1346361Y295746D01*
X1346323Y296159D01*
X1346399Y296572D01*
X1346591Y296831D01*
X1346859Y297037D01*
X1347128Y297089D01*
X1347396Y297037D01*
X1347741Y296831D01*
X1347626Y298174D01*
X1346591D01*
G01X1350816Y293838D02*
X1348916Y291638D01*
G01D02*
X1347016Y293838D01*
G01D02*
X1343669D01*
G01D02*
Y285176D01*
G01D02*
X1354163D01*
G01X1338163Y293838D02*
X1334816D01*
G01X1338163Y285176D02*
Y293838D01*
G01X1345117Y670988D02*
Y664788D01*
G01D02*
X1348317D01*
G01D02*
Y670988D01*
G01D02*
X1345117D01*
G01X1338477Y849088D02*
X1336900D01*
G01X1338477Y842888D02*
Y849088D01*
G01X1337400Y842888D02*
X1338477D01*
G01X1335277Y847500D02*
Y844500D01*
G01X1334477D02*
Y847500D01*
G01X1341700Y857796D02*
X1365200D01*
G01X1346821Y1185527D02*
X1348200D01*
G01X1346821Y1191727D02*
Y1185527D01*
G01X1348200Y1191727D02*
X1346821D01*
G01X1338277Y1206388D02*
Y1209588D01*
G01Y1202388D02*
Y1205588D01*
G01Y1209888D02*
Y1213088D01*
G01X1335577Y1214278D02*
Y1220478D01*
G01X1341291Y1222709D02*
X1347491D01*
G01D02*
Y1225909D01*
G01X1341291D02*
Y1222709D01*
G01X1336377Y1214278D02*
X1339577D01*
G01X1336377Y1220478D02*
Y1214278D01*
G01X1339577Y1220478D02*
X1336377D01*
G01X1339577Y1214278D02*
Y1220478D01*
G01X1347491Y1225909D02*
X1341291D01*
G01X1338332Y1226959D02*
Y1230159D01*
G01X1343247Y1274328D02*
X1360963D01*
G01X1343247Y1310024D02*
Y1274328D01*
G01X1341330Y1278894D02*
Y1290894D01*
G01X1335330Y1278894D02*
X1341330D01*
G01X1335330Y1290894D02*
Y1278894D01*
G01X1334443Y1278808D02*
Y1290808D01*
G01X1341330Y1290894D02*
X1335330D01*
G01X1351805Y1312863D02*
Y1315289D01*
G01X1360963Y1310024D02*
X1343247D01*
G01X1334924Y1313061D02*
Y1325061D01*
G01X1335915Y1326387D02*
X1339115D01*
G01X1335915Y1332587D02*
Y1326387D01*
G01X1339115D02*
Y1332587D01*
G01X1344432Y1320064D02*
Y1326264D01*
G01X1341232Y1320064D02*
X1344432D01*
G01X1341232Y1326264D02*
Y1320064D01*
G01X1344432Y1326264D02*
X1341232D01*
G01X1339115Y1332587D02*
X1335915D01*
G01X1348190Y1522864D02*
X1348420Y1523019D01*
X1348688Y1523122D01*
X1348995D01*
X1349340Y1522967D01*
X1349608Y1522709D01*
X1349800Y1522399D01*
X1349953Y1521882D01*
X1349991Y1521417D01*
X1349915Y1520952D01*
X1349800Y1520642D01*
X1349570Y1520332D01*
X1349301Y1520125D01*
X1349033Y1520022D01*
X1348765D01*
X1348496Y1520125D01*
X1348266Y1520280D01*
X1348075Y1520487D01*
G01X1346010Y1520022D02*
X1345933Y1520694D01*
X1345818Y1521262D01*
X1345665Y1521779D01*
X1345473Y1522347D01*
X1345166Y1523122D01*
X1346700D01*
G01X1342833D02*
X1343140Y1523019D01*
X1343370Y1522760D01*
X1343523Y1522450D01*
X1343638Y1522037D01*
X1343676Y1521572D01*
X1343638Y1521107D01*
X1343523Y1520694D01*
X1343370Y1520384D01*
X1343140Y1520125D01*
X1342833Y1520022D01*
X1342526Y1520125D01*
X1342296Y1520384D01*
X1342143Y1520694D01*
X1342028Y1521107D01*
X1341990Y1521572D01*
X1342028Y1522037D01*
X1342143Y1522450D01*
X1342296Y1522760D01*
X1342526Y1523019D01*
X1342833Y1523122D01*
G01X1339733Y1520022D02*
Y1523122D01*
X1340193Y1522502D01*
G01Y1520022D02*
X1339273D01*
G01X1336633D02*
Y1523122D01*
X1337093Y1522502D01*
G01Y1520022D02*
X1336173D01*
G01X1347737Y1573738D02*
X1344537D01*
G01X1347737Y1567538D02*
Y1573738D01*
G01X1344537Y1567538D02*
X1347737D01*
G01X1344537Y1573738D02*
Y1567538D01*
G01X1338288Y1573738D02*
X1335088D01*
G01X1338288Y1567538D02*
Y1573738D01*
G01X1335088Y1567538D02*
X1338288D01*
G01X1335088Y1573738D02*
Y1567538D01*
G01X1339813Y1573738D02*
Y1567538D01*
X1343013D01*
Y1573738D01*
X1339813D01*
G01X1345600Y1646023D02*
X1339300D01*
G01X1338372Y1669055D02*
X1338630Y1668825D01*
X1338785Y1668557D01*
X1338837Y1668212D01*
X1338734Y1667867D01*
X1338527Y1667599D01*
X1338165Y1667407D01*
X1337752Y1667369D01*
X1337339Y1667445D01*
X1337080Y1667637D01*
X1336874Y1667905D01*
X1336822Y1668174D01*
X1336874Y1668442D01*
X1337080Y1668787D01*
X1335737Y1668672D01*
Y1667637D01*
G01X1345419Y1668940D02*
X1345058Y1668672D01*
X1344851Y1668442D01*
X1344748Y1668135D01*
X1344851Y1667867D01*
X1345058Y1667675D01*
X1345368Y1667522D01*
X1345729Y1667484D01*
X1346039Y1667522D01*
X1346349Y1667675D01*
X1346608Y1667905D01*
X1346711Y1668174D01*
X1346608Y1668480D01*
X1346298Y1668749D01*
X1345833Y1668902D01*
X1345316Y1668940D01*
X1344644Y1668864D01*
X1344283Y1668749D01*
X1343921Y1668557D01*
X1343663Y1668289D01*
X1343611Y1668020D01*
X1343714Y1667752D01*
X1343973Y1667560D01*
G01X1356494Y265733D02*
Y259533D01*
G01D02*
X1359694D01*
G01D02*
Y265733D01*
G01D02*
X1356494D01*
G01X1351694Y259533D02*
Y265733D01*
G01X1369366Y295074D02*
X1369673Y295126D01*
X1369941Y295332D01*
X1370171Y295642D01*
X1370324Y296004D01*
X1370401Y296417D01*
Y296831D01*
X1370324Y297244D01*
X1370171Y297606D01*
X1369941Y297916D01*
X1369673Y298122D01*
X1369366Y298174D01*
X1369059Y298122D01*
X1368791Y297916D01*
X1368561Y297606D01*
X1368408Y297244D01*
X1368331Y296831D01*
Y296417D01*
X1368408Y296004D01*
X1368561Y295642D01*
X1368791Y295332D01*
X1369059Y295126D01*
X1369366Y295074D01*
G01X1369059Y295901D02*
X1368599Y295074D01*
G01X1366266D02*
X1365998Y295126D01*
X1365691Y295281D01*
X1365499Y295539D01*
X1365423Y295901D01*
X1365499Y296262D01*
X1365729Y296572D01*
X1366074Y296727D01*
X1366458D01*
X1366688Y296831D01*
X1366879Y297089D01*
X1366956Y297451D01*
X1366841Y297812D01*
X1366573Y298071D01*
X1366266Y298174D01*
X1365959Y298071D01*
X1365691Y297812D01*
X1365576Y297451D01*
X1365653Y297089D01*
X1365844Y296831D01*
X1366074Y296727D01*
X1366458D01*
X1366803Y296572D01*
X1367033Y296262D01*
X1367109Y295901D01*
X1367033Y295539D01*
X1366841Y295281D01*
X1366534Y295126D01*
X1366266Y295074D01*
G01X1363894Y296366D02*
X1363626Y296727D01*
X1363396Y296934D01*
X1363089Y297037D01*
X1362821Y296934D01*
X1362629Y296727D01*
X1362476Y296417D01*
X1362438Y296056D01*
X1362476Y295746D01*
X1362629Y295436D01*
X1362859Y295177D01*
X1363128Y295074D01*
X1363434Y295177D01*
X1363703Y295487D01*
X1363856Y295952D01*
X1363894Y296469D01*
X1363818Y297141D01*
X1363703Y297502D01*
X1363511Y297864D01*
X1363243Y298122D01*
X1362974Y298174D01*
X1362706Y298071D01*
X1362514Y297812D01*
G01X1364916Y291638D02*
X1363016Y293838D01*
G01D02*
X1359669D01*
G01D02*
Y285176D01*
G01D02*
X1370163D01*
G01X1354163Y293838D02*
X1350816D01*
G01X1354163Y285176D02*
Y293838D01*
G01X1361034Y613590D02*
X1367034D01*
G01Y625590D02*
X1361034D01*
G01D02*
Y613590D01*
G01X1359964Y640894D02*
X1353964D01*
G01D02*
Y628894D01*
G01D02*
X1359964D01*
G01D02*
Y640894D01*
G01X1367964D02*
X1361964D01*
G01D02*
Y628894D01*
G01D02*
X1367964D01*
G01X1348930Y662453D02*
X1354930D01*
G01D02*
Y674453D01*
G01X1348930D02*
Y662453D01*
G01X1357278D02*
X1363278D01*
G01D02*
Y674453D01*
G01X1357278D02*
Y662453D01*
G01X1354930Y674453D02*
X1348930D01*
G01X1363278D02*
X1357278D01*
G01X1359716Y973937D02*
G03X1369559Y964095I9843J1D01*
G01X1359716Y973937D02*
Y1064489D01*
G01X1363077Y980165D02*
X1369277D01*
Y983365D01*
X1363077D01*
Y980165D01*
G01X1360877Y976665D02*
X1367077D01*
Y979865D01*
X1360877D01*
Y976665D01*
G01X1363077Y998665D02*
X1369277D01*
Y1001865D01*
X1363077D01*
Y998665D01*
G01Y986165D02*
X1369277D01*
Y989365D01*
X1363077D01*
Y986165D01*
G01Y992665D02*
X1369277D01*
Y995865D01*
X1363077D01*
Y992665D01*
G01X1361201Y1009165D02*
X1367401D01*
Y1012365D01*
X1361201D01*
Y1009165D01*
G01X1361148Y1013873D02*
X1367348D01*
Y1017073D01*
X1361148D01*
Y1013873D01*
G01X1363201Y1005665D02*
X1369401D01*
Y1008865D01*
X1363201D01*
Y1005665D01*
G01X1367452Y1005365D02*
X1361252D01*
Y1002165D01*
X1367452D01*
Y1005365D01*
G01X1361148Y1020959D02*
X1367348D01*
Y1024159D01*
X1361148D01*
Y1020959D01*
G01Y1017416D02*
X1367348D01*
Y1020616D01*
X1361148D01*
Y1017416D01*
G01X1366777Y1032588D02*
X1360577D01*
Y1029388D01*
X1366777D01*
Y1032588D01*
G01Y1045088D02*
X1360577D01*
Y1041888D01*
X1366777D01*
Y1045088D01*
G01Y1039088D02*
X1360577D01*
Y1035888D01*
X1366777D01*
Y1039088D01*
G01X1362701Y1051665D02*
X1368901D01*
G01X1362701Y1054865D02*
Y1051665D01*
G01X1368901Y1054865D02*
X1362701D01*
G01X1361201Y1048165D02*
X1367401D01*
G01X1361201Y1051365D02*
Y1048165D01*
G01X1367401Y1051365D02*
X1361201D01*
G01X1362077Y1058665D02*
X1368277D01*
Y1061865D01*
X1362077D01*
Y1058665D01*
G01X1369559Y1074331D02*
G03X1359716Y1064489I0J-9843D01*
G01X1354021Y1191727D02*
X1352400D01*
G01X1354021Y1185527D02*
Y1191727D01*
G01X1352400Y1185527D02*
X1354021D01*
G01X1350821Y1190100D02*
Y1187400D01*
G01X1350021D02*
Y1190100D01*
G01X1353800Y1180630D02*
X1378000D01*
G01X1351077Y1209588D02*
Y1206388D01*
G01X1357277D02*
Y1209588D01*
G01X1351077Y1206388D02*
X1357277D01*
G01Y1209588D02*
X1351077D01*
G01X1359211Y1213037D02*
X1365411D01*
G01X1359211Y1216237D02*
Y1213037D01*
G01X1365411Y1216237D02*
X1359211D01*
G01X1351779Y1254185D02*
X1354879D01*
Y1255105D01*
X1354724Y1255412D01*
X1354362Y1255642D01*
X1353949Y1255719D01*
X1353536Y1255642D01*
X1353226Y1255450D01*
X1353071Y1255105D01*
Y1254185D01*
G01X1354621Y1258895D02*
X1354776Y1258665D01*
X1354879Y1258397D01*
Y1258090D01*
X1354724Y1257745D01*
X1354466Y1257477D01*
X1354156Y1257285D01*
X1353639Y1257132D01*
X1353174Y1257094D01*
X1352709Y1257170D01*
X1352399Y1257285D01*
X1352089Y1257515D01*
X1351882Y1257784D01*
X1351779Y1258052D01*
Y1258320D01*
X1351882Y1258589D01*
X1352037Y1258819D01*
X1352244Y1259010D01*
G01X1352141Y1260500D02*
X1351882Y1260769D01*
X1351779Y1261075D01*
X1351882Y1261382D01*
X1352192Y1261650D01*
X1352657Y1261842D01*
X1353122Y1261919D01*
X1353691D01*
X1354156Y1261842D01*
X1354569Y1261650D01*
X1354776Y1261420D01*
X1354879Y1261152D01*
X1354776Y1260845D01*
X1354569Y1260615D01*
X1354259Y1260462D01*
X1353846Y1260385D01*
X1353484Y1260462D01*
X1353122Y1260654D01*
X1352916Y1260884D01*
X1352864Y1261152D01*
X1352967Y1261459D01*
X1353226Y1261689D01*
X1353691Y1261919D01*
G01X1351779Y1264252D02*
X1351831Y1264520D01*
X1351986Y1264827D01*
X1352244Y1265019D01*
X1352606Y1265095D01*
X1352967Y1265019D01*
X1353277Y1264789D01*
X1353432Y1264444D01*
Y1264060D01*
X1353536Y1263830D01*
X1353794Y1263639D01*
X1354156Y1263562D01*
X1354517Y1263677D01*
X1354776Y1263945D01*
X1354879Y1264252D01*
X1354776Y1264559D01*
X1354517Y1264827D01*
X1354156Y1264942D01*
X1353794Y1264865D01*
X1353536Y1264674D01*
X1353432Y1264444D01*
Y1264060D01*
X1353277Y1263715D01*
X1352967Y1263485D01*
X1352606Y1263409D01*
X1352244Y1263485D01*
X1351986Y1263677D01*
X1351831Y1263984D01*
X1351779Y1264252D01*
G01X1350782Y1268160D02*
X1353022D01*
G01X1351809Y1266535D02*
Y1269785D01*
G01X1360963Y1274328D02*
Y1310024D01*
G01X1362830Y1280694D02*
X1368830D01*
G01X1362830Y1292694D02*
Y1280694D01*
G01X1368830Y1292694D02*
X1362830D01*
G01X1361724Y1325261D02*
Y1313261D01*
G01D02*
X1367724D01*
G01X1359346D02*
Y1325261D01*
G01X1353346D02*
Y1313261D01*
G01D02*
X1359346D01*
G01X1367724Y1325261D02*
X1361724D01*
G01X1359346D02*
X1353346D01*
G01X1359346Y1328504D02*
Y1340504D01*
G01X1353346Y1328504D02*
X1359346D01*
G01X1353346Y1340504D02*
Y1328504D01*
G01X1359346Y1340504D02*
X1353346D01*
G01X1356535Y1523458D02*
X1358961D01*
G01X1367005Y1523372D02*
X1364579D01*
G01X1397773Y1541910D02*
X1362033D01*
Y1524980D01*
X1397773D01*
Y1541910D01*
G01X1352461Y1573738D02*
X1349261D01*
G01X1352461Y1567538D02*
Y1573738D01*
G01X1349261Y1567538D02*
X1352461D01*
G01X1349261Y1573738D02*
Y1567538D01*
G01X1361910Y1573738D02*
X1358710D01*
G01X1361910Y1567538D02*
Y1573738D01*
G01X1358710Y1567538D02*
X1361910D01*
G01X1358710Y1573738D02*
Y1567538D01*
G01X1357186Y1573738D02*
X1353986D01*
G01X1357186Y1567538D02*
Y1573738D01*
G01X1353986Y1567538D02*
X1357186D01*
G01X1353986Y1573738D02*
Y1567538D01*
G01X1363435Y1573738D02*
Y1567538D01*
X1366635D01*
Y1573738D01*
X1363435D01*
G01X1369900Y1646023D02*
X1363500D01*
G01X1358000D02*
X1351200D01*
G01X1362459Y1668212D02*
X1362407Y1667944D01*
X1362252Y1667637D01*
X1361994Y1667445D01*
X1361632Y1667369D01*
X1361271Y1667445D01*
X1360961Y1667675D01*
X1360806Y1668020D01*
Y1668404D01*
X1360702Y1668634D01*
X1360444Y1668825D01*
X1360082Y1668902D01*
X1359721Y1668787D01*
X1359462Y1668519D01*
X1359359Y1668212D01*
X1359462Y1667905D01*
X1359721Y1667637D01*
X1360082Y1667522D01*
X1360444Y1667599D01*
X1360702Y1667790D01*
X1360806Y1668020D01*
Y1668404D01*
X1360961Y1668749D01*
X1361271Y1668979D01*
X1361632Y1669055D01*
X1361994Y1668979D01*
X1362252Y1668787D01*
X1362407Y1668480D01*
X1362459Y1668212D01*
G01X1354585Y1668289D02*
X1353913Y1668212D01*
X1353345Y1668097D01*
X1352828Y1667944D01*
X1352260Y1667752D01*
X1351485Y1667445D01*
Y1668979D01*
G01X1364494Y265733D02*
Y259533D01*
G01D02*
X1367694D01*
G01D02*
Y265733D01*
G01D02*
X1364494D01*
G01X1370163Y293838D02*
X1366816D01*
G01D02*
X1364916Y291638D01*
G01X1370163Y285176D02*
Y293838D01*
G01X1376505Y633337D02*
Y627137D01*
G01D02*
X1379705D01*
G01X1367034Y613590D02*
Y625590D01*
G01X1379705Y633337D02*
X1376505D01*
G01X1367964Y628894D02*
Y640894D01*
G01X1365602Y662453D02*
X1371602D01*
G01D02*
Y674453D01*
G01X1365602D02*
Y662453D01*
G01X1376644Y668610D02*
X1382644D01*
G01X1376644Y680610D02*
Y668610D01*
G01X1371602Y674453D02*
X1365602D01*
G01X1382644Y680610D02*
X1376644D01*
G01X1464047Y964095D02*
X1369559D01*
G01X1372577Y964888D02*
X1378777D01*
Y968088D01*
X1372577D01*
Y964888D01*
G01X1371277D02*
Y971088D01*
X1368077D01*
Y964888D01*
X1371277D01*
G01X1372177Y976665D02*
X1378377D01*
Y979865D01*
X1372177D01*
Y976665D01*
G01X1370577Y980165D02*
X1376777D01*
Y983365D01*
X1370577D01*
Y980165D01*
G01X1378077D02*
X1384277D01*
Y983365D01*
X1378077D01*
Y980165D01*
G01X1378901Y996493D02*
X1375801Y991123D01*
X1378573Y989523D01*
X1381673Y994893D01*
X1378901Y996493D01*
G01X1381693Y1000113D02*
X1378593Y1005483D01*
X1375821Y1003883D01*
X1378921Y998513D01*
X1381693Y1000113D01*
G01X1370477Y998665D02*
X1376677D01*
Y1001865D01*
X1370477D01*
Y998665D01*
G01X1370077Y992665D02*
X1376277D01*
Y995865D01*
X1370077D01*
Y992665D01*
G01X1370577Y986165D02*
X1376777D01*
Y989365D01*
X1370577D01*
Y986165D01*
G01X1378077D02*
X1384277D01*
Y989365D01*
X1378077D01*
Y986165D01*
G01X1368628Y1013873D02*
X1374828D01*
Y1017073D01*
X1368628D01*
Y1013873D01*
G01X1376108D02*
X1382308D01*
Y1017073D01*
X1376108D01*
Y1013873D01*
G01X1368701Y1009165D02*
X1374901D01*
Y1012365D01*
X1368701D01*
Y1009165D01*
G01X1380401Y1008865D02*
X1374201D01*
Y1005665D01*
X1380401D01*
Y1008865D01*
G01X1376201Y1009165D02*
X1382401D01*
Y1012365D01*
X1376201D01*
Y1009165D01*
G01X1373777Y1032588D02*
X1367577D01*
Y1029388D01*
X1373777D01*
Y1032588D01*
G01X1376108Y1017416D02*
X1382308D01*
Y1020616D01*
X1376108D01*
Y1017416D01*
G01X1368628D02*
X1374828D01*
Y1020616D01*
X1368628D01*
Y1017416D01*
G01Y1020959D02*
X1374828D01*
Y1024159D01*
X1368628D01*
Y1020959D01*
G01X1376108D02*
X1382308D01*
Y1024159D01*
X1376108D01*
Y1020959D01*
G01X1380401Y1029865D02*
X1374201D01*
Y1026665D01*
X1380401D01*
Y1029865D01*
G01X1373777Y1045088D02*
X1367577D01*
Y1041888D01*
X1373777D01*
Y1045088D01*
G01Y1039088D02*
X1367577D01*
Y1035888D01*
X1373777D01*
Y1039088D01*
G01X1380401Y1035865D02*
X1374201D01*
Y1032665D01*
X1380401D01*
Y1035865D01*
G01X1383401Y1042365D02*
X1377201D01*
Y1039165D01*
X1383401D01*
Y1042365D01*
G01X1368901Y1051665D02*
Y1054865D01*
G01X1367401Y1048165D02*
Y1051365D01*
G01X1383901Y1048865D02*
X1377701D01*
Y1045665D01*
X1383901D01*
Y1048865D01*
G01X1376401D02*
X1370201D01*
Y1045665D01*
X1376401D01*
Y1048865D01*
G01X1381901Y1058365D02*
X1375701D01*
Y1055165D01*
X1381901D01*
Y1058365D01*
G01X1376401Y1054865D02*
X1370201D01*
Y1051665D01*
X1376401D01*
Y1054865D01*
G01X1364577Y1055165D02*
X1370777D01*
Y1058365D01*
X1364577D01*
Y1055165D01*
G01X1383901Y1061865D02*
X1377701D01*
Y1058665D01*
X1383901D01*
Y1061865D01*
G01X1383401Y1054865D02*
X1377201D01*
Y1051665D01*
X1383401D01*
Y1054865D01*
G01X1464047Y1074331D02*
X1369559D01*
G01X1373577Y1070388D02*
X1379777D01*
Y1073588D01*
X1373577D01*
Y1070388D01*
G01X1368877Y1073488D02*
Y1067288D01*
X1372077D01*
Y1073488D01*
X1368877D01*
G01X1365411Y1213037D02*
Y1216237D01*
G01X1368830Y1280694D02*
Y1292694D01*
G01X1377932Y1293652D02*
X1395648D01*
G01X1377932Y1329348D02*
Y1293652D01*
G01X1375305Y1298232D02*
Y1310232D01*
G01X1369305Y1298232D02*
X1375305D01*
G01X1369305Y1310232D02*
Y1298232D01*
G01X1375305Y1310232D02*
X1369305D01*
G01X1367724Y1313261D02*
Y1325261D01*
G01X1374513Y1330272D02*
Y1332698D01*
G01X1395648Y1329348D02*
X1377932D01*
G01X1373814Y1339395D02*
X1377014D01*
G01X1373814Y1345595D02*
Y1339395D01*
G01X1377014D02*
Y1345595D01*
G01D02*
X1373814D01*
G01X1371697Y1345718D02*
Y1351918D01*
G01X1368497Y1345718D02*
X1371697D01*
G01X1368497Y1351918D02*
Y1345718D01*
G01X1371697Y1351918D02*
X1368497D01*
G01X1387200Y1522754D02*
X1387430Y1522909D01*
X1387698Y1523012D01*
X1388005D01*
X1388350Y1522857D01*
X1388618Y1522599D01*
X1388810Y1522289D01*
X1388963Y1521772D01*
X1389001Y1521307D01*
X1388925Y1520842D01*
X1388810Y1520532D01*
X1388580Y1520222D01*
X1388311Y1520015D01*
X1388043Y1519912D01*
X1387775D01*
X1387506Y1520015D01*
X1387276Y1520170D01*
X1387085Y1520377D01*
G01X1385020Y1519912D02*
X1384943Y1520584D01*
X1384828Y1521152D01*
X1384675Y1521669D01*
X1384483Y1522237D01*
X1384176Y1523012D01*
X1385710D01*
G01X1381843D02*
X1382150Y1522909D01*
X1382380Y1522650D01*
X1382533Y1522340D01*
X1382648Y1521927D01*
X1382686Y1521462D01*
X1382648Y1520997D01*
X1382533Y1520584D01*
X1382380Y1520274D01*
X1382150Y1520015D01*
X1381843Y1519912D01*
X1381536Y1520015D01*
X1381306Y1520274D01*
X1381153Y1520584D01*
X1381038Y1520997D01*
X1381000Y1521462D01*
X1381038Y1521927D01*
X1381153Y1522340D01*
X1381306Y1522650D01*
X1381536Y1522909D01*
X1381843Y1523012D01*
G01X1378743Y1519912D02*
Y1523012D01*
X1379203Y1522392D01*
G01Y1519912D02*
X1378283D01*
G01X1376371Y1522495D02*
X1376141Y1522805D01*
X1375873Y1522960D01*
X1375566Y1523012D01*
X1375183Y1522909D01*
X1374915Y1522650D01*
X1374838Y1522340D01*
X1374876Y1522030D01*
X1375030Y1521772D01*
X1375796Y1521255D01*
X1376141Y1520894D01*
X1376371Y1520377D01*
X1376448Y1519912D01*
X1374838D01*
G01X1372883Y1573738D02*
Y1567538D01*
X1376083D01*
Y1573738D01*
X1372883D01*
G01X1377608D02*
Y1567538D01*
X1380808D01*
Y1573738D01*
X1377608D01*
G01X1379133Y1646023D02*
X1375300D01*
G01X1376948Y1733579D02*
X1369448D01*
Y1731339D01*
X1369823Y1730592D01*
X1370698Y1730032D01*
X1371698Y1729845D01*
X1372698Y1730032D01*
X1373448Y1730499D01*
X1373823Y1731339D01*
Y1733579D01*
G01X1376948Y1726079D02*
X1369448D01*
Y1723745D01*
X1369823Y1722999D01*
X1370323Y1722532D01*
X1371323Y1722345D01*
X1372323Y1722532D01*
X1372948Y1723092D01*
X1373323Y1723745D01*
Y1726079D01*
G01Y1723745D02*
X1376948Y1722345D01*
G01Y1714845D02*
Y1718579D01*
X1369448D01*
Y1714845D01*
G01X1373073Y1716339D02*
Y1718579D01*
G01X1375948Y1711172D02*
X1376573Y1710425D01*
X1376948Y1709585D01*
Y1708839D01*
X1376573Y1708092D01*
X1375948Y1707532D01*
X1375073Y1707252D01*
X1374198Y1707439D01*
X1373448Y1707905D01*
X1372948Y1708745D01*
X1372698Y1709865D01*
X1372198Y1710519D01*
X1371323Y1710799D01*
X1370448Y1710612D01*
X1369823Y1710145D01*
X1369448Y1709492D01*
Y1708839D01*
X1369698Y1708185D01*
X1370323Y1707625D01*
G01X1375948Y1703672D02*
X1376573Y1702925D01*
X1376948Y1702085D01*
Y1701339D01*
X1376573Y1700592D01*
X1375948Y1700032D01*
X1375073Y1699752D01*
X1374198Y1699939D01*
X1373448Y1700405D01*
X1372948Y1701245D01*
X1372698Y1702365D01*
X1372198Y1703019D01*
X1371323Y1703299D01*
X1370448Y1703112D01*
X1369823Y1702645D01*
X1369448Y1701992D01*
Y1701339D01*
X1369698Y1700685D01*
X1370323Y1700125D01*
G01X1374448Y1695425D02*
Y1692999D01*
G01X1376948Y1688485D02*
X1369448D01*
Y1684939D01*
G01X1373073Y1686245D02*
Y1688485D01*
G01X1369448Y1680332D02*
Y1678092D01*
G01Y1679212D02*
X1376948D01*
G01Y1680332D02*
Y1678092D01*
G01X1369448Y1671712D02*
X1376948D01*
G01X1369448Y1673859D02*
Y1669565D01*
G01X1381822Y627014D02*
Y620814D01*
G01D02*
X1385022D01*
G01D02*
Y627014D01*
G01D02*
X1381822D01*
G01X1379705Y627137D02*
Y633337D01*
G01X1382644Y668610D02*
Y680610D01*
G01X1386664Y673794D02*
Y661794D01*
G01D02*
X1392664D01*
G01D02*
Y673794D01*
G01X1392431Y711724D02*
Y676028D01*
G01D02*
X1410147D01*
G01X1392664Y673794D02*
X1386664D01*
G01X1384500Y694443D02*
X1390500D01*
G01D02*
Y706443D01*
G01X1384500D02*
Y694443D01*
G01X1410147Y711724D02*
X1392431D01*
G01X1390500Y706443D02*
X1384500D01*
G01X1393777Y968088D02*
X1387577D01*
Y964888D01*
X1393777D01*
Y968088D01*
G01X1393401Y979865D02*
X1387201D01*
Y976665D01*
X1393401D01*
Y979865D01*
G01X1385577Y980165D02*
X1391777D01*
Y983365D01*
X1385577D01*
Y980165D01*
G01X1393077D02*
X1399277D01*
Y983365D01*
X1393077D01*
Y980165D01*
G01X1389901Y992865D02*
X1383701D01*
Y989665D01*
X1389901D01*
Y992865D01*
G01Y999365D02*
X1383701D01*
Y996165D01*
X1389901D01*
Y999365D01*
G01X1397401Y992865D02*
X1391201D01*
Y989665D01*
X1397401D01*
Y992865D01*
G01Y999365D02*
X1391201D01*
Y996165D01*
X1397401D01*
Y999365D01*
G01X1392277Y986165D02*
X1398477D01*
Y989365D01*
X1392277D01*
Y986165D01*
G01X1385077D02*
X1391277D01*
Y989365D01*
X1385077D01*
Y986165D01*
G01X1390208Y1012003D02*
X1396408D01*
Y1015203D01*
X1390208D01*
Y1012003D01*
G01X1381701Y1005665D02*
X1387901D01*
Y1008865D01*
X1381701D01*
Y1005665D01*
G01X1390208Y1004522D02*
X1396408D01*
Y1007722D01*
X1390208D01*
Y1004522D01*
G01Y1008263D02*
X1396408D01*
Y1011463D01*
X1390208D01*
Y1008263D01*
G01Y1015743D02*
X1396408D01*
Y1018943D01*
X1390208D01*
Y1015743D01*
G01Y1019483D02*
X1396408D01*
Y1022683D01*
X1390208D01*
Y1019483D01*
G01Y1023223D02*
X1396408D01*
Y1026423D01*
X1390208D01*
Y1023223D01*
G01X1381201Y1026665D02*
X1387401D01*
Y1029865D01*
X1381201D01*
Y1026665D01*
G01X1390208Y1026963D02*
X1396408D01*
Y1030163D01*
X1390208D01*
Y1026963D01*
G01X1396408Y1033903D02*
X1390208D01*
Y1030703D01*
X1396408D01*
Y1033903D01*
G01X1390901Y1042365D02*
X1384701D01*
Y1039165D01*
X1390901D01*
Y1042365D01*
G01X1398401D02*
X1392201D01*
Y1039165D01*
X1398401D01*
Y1042365D01*
G01X1381201Y1032665D02*
X1387401D01*
Y1035865D01*
X1381201D01*
Y1032665D01*
G01X1390901Y1048865D02*
X1384701D01*
Y1045665D01*
X1390901D01*
Y1048865D01*
G01X1398401D02*
X1392201D01*
Y1045665D01*
X1398401D01*
Y1048865D01*
G01Y1054865D02*
X1392201D01*
Y1051665D01*
X1398401D01*
Y1054865D01*
G01X1390901D02*
X1384701D01*
Y1051665D01*
X1390901D01*
Y1054865D01*
G01X1396901Y1058365D02*
X1390701D01*
Y1055165D01*
X1396901D01*
Y1058365D01*
G01X1389401D02*
X1383201D01*
Y1055165D01*
X1389401D01*
Y1058365D01*
G01X1394901Y1061865D02*
X1388701D01*
Y1058665D01*
X1394901D01*
Y1061865D01*
G01X1394777Y1073588D02*
X1388577D01*
Y1070388D01*
X1394777D01*
Y1073588D01*
G01X1384000Y1180630D02*
X1497216D01*
G01X1381504Y1273929D02*
X1384604D01*
Y1274849D01*
X1384449Y1275156D01*
X1384087Y1275386D01*
X1383674Y1275463D01*
X1383261Y1275386D01*
X1382951Y1275194D01*
X1382796Y1274849D01*
Y1273929D01*
G01X1384346Y1278639D02*
X1384501Y1278409D01*
X1384604Y1278141D01*
Y1277834D01*
X1384449Y1277489D01*
X1384191Y1277221D01*
X1383881Y1277029D01*
X1383364Y1276876D01*
X1382899Y1276838D01*
X1382434Y1276914D01*
X1382124Y1277029D01*
X1381814Y1277259D01*
X1381607Y1277528D01*
X1381504Y1277796D01*
Y1278064D01*
X1381607Y1278333D01*
X1381762Y1278563D01*
X1381969Y1278754D01*
G01X1381504Y1280896D02*
X1384604D01*
X1383984Y1280436D01*
G01X1381504D02*
Y1281356D01*
G01X1384604Y1283996D02*
X1384501Y1283689D01*
X1384242Y1283459D01*
X1383932Y1283306D01*
X1383519Y1283191D01*
X1383054Y1283153D01*
X1382589Y1283191D01*
X1382176Y1283306D01*
X1381866Y1283459D01*
X1381607Y1283689D01*
X1381504Y1283996D01*
X1381607Y1284303D01*
X1381866Y1284533D01*
X1382176Y1284686D01*
X1382589Y1284801D01*
X1383054Y1284839D01*
X1383519Y1284801D01*
X1383932Y1284686D01*
X1384242Y1284533D01*
X1384501Y1284303D01*
X1384604Y1283996D01*
G01Y1287096D02*
X1384501Y1286789D01*
X1384242Y1286559D01*
X1383932Y1286406D01*
X1383519Y1286291D01*
X1383054Y1286253D01*
X1382589Y1286291D01*
X1382176Y1286406D01*
X1381866Y1286559D01*
X1381607Y1286789D01*
X1381504Y1287096D01*
X1381607Y1287403D01*
X1381866Y1287633D01*
X1382176Y1287786D01*
X1382589Y1287901D01*
X1383054Y1287939D01*
X1383519Y1287901D01*
X1383932Y1287786D01*
X1384242Y1287633D01*
X1384501Y1287403D01*
X1384604Y1287096D01*
G01X1385467Y1287484D02*
X1387707D01*
G01X1386494Y1285859D02*
Y1289109D01*
G01X1391928Y1332592D02*
Y1344592D01*
G01X1385928D02*
Y1332592D01*
G01D02*
X1391928D01*
G01Y1344592D02*
X1385928D01*
G01X1391928Y1347835D02*
Y1359835D01*
G01X1385928Y1347835D02*
X1391928D01*
G01X1385928Y1359835D02*
Y1347835D01*
G01X1391928Y1359835D02*
X1385928D01*
G01X1394981Y1573738D02*
X1391781D01*
G01Y1567538D02*
X1394981D01*
G01X1391781Y1573738D02*
Y1567538D01*
G01X1387057Y1573738D02*
Y1567538D01*
X1390257D01*
Y1573738D01*
X1387057D01*
G01X1382332D02*
Y1567538D01*
X1385532D01*
Y1573738D01*
X1382332D01*
G01X1393438Y1648571D02*
Y1639909D01*
G01D02*
X1403932D01*
G01X1392145Y1652531D02*
X1392452Y1652583D01*
X1392720Y1652789D01*
X1392950Y1653099D01*
X1393103Y1653461D01*
X1393180Y1653874D01*
Y1654288D01*
X1393103Y1654701D01*
X1392950Y1655063D01*
X1392720Y1655373D01*
X1392452Y1655579D01*
X1392145Y1655631D01*
X1391838Y1655579D01*
X1391570Y1655373D01*
X1391340Y1655063D01*
X1391187Y1654701D01*
X1391110Y1654288D01*
Y1653874D01*
X1391187Y1653461D01*
X1391340Y1653099D01*
X1391570Y1652789D01*
X1391838Y1652583D01*
X1392145Y1652531D01*
G01X1391838Y1653358D02*
X1391378Y1652531D01*
G01X1389122D02*
X1389045Y1653203D01*
X1388930Y1653771D01*
X1388777Y1654288D01*
X1388585Y1654856D01*
X1388278Y1655631D01*
X1389812D01*
G01X1385945Y1652531D02*
Y1655631D01*
X1386405Y1655011D01*
G01Y1652531D02*
X1385485D01*
G01X1396785Y1648571D02*
X1393438D01*
G01X1379133Y1781456D02*
Y1646023D01*
G01X1393924Y646480D02*
X1399924D01*
G01D02*
Y658480D01*
G01X1393924D02*
Y646480D01*
G01X1401589Y673189D02*
Y670763D01*
G01X1394664Y673794D02*
Y661794D01*
G01D02*
X1400664D01*
G01D02*
Y673794D01*
G01X1399924Y658480D02*
X1393924D01*
G01X1400664Y673794D02*
X1394664D01*
G01X1402612Y717892D02*
X1400372D01*
G01X1401585Y719517D02*
Y716267D01*
G01X1397915Y721023D02*
X1401015D01*
Y721943D01*
X1400860Y722250D01*
X1400498Y722480D01*
X1400085Y722557D01*
X1399672Y722480D01*
X1399362Y722288D01*
X1399207Y721943D01*
Y721023D01*
G01X1400757Y725733D02*
X1400912Y725503D01*
X1401015Y725235D01*
Y724928D01*
X1400860Y724583D01*
X1400602Y724315D01*
X1400292Y724123D01*
X1399775Y723970D01*
X1399310Y723932D01*
X1398845Y724008D01*
X1398535Y724123D01*
X1398225Y724353D01*
X1398018Y724622D01*
X1397915Y724890D01*
Y725158D01*
X1398018Y725427D01*
X1398173Y725657D01*
X1398380Y725848D01*
G01X1397915Y728450D02*
X1401015D01*
X1398793Y727032D01*
Y728948D01*
G01X1398277Y730438D02*
X1398018Y730707D01*
X1397915Y731013D01*
X1398018Y731320D01*
X1398328Y731588D01*
X1398793Y731780D01*
X1399258Y731857D01*
X1399827D01*
X1400292Y731780D01*
X1400705Y731588D01*
X1400912Y731358D01*
X1401015Y731090D01*
X1400912Y730783D01*
X1400705Y730553D01*
X1400395Y730400D01*
X1399982Y730323D01*
X1399620Y730400D01*
X1399258Y730592D01*
X1399052Y730822D01*
X1399000Y731090D01*
X1399103Y731397D01*
X1399362Y731627D01*
X1399827Y731857D01*
G01X1398380Y733347D02*
X1398122Y733577D01*
X1397967Y733845D01*
X1397915Y734190D01*
X1398018Y734535D01*
X1398225Y734803D01*
X1398587Y734995D01*
X1399000Y735033D01*
X1399413Y734957D01*
X1399672Y734765D01*
X1399878Y734497D01*
X1399930Y734228D01*
X1399878Y733960D01*
X1399672Y733615D01*
X1401015Y733730D01*
Y734765D01*
G01X1395300Y857796D02*
X1406500D01*
G01X1406277Y971588D02*
X1400077D01*
Y968388D01*
X1406277D01*
Y971588D01*
G01X1409637Y966780D02*
X1412737Y972150D01*
X1409965Y973750D01*
X1406865Y968380D01*
X1409637Y966780D01*
G01X1394577Y964888D02*
X1400777D01*
Y968088D01*
X1394577D01*
Y964888D01*
G01X1406741Y981873D02*
X1409841Y976503D01*
X1412613Y978103D01*
X1409513Y983473D01*
X1406741Y981873D01*
G01X1411901Y986865D02*
X1405701D01*
Y983665D01*
X1411901D01*
Y986865D01*
G01X1404997D02*
X1398797D01*
Y983665D01*
X1404997D01*
Y986865D01*
G01X1400077Y980165D02*
X1406277D01*
Y983365D01*
X1400077D01*
Y980165D01*
G01X1394701Y976665D02*
X1400901D01*
Y979865D01*
X1394701D01*
Y976665D01*
G01X1411901Y992865D02*
X1405701D01*
Y989665D01*
X1411901D01*
Y992865D01*
G01X1404901D02*
X1398701D01*
Y989665D01*
X1404901D01*
Y992865D01*
G01Y999365D02*
X1398701D01*
Y996165D01*
X1404901D01*
Y999365D01*
G01X1411901D02*
X1405701D01*
Y996165D01*
X1411901D01*
Y999365D01*
G01X1401663Y1004822D02*
Y1011022D01*
X1398463D01*
Y1004822D01*
X1401663D01*
G01X1405403D02*
Y1011022D01*
X1402203D01*
Y1004822D01*
X1405403D01*
G01X1409143D02*
Y1011022D01*
X1405943D01*
Y1004822D01*
X1409143D01*
G01X1399640Y1013144D02*
X1405840D01*
Y1016344D01*
X1399640D01*
Y1013144D01*
G01X1398468Y1033603D02*
Y1027403D01*
X1401668D01*
Y1033603D01*
X1398468D01*
G01X1402208D02*
Y1027403D01*
X1405408D01*
Y1033603D01*
X1402208D01*
G01X1399640Y1017278D02*
X1405840D01*
Y1020478D01*
X1399640D01*
Y1017278D01*
G01X1405948Y1033603D02*
Y1027403D01*
X1409148D01*
Y1033603D01*
X1405948D01*
G01X1399640Y1021412D02*
X1405840D01*
Y1024612D01*
X1399640D01*
Y1021412D01*
G01X1405901Y1042365D02*
X1399701D01*
Y1039165D01*
X1405901D01*
Y1042365D01*
G01X1412901Y1048865D02*
X1406701D01*
Y1045665D01*
X1412901D01*
Y1048865D01*
G01X1405901D02*
X1399701D01*
Y1045665D01*
X1405901D01*
Y1048865D01*
G01X1413401Y1054865D02*
X1407201D01*
Y1051665D01*
X1413401D01*
Y1054865D01*
G01X1405901D02*
X1399701D01*
Y1051665D01*
X1405901D01*
Y1054865D01*
G01X1403901Y1058365D02*
X1397701D01*
Y1055165D01*
X1403901D01*
Y1058365D01*
G01X1411401D02*
X1405201D01*
Y1055165D01*
X1411401D01*
Y1058365D01*
G01X1395701Y1058665D02*
X1401901D01*
Y1061865D01*
X1395701D01*
Y1058665D01*
G01X1395577Y1070388D02*
X1401777D01*
Y1073588D01*
X1395577D01*
Y1070388D01*
G01X1407477Y1070088D02*
X1401277D01*
Y1066888D01*
X1407477D01*
Y1070088D01*
G01X1395648Y1293652D02*
Y1329348D01*
G01X1403502Y1298349D02*
Y1310349D01*
G01X1397502Y1298349D02*
X1403502D01*
G01X1397502Y1310349D02*
Y1298349D01*
G01X1404086Y1301658D02*
X1407286D01*
G01X1404086Y1307858D02*
Y1301658D01*
G01X1407286Y1307858D02*
X1404086D01*
G01X1407286Y1301658D02*
Y1307858D01*
G01X1403502Y1310349D02*
X1397502D01*
G01X1394306Y1344592D02*
Y1332592D01*
G01X1400306D02*
Y1344592D01*
G01X1394306Y1332592D02*
X1400306D01*
G01Y1344592D02*
X1394306D01*
G01X1402598Y1533897D02*
X1400358D01*
G01X1401571Y1535522D02*
Y1532272D01*
G01X1398923Y1524979D02*
X1397414Y1524983D01*
G01X1398973Y1541912D02*
X1398967Y1524929D01*
G01X1398373Y1541912D02*
X1398377Y1524937D01*
G01X1397773Y1541912D02*
X1397776Y1524972D01*
G01X1404259Y1550953D02*
X1410259D01*
G01X1404259Y1562953D02*
Y1550953D01*
G01X1406079Y1550277D02*
Y1543877D01*
G01D02*
X1418959D01*
G01Y1550277D02*
X1406079D01*
G01X1398973Y1541912D02*
X1397773D01*
G01X1410259Y1562953D02*
X1404259D01*
G01X1404981Y1565721D02*
X1416981D01*
G01X1404981Y1571721D02*
Y1565721D01*
G01X1394981Y1567538D02*
Y1573738D01*
G01X1404981Y1572575D02*
X1416981D01*
G01X1404981Y1578575D02*
Y1572575D01*
G01X1416981Y1578575D02*
X1404981D01*
G01X1416981Y1571721D02*
X1404981D01*
G01X1397112Y1573738D02*
Y1567538D01*
X1400312D01*
Y1573738D01*
X1397112D01*
G01X1406498Y1643005D02*
Y1639805D01*
G01D02*
X1412698D01*
G01X1403932Y1639909D02*
Y1648571D01*
G01X1398501Y1652908D02*
Y1659108D01*
G01X1395301Y1652908D02*
X1398501D01*
G01X1395301Y1659108D02*
Y1652908D01*
G01X1412698Y1643005D02*
X1406498D01*
G01X1405289Y1648120D02*
X1411489D01*
G01X1405289Y1651320D02*
Y1648120D01*
G01X1411489Y1651320D02*
X1405289D01*
G01X1398685Y1646371D02*
X1396785Y1648571D01*
G01X1400585D02*
X1398685Y1646371D01*
G01X1403932Y1648571D02*
X1400585D01*
G01X1398501Y1659108D02*
X1395301D01*
G01X1414522Y659914D02*
Y653714D01*
G01D02*
X1417722D01*
G01D02*
Y659914D01*
G01D02*
X1414522D01*
G01X1409205Y666237D02*
Y660037D01*
G01D02*
X1412405D01*
G01D02*
Y666237D01*
G01D02*
X1409205D01*
G01X1410147Y676028D02*
Y711724D01*
G01X1412044Y701380D02*
X1418044D01*
G01D02*
Y713380D01*
G01X1412044D02*
Y701380D01*
G01X1419264Y706374D02*
Y694374D01*
G01D02*
X1425264D01*
G01X1418044Y713380D02*
X1412044D01*
G01X1425264Y706374D02*
X1419264D01*
G01X1420390Y739173D02*
Y727173D01*
G01D02*
X1426390D01*
G01Y739173D02*
X1420390D01*
G01X1425737Y968380D02*
X1422637Y973750D01*
X1419865Y972150D01*
X1422965Y966780D01*
X1425737Y968380D01*
G01X1414701Y971865D02*
Y965665D01*
X1417901D01*
Y971865D01*
X1414701D01*
G01X1426901Y986865D02*
X1420701D01*
Y983665D01*
X1426901D01*
Y986865D01*
G01X1414701Y979365D02*
Y973165D01*
X1417901D01*
Y979365D01*
X1414701D01*
G01Y986865D02*
Y980665D01*
X1417901D01*
Y986865D01*
X1414701D01*
G01X1428499Y983365D02*
X1422299D01*
Y980165D01*
X1428499D01*
Y983365D01*
G01X1413126Y992165D02*
X1419326D01*
Y995365D01*
X1413126D01*
Y992165D01*
G01X1413201Y988165D02*
X1419401D01*
Y991365D01*
X1413201D01*
Y988165D01*
G01X1426901Y999365D02*
X1420701D01*
Y996165D01*
X1426901D01*
Y999365D01*
G01Y992865D02*
X1420701D01*
Y989665D01*
X1426901D01*
Y992865D01*
G01X1413126Y996165D02*
X1419326D01*
Y999365D01*
X1413126D01*
Y996165D01*
G01Y1000165D02*
X1419326D01*
Y1003365D01*
X1413126D01*
Y1000165D01*
G01X1416624Y1004822D02*
Y1011022D01*
X1413424D01*
Y1004822D01*
X1416624D01*
G01X1409483Y1013144D02*
X1415683D01*
Y1016344D01*
X1409483D01*
Y1013144D01*
G01X1418341D02*
X1424541D01*
Y1016344D01*
X1418341D01*
Y1013144D01*
G01X1424104Y1004822D02*
Y1011022D01*
X1420904D01*
Y1004822D01*
X1424104D01*
G01X1412883D02*
Y1011022D01*
X1409683D01*
Y1004822D01*
X1412883D01*
G01X1420364D02*
Y1011022D01*
X1417164D01*
Y1004822D01*
X1420364D01*
G01X1418341Y1017278D02*
X1424541D01*
Y1020478D01*
X1418341D01*
Y1017278D01*
G01X1420908Y1033603D02*
Y1027403D01*
X1424108D01*
Y1033603D01*
X1420908D01*
G01X1417168D02*
Y1027403D01*
X1420368D01*
Y1033603D01*
X1417168D01*
G01X1409483Y1021412D02*
X1415683D01*
Y1024612D01*
X1409483D01*
Y1021412D01*
G01X1409688Y1033603D02*
Y1027403D01*
X1412888D01*
Y1033603D01*
X1409688D01*
G01X1409483Y1017278D02*
X1415683D01*
Y1020478D01*
X1409483D01*
Y1017278D01*
G01X1413428Y1033603D02*
Y1027403D01*
X1416628D01*
Y1033603D01*
X1413428D01*
G01X1418341Y1021412D02*
X1424541D01*
Y1024612D01*
X1418341D01*
Y1021412D01*
G01X1420401Y1040365D02*
X1414201D01*
Y1037165D01*
X1420401D01*
Y1040365D01*
G01Y1044365D02*
X1414201D01*
Y1041165D01*
X1420401D01*
Y1044365D01*
G01X1427901Y1048865D02*
X1421701D01*
Y1045665D01*
X1427901D01*
Y1048865D01*
G01X1418901Y1050165D02*
Y1056365D01*
X1415701D01*
Y1050165D01*
X1418901D01*
G01X1428191Y1054865D02*
X1421991D01*
Y1051665D01*
X1428191D01*
Y1054865D01*
G01X1410259Y1550953D02*
Y1562953D01*
G01X1417067Y1550953D02*
Y1562953D01*
G01X1411067Y1550953D02*
X1417067D01*
G01X1411067Y1562953D02*
Y1550953D01*
G01X1418959Y1550277D02*
Y1543877D01*
G01X1422006Y1552522D02*
X1425206D01*
G01X1422006Y1558722D02*
Y1552522D01*
G01X1425206Y1558722D02*
X1422006D01*
G01X1418006Y1552522D02*
X1421206D01*
G01X1418006Y1558722D02*
Y1552522D01*
G01X1421206Y1558722D02*
X1418006D01*
G01X1421206Y1552522D02*
Y1558722D01*
G01X1417067Y1562953D02*
X1411067D01*
G01X1416981Y1565721D02*
Y1571721D01*
G01Y1572575D02*
Y1578575D01*
G01X1413569Y1643031D02*
Y1639831D01*
G01X1419769D02*
Y1643031D01*
G01X1413569Y1639831D02*
X1419769D01*
G01X1412698Y1639805D02*
Y1643005D01*
G01X1419769Y1643031D02*
X1413569D01*
G01X1411489Y1648120D02*
Y1651320D01*
G01X1412411Y1651316D02*
Y1648116D01*
G01X1418611Y1651316D02*
X1412411D01*
G01X1418611Y1648116D02*
Y1651316D01*
G01X1412411Y1648116D02*
X1418611D01*
G01X1437281Y-21871D02*
Y-38151D01*
X1446881D01*
Y-21871D01*
X1437281D01*
G01Y-1871D02*
Y-18151D01*
X1446881D01*
Y-1871D01*
X1437281D01*
G01Y18129D02*
Y1849D01*
X1446881D01*
Y18129D01*
X1437281D01*
G01X1435307Y567291D02*
X1438407D01*
Y568211D01*
X1438252Y568518D01*
X1437890Y568748D01*
X1437477Y568825D01*
X1437064Y568748D01*
X1436754Y568556D01*
X1436599Y568211D01*
Y567291D01*
G01X1435307Y571158D02*
X1435359Y570851D01*
X1435565Y570583D01*
X1435875Y570353D01*
X1436237Y570200D01*
X1436650Y570123D01*
X1437064D01*
X1437477Y570200D01*
X1437839Y570353D01*
X1438149Y570583D01*
X1438355Y570851D01*
X1438407Y571158D01*
X1438355Y571465D01*
X1438149Y571733D01*
X1437839Y571963D01*
X1437477Y572116D01*
X1437064Y572193D01*
X1436650D01*
X1436237Y572116D01*
X1435875Y571963D01*
X1435565Y571733D01*
X1435359Y571465D01*
X1435307Y571158D01*
G01X1436134Y571465D02*
X1435307Y571925D01*
G01Y574258D02*
X1438407D01*
X1437787Y573798D01*
G01X1435307D02*
Y574718D01*
G01X1435927Y576515D02*
X1435565Y576745D01*
X1435359Y577051D01*
X1435307Y577396D01*
X1435359Y577703D01*
X1435617Y578010D01*
X1435927Y578201D01*
X1436237Y578240D01*
X1436599Y578163D01*
X1436857Y577895D01*
X1436960Y577626D01*
Y577281D01*
G01Y577626D02*
X1437115Y577856D01*
X1437374Y578048D01*
X1437684Y578125D01*
X1437994Y578048D01*
X1438252Y577856D01*
X1438407Y577511D01*
X1438355Y577166D01*
X1438149Y576821D01*
G01X1426484Y679110D02*
X1432484D01*
G01D02*
Y691110D01*
G01X1426484D02*
Y679110D01*
G01X1437561Y705648D02*
Y703222D01*
G01X1425264Y694374D02*
Y706374D01*
G01X1427264D02*
Y694374D01*
G01D02*
X1433264D01*
G01D02*
Y706374D01*
G01X1432484Y691110D02*
X1426484D01*
G01X1428403Y744183D02*
Y708487D01*
G01D02*
X1446119D01*
G01X1433264Y706374D02*
X1427264D01*
G01X1426390Y727173D02*
Y739173D01*
G01X1438584Y750351D02*
X1436344D01*
G01X1437557Y751976D02*
Y748726D01*
G01X1446119Y744183D02*
X1428403D01*
G01X1431213Y749924D02*
X1434313D01*
Y750844D01*
X1434158Y751151D01*
X1433796Y751381D01*
X1433383Y751458D01*
X1432970Y751381D01*
X1432660Y751189D01*
X1432505Y750844D01*
Y749924D01*
G01X1434055Y754634D02*
X1434210Y754404D01*
X1434313Y754136D01*
Y753829D01*
X1434158Y753484D01*
X1433900Y753216D01*
X1433590Y753024D01*
X1433073Y752871D01*
X1432608Y752833D01*
X1432143Y752909D01*
X1431833Y753024D01*
X1431523Y753254D01*
X1431316Y753523D01*
X1431213Y753791D01*
Y754059D01*
X1431316Y754328D01*
X1431471Y754558D01*
X1431678Y754749D01*
G01X1431213Y757351D02*
X1434313D01*
X1432091Y755933D01*
Y757849D01*
G01X1431575Y759339D02*
X1431316Y759608D01*
X1431213Y759914D01*
X1431316Y760221D01*
X1431626Y760489D01*
X1432091Y760681D01*
X1432556Y760758D01*
X1433125D01*
X1433590Y760681D01*
X1434003Y760489D01*
X1434210Y760259D01*
X1434313Y759991D01*
X1434210Y759684D01*
X1434003Y759454D01*
X1433693Y759301D01*
X1433280Y759224D01*
X1432918Y759301D01*
X1432556Y759493D01*
X1432350Y759723D01*
X1432298Y759991D01*
X1432401Y760298D01*
X1432660Y760528D01*
X1433125Y760758D01*
G01X1431213Y763551D02*
X1434313D01*
X1432091Y762133D01*
Y764049D01*
G01X1426077Y968388D02*
X1432277D01*
Y971588D01*
X1426077D01*
Y968388D01*
G01X1437777Y968088D02*
X1431577D01*
Y964888D01*
X1437777D01*
Y968088D01*
G01X1443401Y983365D02*
X1437201D01*
Y980165D01*
X1443401D01*
Y983365D01*
G01X1437901Y979865D02*
X1431701D01*
Y976665D01*
X1437901D01*
Y979865D01*
G01X1435901Y983365D02*
X1429701D01*
Y980165D01*
X1435901D01*
Y983365D01*
G01Y989365D02*
X1429701D01*
Y986165D01*
X1435901D01*
Y989365D01*
G01X1441401Y999365D02*
X1435201D01*
Y996165D01*
X1441401D01*
Y999365D01*
G01X1443401Y989365D02*
X1437201D01*
Y986165D01*
X1443401D01*
Y989365D01*
G01X1434401Y992865D02*
X1428201D01*
Y989665D01*
X1434401D01*
Y992865D01*
G01X1441401D02*
X1435201D01*
Y989665D01*
X1441401D01*
Y992865D01*
G01X1434401Y999365D02*
X1428201D01*
Y996165D01*
X1434401D01*
Y999365D01*
G01X1443398Y1015203D02*
X1437198D01*
Y1012003D01*
X1443398D01*
Y1015203D01*
G01X1428577Y1013144D02*
X1434777D01*
Y1016344D01*
X1428577D01*
Y1013144D01*
G01X1427844Y1004822D02*
Y1011022D01*
X1424644D01*
Y1004822D01*
X1427844D01*
G01X1431584D02*
Y1011022D01*
X1428384D01*
Y1004822D01*
X1431584D01*
G01X1435324D02*
Y1011022D01*
X1432124D01*
Y1004822D01*
X1435324D01*
G01X1443398Y1007722D02*
X1437198D01*
Y1004522D01*
X1443398D01*
Y1007722D01*
G01Y1011463D02*
X1437198D01*
Y1008263D01*
X1443398D01*
Y1011463D01*
G01X1432129Y1033603D02*
Y1027403D01*
X1435329D01*
Y1033603D01*
X1432129D01*
G01X1424649D02*
Y1027403D01*
X1427849D01*
Y1033603D01*
X1424649D01*
G01X1428577Y1021412D02*
X1434777D01*
Y1024612D01*
X1428577D01*
Y1021412D01*
G01X1443398Y1030163D02*
X1437198D01*
Y1026963D01*
X1443398D01*
Y1030163D01*
G01Y1018943D02*
X1437198D01*
Y1015743D01*
X1443398D01*
Y1018943D01*
G01X1428577Y1017278D02*
X1434777D01*
Y1020478D01*
X1428577D01*
Y1017278D01*
G01X1443398Y1022683D02*
X1437198D01*
Y1019483D01*
X1443398D01*
Y1022683D01*
G01Y1026423D02*
X1437198D01*
Y1023223D01*
X1443398D01*
Y1026423D01*
G01X1428389Y1033603D02*
Y1027403D01*
X1431589D01*
Y1033603D01*
X1428389D01*
G01X1443398Y1033903D02*
X1437198D01*
Y1030703D01*
X1443398D01*
Y1033903D01*
G01X1442901Y1042365D02*
X1436701D01*
Y1039165D01*
X1442901D01*
Y1042365D01*
G01X1435401D02*
X1429201D01*
Y1039165D01*
X1435401D01*
Y1042365D01*
G01Y1048865D02*
X1429201D01*
Y1045665D01*
X1435401D01*
Y1048865D01*
G01X1442901D02*
X1436701D01*
Y1045665D01*
X1442901D01*
Y1048865D01*
G01X1443152Y1054865D02*
X1436952D01*
Y1051665D01*
X1443152D01*
Y1054865D01*
G01X1439401Y1061865D02*
X1433201D01*
Y1058665D01*
X1439401D01*
Y1061865D01*
G01X1429901Y1058365D02*
X1423701D01*
Y1055165D01*
X1429901D01*
Y1058365D01*
G01X1437401D02*
X1431201D01*
Y1055165D01*
X1437401D01*
Y1058365D01*
G01X1435672Y1054865D02*
X1429472D01*
Y1051665D01*
X1435672D01*
Y1054865D01*
G01X1427377Y1066888D02*
X1433577D01*
Y1070088D01*
X1427377D01*
Y1066888D01*
G01X1439277Y1073588D02*
X1433077D01*
Y1070388D01*
X1439277D01*
Y1073588D01*
G01X1425206Y1552522D02*
Y1558722D01*
G01X1426271Y1573146D02*
Y1561146D01*
G01X1432271D02*
Y1573146D01*
G01X1426271Y1561146D02*
X1432271D01*
G01X1433027Y1560892D02*
X1445027D01*
G01X1433027Y1566892D02*
Y1560892D01*
G01X1429789Y1583499D02*
Y1578899D01*
G01D02*
X1439989D01*
G01X1423989Y1583499D02*
Y1578899D01*
G01X1434189D02*
Y1583499D01*
G01X1423989Y1578899D02*
X1434189D01*
G01X1432271Y1573146D02*
X1426271D01*
G01X1445053Y1573746D02*
X1433053D01*
G01Y1567746D02*
X1445053D01*
G01X1433053Y1573746D02*
Y1567746D01*
G01X1445027Y1566892D02*
X1433027D01*
G01X1439989Y1583499D02*
X1429789D01*
G01X1434189D02*
X1423989D01*
G01X1444427Y540918D02*
Y537718D01*
G01D02*
X1450627D01*
G01D02*
Y540918D01*
G01X1444427Y529718D02*
X1450627D01*
G01D02*
Y532918D01*
G01D02*
X1444427D01*
G01D02*
Y529718D01*
G01X1450627Y536918D02*
X1444427D01*
G01D02*
Y533718D01*
G01D02*
X1450627D01*
G01D02*
Y536918D01*
G01Y540918D02*
X1444427D01*
G01X1440888Y557995D02*
Y542641D01*
G01D02*
X1453566D01*
G01X1443927Y559718D02*
X1450127D01*
G01D02*
Y562918D01*
G01D02*
X1443927D01*
G01D02*
Y559718D01*
G01X1453369Y557995D02*
X1440888D01*
G01X1441321Y579130D02*
Y566506D01*
G01D02*
X1453133D01*
G01D02*
Y579130D01*
G01D02*
X1441321D01*
G01X1447122Y692494D02*
Y686294D01*
G01D02*
X1450322D01*
G01D02*
Y692494D01*
G01D02*
X1447122D01*
G01X1441805Y698817D02*
Y692617D01*
G01D02*
X1445005D01*
G01D02*
Y698817D01*
G01D02*
X1441805D01*
G01X1446119Y708487D02*
Y744183D01*
G01X1451431Y725197D02*
Y713197D01*
G01D02*
X1457431D01*
G01Y725197D02*
X1451431D01*
G01X1449334Y759245D02*
Y747245D01*
G01X1455334Y759245D02*
X1449334D01*
G01Y747245D02*
X1455334D01*
G01X1442187Y849252D02*
Y846052D01*
G01X1448387Y849252D02*
X1442187D01*
G01X1448387Y846052D02*
Y849252D01*
G01X1442187Y846052D02*
X1448387D01*
G01X1448203Y845252D02*
Y842052D01*
G01X1454403Y845252D02*
X1448203D01*
G01Y842052D02*
X1454403D01*
G01X1453200Y857796D02*
X1468300D01*
G01X1439077Y964888D02*
X1445277D01*
Y968088D01*
X1439077D01*
Y964888D01*
G01X1458101Y983365D02*
X1451901D01*
Y980165D01*
X1458101D01*
Y983365D01*
G01X1450901D02*
X1444701D01*
Y980165D01*
X1450901D01*
Y983365D01*
G01X1438701Y976665D02*
X1444901D01*
Y979865D01*
X1438701D01*
Y976665D01*
G01X1448901Y992865D02*
X1442701D01*
Y989665D01*
X1448901D01*
Y992865D01*
G01X1458401Y1002365D02*
X1452201D01*
Y999165D01*
X1458401D01*
Y1002365D01*
G01Y989365D02*
X1452201D01*
Y986165D01*
X1458401D01*
Y989365D01*
G01X1448901Y999365D02*
X1442701D01*
Y996165D01*
X1448901D01*
Y999365D01*
G01X1458401Y995865D02*
X1452201D01*
Y992665D01*
X1458401D01*
Y995865D01*
G01X1450901Y989365D02*
X1444701D01*
Y986165D01*
X1450901D01*
Y989365D01*
G01X1458320Y1017073D02*
X1452120D01*
Y1013873D01*
X1458320D01*
Y1017073D01*
G01X1458401Y1008865D02*
X1452201D01*
Y1005665D01*
X1458401D01*
Y1008865D01*
G01X1458320Y1024159D02*
X1452120D01*
Y1020959D01*
X1458320D01*
Y1024159D01*
G01Y1020616D02*
X1452120D01*
Y1017416D01*
X1458320D01*
Y1020616D01*
G01X1459339Y1038865D02*
X1453139D01*
Y1035665D01*
X1459339D01*
Y1038865D01*
G01X1450401Y1042365D02*
X1444201D01*
Y1039165D01*
X1450401D01*
Y1042365D01*
G01X1457401D02*
X1451201D01*
Y1039165D01*
X1457401D01*
Y1042365D01*
G01X1457901Y1048865D02*
X1451701D01*
Y1045665D01*
X1457901D01*
Y1048865D01*
G01X1457401Y1054744D02*
X1451201D01*
Y1051544D01*
X1457401D01*
Y1054744D01*
G01X1451901Y1058365D02*
X1445701D01*
Y1055165D01*
X1451901D01*
Y1058365D01*
G01X1444901D02*
X1438701D01*
Y1055165D01*
X1444901D01*
Y1058365D01*
G01X1459401D02*
X1453201D01*
Y1055165D01*
X1459401D01*
Y1058365D01*
G01X1450401Y1054744D02*
X1444201D01*
Y1051544D01*
X1450401D01*
Y1054744D01*
G01X1440201Y1058665D02*
X1446401D01*
Y1061865D01*
X1440201D01*
Y1058665D01*
G01X1450401Y1048865D02*
X1444201D01*
Y1045665D01*
X1450401D01*
Y1048865D01*
G01X1440077Y1070388D02*
X1446277D01*
Y1073588D01*
X1440077D01*
Y1070388D01*
G01X1445582Y1538743D02*
Y1532743D01*
X1457582D01*
Y1538743D01*
X1445582D01*
G01X1445027Y1560892D02*
Y1566892D01*
G01X1439989Y1578899D02*
Y1583499D01*
G01X1445053Y1567746D02*
Y1573746D01*
G01X1458869Y-35955D02*
X1458559Y-35763D01*
X1458352Y-35533D01*
X1458249Y-35265D01*
X1458352Y-34958D01*
X1458559Y-34728D01*
X1458869Y-34498D01*
X1459282Y-34421D01*
X1461349D01*
G01X1458249Y-32088D02*
X1461349D01*
X1460729Y-32548D01*
G01X1458249D02*
Y-31628D01*
G01Y-28988D02*
X1461349D01*
X1460729Y-29448D01*
G01X1458249D02*
Y-28528D01*
G01X1459541Y-26616D02*
X1459902Y-26348D01*
X1460109Y-26118D01*
X1460212Y-25811D01*
X1460109Y-25543D01*
X1459902Y-25351D01*
X1459592Y-25198D01*
X1459231Y-25160D01*
X1458921Y-25198D01*
X1458611Y-25351D01*
X1458352Y-25581D01*
X1458249Y-25850D01*
X1458352Y-26156D01*
X1458662Y-26425D01*
X1459127Y-26578D01*
X1459644Y-26616D01*
X1460316Y-26540D01*
X1460677Y-26425D01*
X1461039Y-26233D01*
X1461297Y-25965D01*
X1461349Y-25696D01*
X1461246Y-25428D01*
X1460987Y-25236D01*
G01X1458073Y-13902D02*
X1457763Y-13710D01*
X1457556Y-13480D01*
X1457453Y-13212D01*
X1457556Y-12905D01*
X1457763Y-12675D01*
X1458073Y-12445D01*
X1458486Y-12368D01*
X1460553D01*
G01X1458745Y-10763D02*
X1459106Y-10495D01*
X1459313Y-10265D01*
X1459416Y-9958D01*
X1459313Y-9690D01*
X1459106Y-9498D01*
X1458796Y-9345D01*
X1458435Y-9307D01*
X1458125Y-9345D01*
X1457815Y-9498D01*
X1457556Y-9728D01*
X1457453Y-9997D01*
X1457556Y-10303D01*
X1457866Y-10572D01*
X1458331Y-10725D01*
X1458848Y-10763D01*
X1459520Y-10687D01*
X1459881Y-10572D01*
X1460243Y-10380D01*
X1460501Y-10112D01*
X1460553Y-9843D01*
X1460450Y-9575D01*
X1460191Y-9383D01*
G01X1457453Y-6475D02*
X1460553D01*
X1458331Y-7893D01*
Y-5977D01*
G01X1458416Y4608D02*
X1458106Y4800D01*
X1457899Y5030D01*
X1457796Y5298D01*
X1457899Y5605D01*
X1458106Y5835D01*
X1458416Y6065D01*
X1458829Y6142D01*
X1460896D01*
G01X1457796Y8475D02*
X1460896D01*
X1460276Y8015D01*
G01X1457796D02*
Y8935D01*
G01Y11575D02*
X1460896D01*
X1460276Y11115D01*
G01X1457796D02*
Y12035D01*
G01Y14598D02*
X1458468Y14675D01*
X1459036Y14790D01*
X1459553Y14943D01*
X1460121Y15135D01*
X1460896Y15442D01*
Y13908D01*
G01X1464232Y542502D02*
Y536302D01*
G01D02*
X1467432D01*
G01D02*
Y542502D01*
G01X1471357Y550577D02*
X1465157D01*
G01D02*
Y547377D01*
G01D02*
X1471357D01*
G01X1465157Y554577D02*
Y551377D01*
G01D02*
X1471357D01*
G01X1467432Y542502D02*
X1464232D01*
G01X1465157Y543377D02*
X1471357D01*
G01Y546577D02*
X1465157D01*
G01D02*
Y543377D01*
G01X1456344Y545181D02*
X1459444D01*
Y546101D01*
X1459289Y546408D01*
X1458927Y546638D01*
X1458514Y546715D01*
X1458101Y546638D01*
X1457791Y546446D01*
X1457636Y546101D01*
Y545181D01*
G01X1456344Y549048D02*
X1456396Y548741D01*
X1456602Y548473D01*
X1456912Y548243D01*
X1457274Y548090D01*
X1457687Y548013D01*
X1458101D01*
X1458514Y548090D01*
X1458876Y548243D01*
X1459186Y548473D01*
X1459392Y548741D01*
X1459444Y549048D01*
X1459392Y549355D01*
X1459186Y549623D01*
X1458876Y549853D01*
X1458514Y550006D01*
X1458101Y550083D01*
X1457687D01*
X1457274Y550006D01*
X1456912Y549853D01*
X1456602Y549623D01*
X1456396Y549355D01*
X1456344Y549048D01*
G01X1457171Y549355D02*
X1456344Y549815D01*
G01Y552148D02*
X1459444D01*
X1458824Y551688D01*
G01X1456344D02*
Y552608D01*
G01Y555171D02*
X1457016Y555248D01*
X1457584Y555363D01*
X1458101Y555516D01*
X1458669Y555708D01*
X1459444Y556015D01*
Y554481D01*
G01X1453566Y542641D02*
Y557995D01*
G01X1471357Y562577D02*
X1465157D01*
G01D02*
Y559377D01*
G01D02*
X1471357D01*
G01Y554577D02*
X1465157D01*
G01X1457157Y570577D02*
Y567377D01*
G01D02*
X1463357D01*
G01D02*
Y570577D01*
G01X1471357Y566577D02*
X1465157D01*
G01D02*
Y563377D01*
G01D02*
X1471357D01*
G01X1465157Y555377D02*
X1471357D01*
G01Y558577D02*
X1465157D01*
G01D02*
Y555377D01*
G01Y570577D02*
Y567377D01*
G01D02*
X1471357D01*
G01X1463357Y574577D02*
X1457157D01*
G01D02*
Y571377D01*
G01D02*
X1463357D01*
G01D02*
Y574577D01*
G01Y570577D02*
X1457157D01*
G01X1463357Y578577D02*
X1457157D01*
G01D02*
Y575377D01*
G01D02*
X1463357D01*
G01D02*
Y578577D01*
G01X1465157Y579377D02*
X1471357D01*
G01Y582577D02*
X1465157D01*
G01D02*
Y579377D01*
G01X1463357Y582577D02*
X1457157D01*
G01D02*
Y579377D01*
G01D02*
X1463357D01*
G01D02*
Y582577D01*
G01X1465157Y575377D02*
X1471357D01*
G01Y578577D02*
X1465157D01*
G01D02*
Y575377D01*
G01X1471357Y570577D02*
X1465157D01*
G01Y574577D02*
Y571377D01*
G01X1471357Y574577D02*
X1465157D01*
G01Y571377D02*
X1471357D01*
G01X1460189Y698704D02*
X1466189D01*
G01D02*
Y710704D01*
G01X1460189D02*
Y698704D01*
G01X1459809Y725197D02*
Y713197D01*
G01D02*
X1465809D01*
G01D02*
Y725197D01*
G01X1457431Y713197D02*
Y725197D01*
G01X1466189Y710704D02*
X1460189D01*
G01X1468089Y725393D02*
Y722967D01*
G01X1458931Y728232D02*
X1476647D01*
G01X1458931Y763928D02*
Y728232D01*
G01X1465809Y725197D02*
X1459809D01*
G01X1455334Y747245D02*
Y759245D01*
G01X1464225Y772379D02*
X1467325D01*
Y773299D01*
X1467170Y773606D01*
X1466808Y773836D01*
X1466395Y773913D01*
X1465982Y773836D01*
X1465672Y773644D01*
X1465517Y773299D01*
Y772379D01*
G01X1467067Y777089D02*
X1467222Y776859D01*
X1467325Y776591D01*
Y776284D01*
X1467170Y775939D01*
X1466912Y775671D01*
X1466602Y775479D01*
X1466085Y775326D01*
X1465620Y775288D01*
X1465155Y775364D01*
X1464845Y775479D01*
X1464535Y775709D01*
X1464328Y775978D01*
X1464225Y776246D01*
Y776514D01*
X1464328Y776783D01*
X1464483Y777013D01*
X1464690Y777204D01*
G01X1464225Y779806D02*
X1467325D01*
X1465103Y778388D01*
Y780304D01*
G01X1464587Y781794D02*
X1464328Y782063D01*
X1464225Y782369D01*
X1464328Y782676D01*
X1464638Y782944D01*
X1465103Y783136D01*
X1465568Y783213D01*
X1466137D01*
X1466602Y783136D01*
X1467015Y782944D01*
X1467222Y782714D01*
X1467325Y782446D01*
X1467222Y782139D01*
X1467015Y781909D01*
X1466705Y781756D01*
X1466292Y781679D01*
X1465930Y781756D01*
X1465568Y781948D01*
X1465362Y782178D01*
X1465310Y782446D01*
X1465413Y782753D01*
X1465672Y782983D01*
X1466137Y783213D01*
G01X1464225Y785546D02*
X1464277Y785814D01*
X1464432Y786121D01*
X1464690Y786313D01*
X1465052Y786389D01*
X1465413Y786313D01*
X1465723Y786083D01*
X1465878Y785738D01*
Y785354D01*
X1465982Y785124D01*
X1466240Y784933D01*
X1466602Y784856D01*
X1466963Y784971D01*
X1467222Y785239D01*
X1467325Y785546D01*
X1467222Y785853D01*
X1466963Y786121D01*
X1466602Y786236D01*
X1466240Y786159D01*
X1465982Y785968D01*
X1465878Y785738D01*
Y785354D01*
X1465723Y785009D01*
X1465413Y784779D01*
X1465052Y784703D01*
X1464690Y784779D01*
X1464432Y784971D01*
X1464277Y785278D01*
X1464225Y785546D01*
G01X1469112Y770096D02*
X1466872D01*
G01X1468085Y771721D02*
Y768471D01*
G01X1476647Y763928D02*
X1458931D01*
G01X1459559Y841482D02*
X1461100D01*
G01X1459559Y847682D02*
Y841482D01*
G01X1461000Y847682D02*
X1459559D01*
G01X1462759Y843200D02*
Y846600D01*
G01X1467159Y847682D02*
X1465800D01*
G01X1467159Y841482D02*
Y847682D01*
G01X1463959Y846600D02*
Y843200D01*
G01X1465800Y841482D02*
X1467159D01*
G01X1454403Y842052D02*
Y845252D01*
G01X1464047Y964095D02*
G03X1473890Y973937I0J9843D01*
G01X1464777Y964888D02*
Y971088D01*
X1461577D01*
Y964888D01*
X1464777D01*
G01X1460277Y968088D02*
X1454077D01*
Y964888D01*
X1460277D01*
Y968088D01*
G01X1459977Y979865D02*
X1453777D01*
Y976665D01*
X1459977D01*
Y979865D01*
G01X1471277D02*
X1465077D01*
Y976665D01*
X1471277D01*
Y979865D01*
G01X1465901Y983365D02*
X1459701D01*
Y980165D01*
X1465901D01*
Y983365D01*
G01X1472901D02*
X1466701D01*
Y980165D01*
X1472901D01*
Y983365D01*
G01Y989365D02*
X1466701D01*
Y986165D01*
X1472901D01*
Y989365D01*
G01X1465901Y1002365D02*
X1459701D01*
Y999165D01*
X1465901D01*
Y1002365D01*
G01X1472901Y995865D02*
X1466701D01*
Y992665D01*
X1472901D01*
Y995865D01*
G01Y1002365D02*
X1466701D01*
Y999165D01*
X1472901D01*
Y1002365D01*
G01X1465901Y989365D02*
X1459701D01*
Y986165D01*
X1465901D01*
Y989365D01*
G01Y995865D02*
X1459701D01*
Y992665D01*
X1465901D01*
Y995865D01*
G01X1472901Y1017073D02*
X1466701D01*
Y1013873D01*
X1472901D01*
Y1017073D01*
G01Y1008865D02*
X1466701D01*
Y1005665D01*
X1472901D01*
Y1008865D01*
G01X1465901Y1017073D02*
X1459701D01*
Y1013873D01*
X1465901D01*
Y1017073D01*
G01Y1008865D02*
X1459701D01*
Y1005665D01*
X1465901D01*
Y1008865D01*
G01X1462949Y1032844D02*
X1456749D01*
Y1029644D01*
X1462949D01*
Y1032844D01*
G01X1472901Y1020616D02*
X1466701D01*
Y1017416D01*
X1472901D01*
Y1020616D01*
G01Y1024159D02*
X1466701D01*
Y1020959D01*
X1472901D01*
Y1024159D01*
G01X1470350Y1032844D02*
X1464150D01*
Y1029644D01*
X1470350D01*
Y1032844D01*
G01X1468901Y1029344D02*
X1462701D01*
Y1026144D01*
X1468901D01*
Y1029344D01*
G01X1465901Y1024159D02*
X1459701D01*
Y1020959D01*
X1465901D01*
Y1024159D01*
G01X1461401Y1029344D02*
X1455201D01*
Y1026144D01*
X1461401D01*
Y1029344D01*
G01X1465901Y1020616D02*
X1459701D01*
Y1017416D01*
X1465901D01*
Y1020616D01*
G01X1464901Y1042365D02*
X1458701D01*
Y1039165D01*
X1464901D01*
Y1042365D01*
G01X1471901D02*
X1465701D01*
Y1039165D01*
X1471901D01*
Y1042365D01*
G01X1468901Y1036344D02*
X1462701D01*
Y1033144D01*
X1468901D01*
Y1036344D01*
G01X1464901Y1048865D02*
X1458701D01*
Y1045665D01*
X1464901D01*
Y1048865D01*
G01X1472401D02*
X1466201D01*
Y1045665D01*
X1472401D01*
Y1048865D01*
G01X1462001Y1058665D02*
X1468201D01*
Y1061865D01*
X1462001D01*
Y1058665D01*
G01X1470341Y1061973D02*
X1467241Y1056603D01*
X1470013Y1055003D01*
X1473113Y1060373D01*
X1470341Y1061973D01*
G01X1466901Y1058365D02*
X1460701D01*
Y1055165D01*
X1466901D01*
Y1058365D01*
G01X1461477Y1061865D02*
X1455277D01*
Y1058665D01*
X1461477D01*
Y1061865D01*
G01X1472401Y1054744D02*
X1466201D01*
Y1051544D01*
X1472401D01*
Y1054744D01*
G01X1464901D02*
X1458701D01*
Y1051544D01*
X1464901D01*
Y1054744D01*
G01X1473890Y1064489D02*
G03X1464047Y1074331I-9843J-1D01*
G01X1462577Y1073388D02*
Y1067188D01*
X1465777D01*
Y1073388D01*
X1462577D01*
G01X1461277Y1073588D02*
X1455077D01*
Y1070388D01*
X1461277D01*
Y1073588D01*
G01X1463834Y1522313D02*
X1466074D01*
G01X1464861Y1520688D02*
Y1523938D01*
G01X1460859Y1524980D02*
X1496599D01*
Y1541910D01*
X1460859D01*
Y1524980D01*
G01X1459659Y1524978D02*
X1460859D01*
G01X1459659D02*
X1459665Y1541961D01*
G01X1460259Y1524978D02*
X1460255Y1541953D01*
G01X1460859Y1524978D02*
X1460856Y1541918D01*
G01X1459709Y1541911D02*
X1461218Y1541907D01*
G01X1469676Y1573738D02*
X1466476D01*
G01Y1567538D02*
X1469676D01*
G01X1466476Y1573738D02*
Y1567538D01*
G01X1453468Y1570612D02*
X1456668D01*
G01Y1576812D02*
X1453468D01*
G01X1456668Y1570612D02*
Y1576812D01*
G01X1453468D02*
Y1570612D01*
G01X1460226Y1573738D02*
X1457026D01*
G01X1460226Y1567538D02*
Y1573738D01*
G01X1457026Y1567538D02*
X1460226D01*
G01X1457026Y1573738D02*
Y1567538D01*
G01X1461751Y1573738D02*
Y1567538D01*
X1464951D01*
Y1573738D01*
X1461751D01*
G01X1465149Y1661511D02*
Y1681197D01*
G01X1479549Y1661511D02*
X1465149D01*
G01X1468106Y1681197D02*
X1472349Y1676954D01*
G01X1465149Y1681197D02*
X1468106D01*
G01X1471432Y536302D02*
Y542502D01*
G01X1468232D02*
Y536302D01*
G01D02*
X1471432D01*
G01X1490250Y536064D02*
Y539164D01*
X1489330D01*
X1489023Y539009D01*
X1488793Y538647D01*
X1488716Y538234D01*
X1488793Y537821D01*
X1488985Y537511D01*
X1489330Y537356D01*
X1490250D01*
G01X1487226Y539164D02*
Y536942D01*
X1487073Y536477D01*
X1486766Y536167D01*
X1486383Y536064D01*
X1486000Y536167D01*
X1485693Y536477D01*
X1485540Y536942D01*
Y539164D01*
G01X1482823Y536064D02*
Y539164D01*
X1484241Y536942D01*
X1482325D01*
G01X1480911Y538647D02*
X1480681Y538957D01*
X1480413Y539112D01*
X1480106Y539164D01*
X1479723Y539061D01*
X1479455Y538802D01*
X1479378Y538492D01*
X1479416Y538182D01*
X1479570Y537924D01*
X1480336Y537407D01*
X1480681Y537046D01*
X1480911Y536529D01*
X1480988Y536064D01*
X1479378D01*
G01X1471357Y547377D02*
Y550577D01*
G01Y551377D02*
Y554577D01*
G01X1471432Y542502D02*
X1468232D01*
G01X1476857Y539377D02*
Y545577D01*
G01D02*
X1473657D01*
G01D02*
Y539377D01*
G01D02*
X1476857D01*
G01X1471357Y543377D02*
Y546577D01*
G01X1477848Y550916D02*
Y548568D01*
G01D02*
X1480196D01*
G01X1471357Y559377D02*
Y562577D01*
G01Y563377D02*
Y566577D01*
G01Y555377D02*
Y558577D01*
G01Y567377D02*
Y570577D01*
G01X1474583Y580058D02*
X1480783D01*
G01D02*
Y583258D01*
G01X1474583D02*
Y580058D01*
G01X1471357Y579377D02*
Y582577D01*
G01Y575377D02*
Y578577D01*
G01Y571377D02*
Y574577D01*
G01X1480196Y572386D02*
X1477848D01*
G01D02*
Y570038D01*
G01X1480783Y583258D02*
X1474583D01*
G01X1473873Y589933D02*
Y583733D01*
G01D02*
X1477073D01*
G01D02*
Y589933D01*
G01D02*
X1473873D01*
G01X1480040Y712071D02*
Y705871D01*
G01D02*
X1483240D01*
G01Y712071D02*
X1480040D01*
G01X1474723Y718394D02*
Y712194D01*
G01D02*
X1477923D01*
G01D02*
Y718394D01*
G01X1476647Y728232D02*
Y763928D01*
G01X1477923Y718394D02*
X1474723D01*
G01X1479900Y758940D02*
Y746940D01*
G01X1485900Y758940D02*
X1479900D01*
G01Y746940D02*
X1485900D01*
G01X1478777Y804388D02*
Y810588D01*
G01X1475577Y804388D02*
X1478777D01*
G01X1475577Y810588D02*
Y804388D01*
G01X1474777D02*
Y810588D01*
G01X1471577Y804388D02*
X1474777D01*
G01X1471577Y810588D02*
Y804388D01*
G01X1479577D02*
X1482777D01*
G01X1479577Y810588D02*
Y804388D01*
G01X1482777D02*
Y810588D01*
G01X1478777D02*
X1475577D01*
G01X1479777Y817888D02*
Y824088D01*
G01X1476577Y817888D02*
X1479777D01*
G01X1476577Y824088D02*
Y817888D01*
G01X1480577D02*
X1483777D01*
G01X1480577Y824088D02*
Y817888D01*
G01X1472577D02*
X1475777D01*
G01X1472577Y824088D02*
Y817888D01*
G01X1475777D02*
Y824088D01*
G01X1474777Y810588D02*
X1471577D01*
G01X1482777D02*
X1479577D01*
G01X1479777Y824088D02*
X1476577D01*
G01X1483777D02*
X1480577D01*
G01X1475777D02*
X1472577D01*
G01X1481559Y846100D02*
Y843200D01*
G01X1477159Y841482D02*
X1478800D01*
G01X1477159Y847682D02*
Y841482D01*
G01X1478700Y847682D02*
X1477159D01*
G01X1480359Y843200D02*
Y846100D01*
G01X1475959Y847682D02*
X1474300D01*
G01X1475959Y841482D02*
Y847682D01*
G01X1472759Y846300D02*
Y843200D01*
G01X1474500Y841482D02*
X1475959D01*
G01X1468359D02*
X1469700D01*
G01X1468359Y847682D02*
Y841482D01*
G01X1470000Y847682D02*
X1468359D01*
G01X1471559Y843200D02*
Y846300D01*
G01X1473890Y1064489D02*
Y973937D01*
G01X1482858Y1522124D02*
X1483088Y1522279D01*
X1483356Y1522382D01*
X1483663D01*
X1484008Y1522227D01*
X1484276Y1521969D01*
X1484468Y1521659D01*
X1484621Y1521142D01*
X1484659Y1520677D01*
X1484583Y1520212D01*
X1484468Y1519902D01*
X1484238Y1519592D01*
X1483969Y1519385D01*
X1483701Y1519282D01*
X1483433D01*
X1483164Y1519385D01*
X1482934Y1519540D01*
X1482743Y1519747D01*
G01X1480678Y1519282D02*
X1480601Y1519954D01*
X1480486Y1520522D01*
X1480333Y1521039D01*
X1480141Y1521607D01*
X1479834Y1522382D01*
X1481368D01*
G01X1477501D02*
X1477808Y1522279D01*
X1478038Y1522020D01*
X1478191Y1521710D01*
X1478306Y1521297D01*
X1478344Y1520832D01*
X1478306Y1520367D01*
X1478191Y1519954D01*
X1478038Y1519644D01*
X1477808Y1519385D01*
X1477501Y1519282D01*
X1477194Y1519385D01*
X1476964Y1519644D01*
X1476811Y1519954D01*
X1476696Y1520367D01*
X1476658Y1520832D01*
X1476696Y1521297D01*
X1476811Y1521710D01*
X1476964Y1522020D01*
X1477194Y1522279D01*
X1477501Y1522382D01*
G01X1474401Y1519282D02*
Y1522382D01*
X1474861Y1521762D01*
G01Y1519282D02*
X1473941D01*
G01X1471378D02*
X1471301Y1519954D01*
X1471186Y1520522D01*
X1471033Y1521039D01*
X1470841Y1521607D01*
X1470534Y1522382D01*
X1472068D01*
G01X1469676Y1567538D02*
Y1573738D01*
G01X1483849D02*
X1480649D01*
G01Y1567538D02*
X1483849D01*
G01X1480649Y1573738D02*
Y1567538D01*
G01X1471200Y1573738D02*
Y1567538D01*
X1474400D01*
Y1573738D01*
X1471200D01*
G01X1475925D02*
Y1567538D01*
X1479125D01*
Y1573738D01*
X1475925D01*
G01X1479549Y1681197D02*
Y1661511D01*
G01X1478193Y1685600D02*
Y1683378D01*
X1478040Y1682913D01*
X1477733Y1682603D01*
X1477350Y1682500D01*
X1476967Y1682603D01*
X1476660Y1682913D01*
X1476507Y1683378D01*
Y1685600D01*
G01X1474250Y1682500D02*
Y1685600D01*
X1474710Y1684980D01*
G01Y1682500D02*
X1473790D01*
G01X1471227D02*
X1471150Y1683172D01*
X1471035Y1683740D01*
X1470882Y1684257D01*
X1470690Y1684825D01*
X1470383Y1685600D01*
X1471917D01*
G01X1476592Y1681197D02*
X1479549D01*
G01X1472349Y1676954D02*
X1476592Y1681197D01*
G01X1496943Y586965D02*
Y580765D01*
G01D02*
X1500143D01*
G01X1496143D02*
Y586965D01*
G01X1492943D02*
Y580765D01*
G01D02*
X1496143D01*
G01X1500143Y586965D02*
X1496943D01*
G01X1496143D02*
X1492943D01*
G01X1492624Y698637D02*
X1498624D01*
G01X1492624Y710637D02*
Y698637D01*
G01X1483240Y705871D02*
Y712071D01*
G01X1493264Y725951D02*
Y713951D01*
G01D02*
X1499264D01*
G01X1485264Y725951D02*
Y713951D01*
G01D02*
X1491264D01*
G01D02*
Y725951D01*
G01X1498624Y710637D02*
X1492624D01*
G01X1501974Y725708D02*
Y723282D01*
G01X1487793Y728064D02*
X1505509D01*
G01X1487793Y763760D02*
Y728064D01*
G01X1499264Y725951D02*
X1493264D01*
G01X1491264D02*
X1485264D01*
G01X1485900Y746940D02*
Y758940D01*
G01X1497974Y769928D02*
X1495734D01*
G01X1496947Y771553D02*
Y768303D01*
G01X1505509Y763760D02*
X1487793D01*
G01X1490777Y804388D02*
Y810588D01*
G01X1487577Y804388D02*
X1490777D01*
G01X1487577Y810588D02*
Y804388D01*
G01X1491577D02*
X1494777D01*
G01X1491577Y810588D02*
Y804388D01*
G01X1494777D02*
Y810588D01*
G01X1483577Y804388D02*
X1486777D01*
G01X1483577Y810588D02*
Y804388D01*
G01X1486777D02*
Y810588D01*
G01X1498777Y804388D02*
Y810588D01*
X1495577D01*
Y804388D01*
X1498777D01*
G01X1490777Y810588D02*
X1487577D01*
G01X1496577Y817888D02*
X1499777D01*
G01X1496577Y824088D02*
Y817888D01*
G01X1495777D02*
Y824088D01*
G01X1492577Y817888D02*
X1495777D01*
G01X1492577Y824088D02*
Y817888D01*
G01X1483777D02*
Y824088D01*
G01X1494777Y810588D02*
X1491577D01*
G01X1484577Y817888D02*
X1487777D01*
G01X1484577Y824088D02*
Y817888D01*
G01X1487777D02*
Y824088D01*
G01X1488577Y817888D02*
X1491777D01*
G01X1488577Y824088D02*
Y817888D01*
G01X1491777D02*
Y824088D01*
G01X1486777Y810588D02*
X1483577D01*
G01X1498777Y807538D02*
Y813738D01*
X1495577D01*
Y807538D01*
X1498777D01*
G01X1499777Y824088D02*
X1496577D01*
G01X1495777D02*
X1492577D01*
G01X1487777D02*
X1484577D01*
G01X1491777D02*
X1488577D01*
G01X1485959Y841482D02*
X1487900D01*
G01X1485959Y847682D02*
Y841482D01*
G01X1487700Y847682D02*
X1485959D01*
G01X1489159Y843100D02*
Y846000D01*
G01X1493559Y847682D02*
X1492000D01*
G01X1493559Y841482D02*
Y847682D01*
G01X1490359Y846000D02*
Y843100D01*
G01X1492300Y841482D02*
X1493559D01*
G01X1494759D02*
X1496400D01*
G01X1494759Y847682D02*
Y841482D01*
G01X1497959Y843300D02*
Y846300D01*
G01X1496500Y847682D02*
X1494759D01*
G01X1484759D02*
X1483100D01*
G01X1484759Y841482D02*
Y847682D01*
G01X1483500Y841482D02*
X1484759D01*
G01X1502099Y856500D02*
G03X1497216Y857796I-4882J-8547D01*
G01X1491700D02*
X1497216D01*
G01Y1180630D02*
G03X1506964Y1189103I1J9843D01*
G01X1490977Y1523548D02*
X1493403D01*
G01X1488573Y1573738D02*
X1485373D01*
G01X1488573Y1567538D02*
Y1573738D01*
G01X1485373Y1567538D02*
X1488573D01*
G01X1485373Y1573738D02*
Y1567538D01*
G01X1483849D02*
Y1573738D01*
G01X1493298D02*
X1490098D01*
G01X1493298Y1567538D02*
Y1573738D01*
G01X1490098Y1567538D02*
X1493298D01*
G01X1490098Y1573738D02*
Y1567538D01*
G01X1498022Y1573738D02*
X1494822D01*
G01Y1567538D02*
X1498022D01*
G01X1494822Y1573738D02*
Y1567538D01*
G01X1486220Y1646023D02*
Y1683300D01*
G01X1500900Y1646023D02*
X1495200D01*
G01X1488800D02*
X1486220D01*
G01X1499832Y1673177D02*
X1496732D01*
X1499832Y1671413D01*
X1496732D01*
G01X1494800Y1735567D02*
X1487300D01*
Y1733327D01*
X1487675Y1732580D01*
X1488550Y1732020D01*
X1489550Y1731833D01*
X1490550Y1732020D01*
X1491300Y1732487D01*
X1491675Y1733327D01*
Y1735567D01*
G01X1494800Y1728067D02*
X1487300D01*
Y1725733D01*
X1487675Y1724987D01*
X1488175Y1724520D01*
X1489175Y1724333D01*
X1490175Y1724520D01*
X1490800Y1725080D01*
X1491175Y1725733D01*
Y1728067D01*
G01Y1725733D02*
X1494800Y1724333D01*
G01Y1716833D02*
Y1720567D01*
X1487300D01*
Y1716833D01*
G01X1490925Y1718327D02*
Y1720567D01*
G01X1493800Y1713160D02*
X1494425Y1712413D01*
X1494800Y1711573D01*
Y1710827D01*
X1494425Y1710080D01*
X1493800Y1709520D01*
X1492925Y1709240D01*
X1492050Y1709427D01*
X1491300Y1709893D01*
X1490800Y1710733D01*
X1490550Y1711853D01*
X1490050Y1712507D01*
X1489175Y1712787D01*
X1488300Y1712600D01*
X1487675Y1712133D01*
X1487300Y1711480D01*
Y1710827D01*
X1487550Y1710173D01*
X1488175Y1709613D01*
G01X1493800Y1705660D02*
X1494425Y1704913D01*
X1494800Y1704073D01*
Y1703327D01*
X1494425Y1702580D01*
X1493800Y1702020D01*
X1492925Y1701740D01*
X1492050Y1701927D01*
X1491300Y1702393D01*
X1490800Y1703233D01*
X1490550Y1704353D01*
X1490050Y1705007D01*
X1489175Y1705287D01*
X1488300Y1705100D01*
X1487675Y1704633D01*
X1487300Y1703980D01*
Y1703327D01*
X1487550Y1702673D01*
X1488175Y1702113D01*
G01X1492300Y1697413D02*
Y1694987D01*
G01X1494800Y1690473D02*
X1487300D01*
Y1686927D01*
G01X1490925Y1688233D02*
Y1690473D01*
G01X1487300Y1682320D02*
Y1680080D01*
G01Y1681200D02*
X1494800D01*
G01Y1682320D02*
Y1680080D01*
G01X1487300Y1673700D02*
X1494800D01*
G01X1487300Y1675847D02*
Y1671553D01*
G01X1499832Y1678016D02*
X1496732D01*
X1499315Y1677019D01*
X1496732Y1676022D01*
X1499832D01*
G01X1496732Y1682510D02*
X1499832D01*
Y1680976D01*
G01Y1687311D02*
X1496732D01*
G01Y1685855D02*
X1498644Y1687311D01*
G01X1499832Y1685625D02*
X1497765Y1686660D01*
G01X1499212Y1691959D02*
X1499522Y1691767D01*
X1499729Y1691537D01*
X1499832Y1691269D01*
X1499729Y1690962D01*
X1499522Y1690732D01*
X1499212Y1690502D01*
X1498799Y1690425D01*
X1496732D01*
G01Y1696377D02*
Y1695457D01*
G01Y1695917D02*
X1499832D01*
G01Y1696377D02*
Y1695457D01*
G01X1499826Y1701017D02*
X1496726D01*
G01Y1699407D02*
X1499826D01*
G01X1498276D02*
Y1701017D01*
G01X1486220Y1689000D02*
Y1781456D01*
G01X1498176Y1704782D02*
Y1704015D01*
X1499106D01*
X1499416Y1704245D01*
X1499623Y1704514D01*
X1499726Y1704897D01*
X1499623Y1705280D01*
X1499416Y1705549D01*
X1499106Y1705779D01*
X1498744Y1705932D01*
X1498331Y1706009D01*
X1497969D01*
X1497659Y1705932D01*
X1497298Y1705779D01*
X1496988Y1705549D01*
X1496781Y1705319D01*
X1496626Y1705012D01*
Y1704744D01*
X1496729Y1704437D01*
X1496936Y1704207D01*
G01X1499832Y1710818D02*
X1496732D01*
Y1709362D01*
G01X1498230Y1709898D02*
Y1710818D01*
G01X1499832Y1714047D02*
Y1715581D01*
X1496732D01*
Y1714047D01*
G01X1498230Y1714661D02*
Y1715581D01*
G01X1499832Y1720382D02*
X1496732D01*
Y1719616D01*
X1496887Y1719309D01*
X1497094Y1719079D01*
X1497404Y1718887D01*
X1497765Y1718734D01*
X1498282Y1718696D01*
X1498799Y1718734D01*
X1499160Y1718887D01*
X1499470Y1719079D01*
X1499677Y1719309D01*
X1499832Y1719616D01*
Y1720382D01*
G01X1496990Y1723420D02*
X1496835Y1723650D01*
X1496732Y1723918D01*
Y1724225D01*
X1496887Y1724570D01*
X1497145Y1724838D01*
X1497455Y1725030D01*
X1497972Y1725183D01*
X1498437Y1725221D01*
X1498902Y1725145D01*
X1499212Y1725030D01*
X1499522Y1724800D01*
X1499729Y1724531D01*
X1499832Y1724263D01*
Y1723995D01*
X1499729Y1723726D01*
X1499574Y1723496D01*
X1499367Y1723305D01*
G01X1498179Y1728681D02*
X1498024Y1728528D01*
X1497765Y1728413D01*
X1497404Y1728336D01*
X1497094Y1728413D01*
X1496887Y1728566D01*
X1496732Y1728835D01*
Y1729870D01*
X1499832D01*
Y1728605D01*
X1499625Y1728336D01*
X1499315Y1728183D01*
X1498954Y1728106D01*
X1498592Y1728183D01*
X1498282Y1728413D01*
X1498179Y1728681D01*
Y1729870D01*
G01X1499626Y1735170D02*
X1496526Y1734212D01*
X1499626Y1733254D01*
G01X1498541Y1733599D02*
Y1734825D01*
G01X1486220Y1781456D02*
X1576377D01*
G01X1509157Y546377D02*
X1515357D01*
G01Y549577D02*
X1509157D01*
G01D02*
Y546377D01*
G01X1507157Y544577D02*
Y538377D01*
G01D02*
X1510357D01*
G01D02*
Y544577D01*
G01D02*
X1507157D01*
G01X1499157Y538377D02*
X1502357D01*
G01D02*
Y544577D01*
G01D02*
X1500600D01*
G01X1499157Y543600D02*
Y538377D01*
G01X1509157Y550377D02*
X1515357D01*
G01X1509157Y553577D02*
Y550377D01*
G01X1503157Y544577D02*
Y538377D01*
G01D02*
X1506357D01*
G01D02*
Y544577D01*
G01D02*
X1503157D01*
G01X1511157D02*
Y538377D01*
G01D02*
X1514357D01*
G01Y544577D02*
X1511157D01*
G01X1499318Y548568D02*
X1501666D01*
G01D02*
Y550916D01*
G01X1515357Y553577D02*
X1509157D01*
G01X1512357Y566377D02*
Y572577D01*
G01X1509157D02*
Y566377D01*
G01D02*
X1512357D01*
G01X1509157Y554377D02*
X1515357D01*
G01Y557577D02*
X1509157D01*
G01D02*
Y554377D01*
G01Y558377D02*
X1515357D01*
G01Y561577D02*
X1509157D01*
G01D02*
Y558377D01*
G01X1515357Y565577D02*
X1509157D01*
G01D02*
Y562377D01*
G01D02*
X1515357D01*
G01X1512357Y572577D02*
X1509157D01*
G01X1500143Y580765D02*
Y586965D01*
G01X1504143Y580765D02*
Y586965D01*
G01X1500943D02*
Y580765D01*
G01D02*
X1504143D01*
G01X1501666Y572386D02*
X1499318D01*
G01X1501666Y570038D02*
Y572386D01*
G01X1504143Y586965D02*
X1500943D01*
G01X1498624Y698637D02*
Y710637D01*
G01X1507805Y718394D02*
Y712194D01*
G01D02*
X1511005D01*
G01D02*
Y718394D01*
G01X1499264Y713951D02*
Y725951D01*
G01X1505509Y728064D02*
Y763760D01*
G01X1511005Y718394D02*
X1507805D01*
G01X1507454Y759287D02*
Y747287D01*
G01X1513454Y759287D02*
X1507454D01*
G01Y747287D02*
X1513454D01*
G01X1499593Y770027D02*
X1502693D01*
Y770947D01*
X1502538Y771254D01*
X1502176Y771484D01*
X1501763Y771561D01*
X1501350Y771484D01*
X1501040Y771292D01*
X1500885Y770947D01*
Y770027D01*
G01X1502435Y774737D02*
X1502590Y774507D01*
X1502693Y774239D01*
Y773932D01*
X1502538Y773587D01*
X1502280Y773319D01*
X1501970Y773127D01*
X1501453Y772974D01*
X1500988Y772936D01*
X1500523Y773012D01*
X1500213Y773127D01*
X1499903Y773357D01*
X1499696Y773626D01*
X1499593Y773894D01*
Y774162D01*
X1499696Y774431D01*
X1499851Y774661D01*
X1500058Y774852D01*
G01X1499593Y776994D02*
X1502693D01*
X1502073Y776534D01*
G01X1499593D02*
Y777454D01*
G01X1502693Y780094D02*
X1502590Y779787D01*
X1502331Y779557D01*
X1502021Y779404D01*
X1501608Y779289D01*
X1501143Y779251D01*
X1500678Y779289D01*
X1500265Y779404D01*
X1499955Y779557D01*
X1499696Y779787D01*
X1499593Y780094D01*
X1499696Y780401D01*
X1499955Y780631D01*
X1500265Y780784D01*
X1500678Y780899D01*
X1501143Y780937D01*
X1501608Y780899D01*
X1502021Y780784D01*
X1502331Y780631D01*
X1502590Y780401D01*
X1502693Y780094D01*
G01X1499593Y783194D02*
X1499645Y783462D01*
X1499800Y783769D01*
X1500058Y783961D01*
X1500420Y784037D01*
X1500781Y783961D01*
X1501091Y783731D01*
X1501246Y783386D01*
Y783002D01*
X1501350Y782772D01*
X1501608Y782581D01*
X1501970Y782504D01*
X1502331Y782619D01*
X1502590Y782887D01*
X1502693Y783194D01*
X1502590Y783501D01*
X1502331Y783769D01*
X1501970Y783884D01*
X1501608Y783807D01*
X1501350Y783616D01*
X1501246Y783386D01*
Y783002D01*
X1501091Y782657D01*
X1500781Y782427D01*
X1500420Y782351D01*
X1500058Y782427D01*
X1499800Y782619D01*
X1499645Y782926D01*
X1499593Y783194D01*
G01X1502400Y804388D02*
X1505600D01*
G01X1502400Y810588D02*
Y804388D01*
G01X1505600D02*
Y810588D01*
G01X1509777Y804388D02*
Y810588D01*
X1506577D01*
Y804388D01*
X1509777D01*
G01X1499777Y817888D02*
Y824088D01*
G01X1505600Y810588D02*
X1502400D01*
G01X1500577Y817888D02*
X1503777D01*
G01X1500577Y824088D02*
Y817888D01*
G01X1503777D02*
Y824088D01*
G01X1511220Y819024D02*
G03X1520968Y810552I9747J1371D01*
G01X1507403Y846200D02*
X1511220Y819024D01*
G01X1509777Y807538D02*
Y813738D01*
X1506577D01*
Y807538D01*
X1509777D01*
G01X1503777Y824088D02*
X1500577D01*
G01X1502359Y847682D02*
X1500700D01*
G01X1502359Y841482D02*
Y847682D01*
G01X1501000Y841482D02*
X1502359D01*
G01X1499159Y846300D02*
Y843300D01*
G01X1506964Y1189103D02*
X1511220Y1219402D01*
G01X1520968Y1227874D02*
G03X1511220Y1219402I-1J-9843D01*
G01X1502547Y1523282D02*
X1500121D01*
G01X1525162Y1522384D02*
X1525392Y1522539D01*
X1525660Y1522642D01*
X1525967D01*
X1526312Y1522487D01*
X1526580Y1522229D01*
X1526772Y1521919D01*
X1526925Y1521402D01*
X1526963Y1520937D01*
X1526887Y1520472D01*
X1526772Y1520162D01*
X1526542Y1519852D01*
X1526273Y1519645D01*
X1526005Y1519542D01*
X1525737D01*
X1525468Y1519645D01*
X1525238Y1519800D01*
X1525047Y1520007D01*
G01X1522982Y1519542D02*
X1522905Y1520214D01*
X1522790Y1520782D01*
X1522637Y1521299D01*
X1522445Y1521867D01*
X1522138Y1522642D01*
X1523672D01*
G01X1519805D02*
X1520112Y1522539D01*
X1520342Y1522280D01*
X1520495Y1521970D01*
X1520610Y1521557D01*
X1520648Y1521092D01*
X1520610Y1520627D01*
X1520495Y1520214D01*
X1520342Y1519904D01*
X1520112Y1519645D01*
X1519805Y1519542D01*
X1519498Y1519645D01*
X1519268Y1519904D01*
X1519115Y1520214D01*
X1519000Y1520627D01*
X1518962Y1521092D01*
X1519000Y1521557D01*
X1519115Y1521970D01*
X1519268Y1522280D01*
X1519498Y1522539D01*
X1519805Y1522642D01*
G01X1516705Y1519542D02*
Y1522642D01*
X1517165Y1522022D01*
G01Y1519542D02*
X1516245D01*
G01X1513605D02*
X1513337Y1519594D01*
X1513030Y1519749D01*
X1512838Y1520007D01*
X1512762Y1520369D01*
X1512838Y1520730D01*
X1513068Y1521040D01*
X1513413Y1521195D01*
X1513797D01*
X1514027Y1521299D01*
X1514218Y1521557D01*
X1514295Y1521919D01*
X1514180Y1522280D01*
X1513912Y1522539D01*
X1513605Y1522642D01*
X1513298Y1522539D01*
X1513030Y1522280D01*
X1512915Y1521919D01*
X1512992Y1521557D01*
X1513183Y1521299D01*
X1513413Y1521195D01*
X1513797D01*
X1514142Y1521040D01*
X1514372Y1520730D01*
X1514448Y1520369D01*
X1514372Y1520007D01*
X1514180Y1519749D01*
X1513873Y1519594D01*
X1513605Y1519542D01*
G01X1533885Y1541910D02*
X1498145D01*
Y1524980D01*
X1533885D01*
Y1541910D01*
G01X1512195Y1573738D02*
X1508995D01*
G01X1512195Y1567538D02*
Y1573738D01*
G01X1508995Y1567538D02*
X1512195D01*
G01X1508995Y1573738D02*
Y1567538D01*
G01X1498022D02*
Y1573738D01*
G01X1499547D02*
Y1567538D01*
X1502747D01*
Y1573738D01*
X1499547D01*
G01X1513300Y1646023D02*
X1507300D01*
G01X1509876Y1668940D02*
X1509566Y1668710D01*
X1509411Y1668442D01*
X1509359Y1668135D01*
X1509462Y1667752D01*
X1509721Y1667484D01*
X1510031Y1667407D01*
X1510341Y1667445D01*
X1510599Y1667599D01*
X1511116Y1668365D01*
X1511477Y1668710D01*
X1511994Y1668940D01*
X1512459Y1669017D01*
Y1667407D01*
G01X1504585Y1668212D02*
X1501485D01*
X1502105Y1668672D01*
G01X1504585D02*
Y1667752D01*
G01X1514858Y-37898D02*
X1514548Y-37706D01*
X1514341Y-37476D01*
X1514238Y-37208D01*
X1514341Y-36901D01*
X1514548Y-36671D01*
X1514858Y-36441D01*
X1515271Y-36364D01*
X1517338D01*
G01X1514238Y-34108D02*
X1514910Y-34031D01*
X1515478Y-33916D01*
X1515995Y-33763D01*
X1516563Y-33571D01*
X1517338Y-33264D01*
Y-34798D01*
G01X1514238Y-30471D02*
X1517338D01*
X1515116Y-31889D01*
Y-29973D01*
G01X1515357Y546377D02*
Y549577D01*
G01Y550377D02*
Y553577D01*
G01X1514357Y538377D02*
Y544577D01*
G01X1515157D02*
Y538377D01*
G01D02*
X1518357D01*
G01D02*
Y544577D01*
G01D02*
X1515157D01*
G01X1515357Y554377D02*
Y557577D01*
G01Y558377D02*
Y561577D01*
G01X1513157Y569577D02*
Y566377D01*
G01D02*
X1519357D01*
G01D02*
Y569577D01*
G01X1515357Y562377D02*
Y565577D01*
G01X1519357Y569577D02*
X1513157D01*
G01X1529197Y585060D02*
X1528835Y585290D01*
X1528629Y585596D01*
X1528577Y585941D01*
X1528629Y586248D01*
X1528887Y586555D01*
X1529197Y586746D01*
X1529507Y586785D01*
X1529869Y586708D01*
X1530127Y586440D01*
X1530230Y586171D01*
Y585826D01*
G01Y586171D02*
X1530385Y586401D01*
X1530644Y586593D01*
X1530954Y586670D01*
X1531264Y586593D01*
X1531522Y586401D01*
X1531677Y586056D01*
X1531625Y585711D01*
X1531419Y585366D01*
G01X1525334Y698587D02*
X1531334D01*
G01X1525334Y710587D02*
Y698587D01*
G01X1513122Y712071D02*
Y705871D01*
G01D02*
X1516322D01*
G01D02*
Y712071D01*
G01D02*
X1513122D01*
G01X1518064Y725951D02*
Y713951D01*
G01D02*
X1524064D01*
G01D02*
Y725951D01*
G01X1526064D02*
Y713951D01*
G01D02*
X1532064D01*
G01X1531334Y710587D02*
X1525334D01*
G01X1522172Y728077D02*
X1539888D01*
G01X1522172Y763773D02*
Y728077D01*
G01X1524064Y725951D02*
X1518064D01*
G01X1532064D02*
X1526064D01*
G01X1513454Y747287D02*
Y759287D01*
G01X1514300Y759270D02*
Y747270D01*
G01X1520300Y759270D02*
X1514300D01*
G01X1520300Y747270D02*
Y759270D01*
G01X1514300Y747270D02*
X1520300D01*
G01X1539888Y763773D02*
X1522172D01*
G01X1526577Y799288D02*
Y796088D01*
G01X1532777Y799288D02*
X1526577D01*
G01Y796088D02*
X1532777D01*
G01X1526577Y803088D02*
Y799888D01*
G01X1532777Y803088D02*
X1526577D01*
G01Y799888D02*
X1532777D01*
G01X1520968Y810552D02*
X1590819D01*
G01X1520968Y1227874D02*
X1590819D01*
G01X1516920Y1573738D02*
X1513720D01*
G01X1516920Y1567538D02*
Y1573738D01*
G01X1513720Y1567538D02*
X1516920D01*
G01X1513720Y1573738D02*
Y1567538D01*
G01X1523169Y1573738D02*
Y1567538D01*
X1526369D01*
Y1573738D01*
X1523169D01*
G01X1518444D02*
Y1567538D01*
X1521644D01*
Y1573738D01*
X1518444D01*
G01X1525600Y1646023D02*
X1519200D01*
G01X1528207Y1667752D02*
X1525107D01*
X1527329Y1669170D01*
Y1667254D01*
G01X1519713Y1669055D02*
X1520075Y1668825D01*
X1520281Y1668519D01*
X1520333Y1668174D01*
X1520281Y1667867D01*
X1520023Y1667560D01*
X1519713Y1667369D01*
X1519403Y1667330D01*
X1519041Y1667407D01*
X1518783Y1667675D01*
X1518680Y1667944D01*
Y1668289D01*
G01Y1667944D02*
X1518525Y1667714D01*
X1518266Y1667522D01*
X1517956Y1667445D01*
X1517646Y1667522D01*
X1517388Y1667714D01*
X1517233Y1668059D01*
X1517285Y1668404D01*
X1517491Y1668749D01*
G01X1538116Y-42352D02*
Y-26072D01*
X1528516D01*
Y-42352D01*
X1538116D01*
G01X1531334Y698587D02*
Y710587D01*
G01X1540605Y718394D02*
Y712194D01*
G01D02*
X1543805D01*
G01X1532064Y713951D02*
Y725951D01*
G01X1535298Y725276D02*
Y722850D01*
G01X1539888Y728077D02*
Y763773D01*
G01X1543805Y718394D02*
X1540605D01*
G01X1532634Y771194D02*
X1535734D01*
Y772114D01*
X1535579Y772421D01*
X1535217Y772651D01*
X1534804Y772728D01*
X1534391Y772651D01*
X1534081Y772459D01*
X1533926Y772114D01*
Y771194D01*
G01X1535476Y775904D02*
X1535631Y775674D01*
X1535734Y775406D01*
Y775099D01*
X1535579Y774754D01*
X1535321Y774486D01*
X1535011Y774294D01*
X1534494Y774141D01*
X1534029Y774103D01*
X1533564Y774179D01*
X1533254Y774294D01*
X1532944Y774524D01*
X1532737Y774793D01*
X1532634Y775061D01*
Y775329D01*
X1532737Y775598D01*
X1532892Y775828D01*
X1533099Y776019D01*
G01X1532634Y778621D02*
X1535734D01*
X1533512Y777203D01*
Y779119D01*
G01X1532996Y780609D02*
X1532737Y780878D01*
X1532634Y781184D01*
X1532737Y781491D01*
X1533047Y781759D01*
X1533512Y781951D01*
X1533977Y782028D01*
X1534546D01*
X1535011Y781951D01*
X1535424Y781759D01*
X1535631Y781529D01*
X1535734Y781261D01*
X1535631Y780954D01*
X1535424Y780724D01*
X1535114Y780571D01*
X1534701Y780494D01*
X1534339Y780571D01*
X1533977Y780763D01*
X1533771Y780993D01*
X1533719Y781261D01*
X1533822Y781568D01*
X1534081Y781798D01*
X1534546Y782028D01*
G01X1533926Y783633D02*
X1534287Y783901D01*
X1534494Y784131D01*
X1534597Y784438D01*
X1534494Y784706D01*
X1534287Y784898D01*
X1533977Y785051D01*
X1533616Y785089D01*
X1533306Y785051D01*
X1532996Y784898D01*
X1532737Y784668D01*
X1532634Y784399D01*
X1532737Y784093D01*
X1533047Y783824D01*
X1533512Y783671D01*
X1534029Y783633D01*
X1534701Y783709D01*
X1535062Y783824D01*
X1535424Y784016D01*
X1535682Y784284D01*
X1535734Y784553D01*
X1535631Y784821D01*
X1535372Y785013D01*
G01X1532353Y769941D02*
X1530113D01*
G01X1531326Y771566D02*
Y768316D01*
G01X1538777Y799585D02*
X1544977D01*
G01X1538777Y802785D02*
Y799585D01*
G01X1544977Y802785D02*
X1538777D01*
G01Y795585D02*
X1544977D01*
G01X1538777Y798785D02*
Y795585D01*
G01X1544977Y798785D02*
X1538777D01*
G01X1532777Y796088D02*
Y799288D01*
G01Y799888D02*
Y803088D01*
G01X1542172Y1233801D02*
X1545372D01*
G01X1542172Y1240001D02*
Y1233801D01*
G01X1541382Y1233831D02*
Y1240031D01*
G01X1538182Y1233831D02*
X1541382D01*
G01X1538182Y1240031D02*
Y1233831D01*
G01X1533912Y1240031D02*
Y1233831D01*
G01X1537112D02*
Y1240031D01*
G01X1533912Y1233831D02*
X1537112D01*
G01X1545372Y1240001D02*
X1542172D01*
G01X1541382Y1240031D02*
X1538182D01*
G01X1537112D02*
X1533912D01*
G01X1537477Y1262888D02*
Y1266088D01*
G01X1531277Y1262888D02*
X1537477D01*
G01X1531277Y1266088D02*
Y1262888D01*
G01X1537477Y1266088D02*
X1531277D01*
G01X1538577Y1262888D02*
X1544777D01*
G01X1538577Y1266088D02*
Y1262888D01*
G01X1544777Y1266088D02*
X1538577D01*
G01X1538710Y1533897D02*
X1536470D01*
G01X1537683Y1535522D02*
Y1532272D01*
G01X1535035Y1524979D02*
X1533526Y1524983D01*
G01X1535085Y1541912D02*
X1535079Y1524929D01*
G01X1534485Y1541912D02*
X1534489Y1524937D01*
G01X1533885Y1541912D02*
X1533888Y1524972D01*
G01X1540371Y1550953D02*
X1546371D01*
G01X1540371Y1562953D02*
Y1550953D01*
G01X1542191Y1550277D02*
Y1543877D01*
G01D02*
X1555071D01*
G01Y1550277D02*
X1542191D01*
G01X1535085Y1541912D02*
X1533885D01*
G01X1546371Y1562953D02*
X1540371D01*
G01X1541093Y1565721D02*
X1553093D01*
G01X1541093Y1571721D02*
Y1565721D01*
G01X1527893Y1573738D02*
Y1567538D01*
X1531093D01*
Y1573738D01*
X1527893D01*
G01X1553093Y1571721D02*
X1541093D01*
G01Y1572575D02*
X1553093D01*
G01X1541093Y1578575D02*
Y1572575D01*
G01X1553093Y1578575D02*
X1541093D01*
G01X1533224Y1573738D02*
Y1567538D01*
X1536424D01*
Y1573738D01*
X1533224D01*
G01X1536800Y1646023D02*
X1530900D01*
G01X1535616Y1669055D02*
X1535874Y1668825D01*
X1536029Y1668557D01*
X1536081Y1668212D01*
X1535978Y1667867D01*
X1535771Y1667599D01*
X1535409Y1667407D01*
X1534996Y1667369D01*
X1534583Y1667445D01*
X1534324Y1667637D01*
X1534118Y1667905D01*
X1534066Y1668174D01*
X1534118Y1668442D01*
X1534324Y1668787D01*
X1532981Y1668672D01*
Y1667637D01*
G01X1542663Y1668940D02*
X1542302Y1668672D01*
X1542095Y1668442D01*
X1541992Y1668135D01*
X1542095Y1667867D01*
X1542302Y1667675D01*
X1542612Y1667522D01*
X1542973Y1667484D01*
X1543283Y1667522D01*
X1543593Y1667675D01*
X1543852Y1667905D01*
X1543955Y1668174D01*
X1543852Y1668480D01*
X1543542Y1668749D01*
X1543077Y1668902D01*
X1542560Y1668940D01*
X1541888Y1668864D01*
X1541527Y1668749D01*
X1541165Y1668557D01*
X1540907Y1668289D01*
X1540855Y1668020D01*
X1540958Y1667752D01*
X1541217Y1667560D01*
G01X1559387Y598959D02*
Y596737D01*
X1559234Y596272D01*
X1558927Y595962D01*
X1558544Y595859D01*
X1558161Y595962D01*
X1557854Y596272D01*
X1557701Y596737D01*
Y598959D01*
G01X1556287Y596479D02*
X1556057Y596117D01*
X1555751Y595911D01*
X1555406Y595859D01*
X1555099Y595911D01*
X1554792Y596169D01*
X1554601Y596479D01*
X1554562Y596789D01*
X1554639Y597151D01*
X1554907Y597409D01*
X1555176Y597512D01*
X1555521D01*
G01X1555176D02*
X1554946Y597667D01*
X1554754Y597926D01*
X1554677Y598236D01*
X1554754Y598546D01*
X1554946Y598804D01*
X1555291Y598959D01*
X1555636Y598907D01*
X1555981Y598701D01*
G01X1553072Y598442D02*
X1552842Y598752D01*
X1552574Y598907D01*
X1552267Y598959D01*
X1551884Y598856D01*
X1551616Y598597D01*
X1551539Y598287D01*
X1551577Y597977D01*
X1551731Y597719D01*
X1552497Y597202D01*
X1552842Y596841D01*
X1553072Y596324D01*
X1553149Y595859D01*
X1551539D01*
G01X1548784D02*
Y598959D01*
X1550202Y596737D01*
X1548286D01*
G01X1548877Y585853D02*
X1551977D01*
X1551357Y585393D01*
G01X1548877D02*
Y586313D01*
G01X1562136Y612465D02*
X1549512D01*
G01Y600653D02*
X1562136D01*
G01X1549512Y612465D02*
Y600653D01*
G01X1552587Y674098D02*
Y668098D01*
G01D02*
X1564587D01*
G01Y674098D02*
X1552587D01*
G01X1551194Y704011D02*
Y692011D01*
G01D02*
X1557194D01*
G01D02*
Y704011D01*
G01X1557583Y741820D02*
Y706124D01*
G01D02*
X1575299D01*
G01X1545922Y712071D02*
Y705871D01*
G01D02*
X1549122D01*
G01D02*
Y712071D01*
G01D02*
X1545922D01*
G01X1543805Y712194D02*
Y718394D01*
G01X1557194Y704011D02*
X1551194D01*
G01X1549500Y736840D02*
Y724840D01*
G01X1555500D02*
Y736840D01*
G01X1549500Y724840D02*
X1555500D01*
G01X1575299Y741820D02*
X1557583D01*
G01X1555500Y736840D02*
X1549500D01*
G01X1543047Y776988D02*
Y764988D01*
G01X1549047D02*
Y776988D01*
G01X1543047Y764988D02*
X1549047D01*
G01X1557203Y787308D02*
Y793508D01*
G01X1554003Y787308D02*
X1557203D01*
G01X1554003Y793508D02*
Y787308D01*
G01X1552032Y787226D02*
Y793426D01*
G01X1548832Y787226D02*
X1552032D01*
G01X1548832Y793426D02*
Y787226D01*
G01X1549047Y776988D02*
X1543047D01*
G01X1557203Y793508D02*
X1554003D01*
G01X1552032Y793426D02*
X1548832D01*
G01X1554511Y799587D02*
X1557711D01*
G01X1554511Y805787D02*
Y799587D01*
G01X1557711Y805787D02*
X1554511D01*
G01X1551846Y802533D02*
Y805733D01*
G01X1545646Y802533D02*
X1551846D01*
G01X1545646Y805733D02*
Y802533D01*
G01X1551846Y805733D02*
X1545646D01*
G01X1544977Y799585D02*
Y802785D01*
G01Y795585D02*
Y798785D01*
G01X1556163Y1236062D02*
X1562363D01*
G01X1556163Y1239262D02*
Y1236062D01*
G01X1556577Y1235762D02*
Y1232562D01*
G01X1562777Y1235762D02*
X1556577D01*
G01Y1232562D02*
X1562777D01*
G01X1545372Y1233801D02*
Y1240001D01*
G01X1562363Y1239262D02*
X1556163D01*
G01X1571929Y1252720D02*
X1556677D01*
G01Y1240604D02*
X1571929D01*
G01X1556677Y1252720D02*
Y1240604D01*
G01X1552852Y1266888D02*
Y1270088D01*
G01X1546652Y1266888D02*
X1552852D01*
G01X1546652Y1270088D02*
Y1266888D01*
G01X1552852Y1262888D02*
Y1266088D01*
G01X1546652Y1262888D02*
X1552852D01*
G01X1546652Y1266088D02*
Y1262888D01*
G01X1552852Y1266088D02*
X1546652D01*
G01X1544777Y1262888D02*
Y1266088D01*
G01X1552852Y1270088D02*
X1546652D01*
G01X1552717Y1272778D02*
Y1275978D01*
G01X1546517Y1272778D02*
X1552717D01*
G01X1546517Y1275978D02*
Y1272778D01*
G01X1552717Y1275978D02*
X1546517D01*
G01X1552777Y1277388D02*
Y1280588D01*
G01X1546577Y1277388D02*
X1552777D01*
G01X1546577Y1280588D02*
Y1277388D01*
G01X1552777Y1280588D02*
X1546577D01*
G01X1552777Y1281388D02*
Y1284588D01*
G01X1546577Y1281388D02*
X1552777D01*
G01X1546577Y1284588D02*
Y1281388D01*
G01X1552777Y1284588D02*
X1546577D01*
G01X1552077Y1288338D02*
Y1291538D01*
G01X1545877Y1288338D02*
X1552077D01*
G01X1545877Y1291538D02*
Y1288338D01*
G01X1552077Y1291538D02*
X1545877D01*
G01X1546371Y1550953D02*
Y1562953D01*
G01X1553179Y1550953D02*
Y1562953D01*
G01X1547179Y1550953D02*
X1553179D01*
G01X1547179Y1562953D02*
Y1550953D01*
G01X1555071Y1550277D02*
Y1543877D01*
G01X1554118Y1552522D02*
X1557318D01*
G01X1554118Y1558722D02*
Y1552522D01*
G01X1557318Y1558722D02*
X1554118D01*
G01X1557318Y1552522D02*
Y1558722D01*
G01X1554333Y1573146D02*
Y1561146D01*
G01D02*
X1560333D01*
G01X1553179Y1562953D02*
X1547179D01*
G01X1553093Y1565721D02*
Y1571721D01*
G01X1552051Y1583499D02*
Y1578899D01*
G01D02*
X1562251D01*
G01X1560333Y1573146D02*
X1554333D01*
G01X1553093Y1572575D02*
Y1578575D01*
G01X1562251Y1583499D02*
X1552051D01*
G01X1561600Y1646023D02*
X1555100D01*
G01X1553150Y1649200D02*
Y1781456D01*
G01X1561600Y1646023D02*
X1555100D01*
G01X1549200D02*
X1543100D01*
G01X1559703Y1668212D02*
X1559651Y1667944D01*
X1559496Y1667637D01*
X1559238Y1667445D01*
X1558876Y1667369D01*
X1558515Y1667445D01*
X1558205Y1667675D01*
X1558050Y1668020D01*
Y1668404D01*
X1557946Y1668634D01*
X1557688Y1668825D01*
X1557326Y1668902D01*
X1556965Y1668787D01*
X1556706Y1668519D01*
X1556603Y1668212D01*
X1556706Y1667905D01*
X1556965Y1667637D01*
X1557326Y1667522D01*
X1557688Y1667599D01*
X1557946Y1667790D01*
X1558050Y1668020D01*
Y1668404D01*
X1558205Y1668749D01*
X1558515Y1668979D01*
X1558876Y1669055D01*
X1559238Y1668979D01*
X1559496Y1668787D01*
X1559651Y1668480D01*
X1559703Y1668212D01*
G01X1551829Y1668289D02*
X1551157Y1668212D01*
X1550589Y1668097D01*
X1550072Y1667944D01*
X1549504Y1667752D01*
X1548729Y1667445D01*
Y1668979D01*
G01X1553150Y1781456D02*
X1643307D01*
G01X1572400Y570100D02*
Y563900D01*
G01D02*
X1575600D01*
G01X1569436Y575547D02*
X1566236D01*
G01X1569436Y569347D02*
Y575547D01*
G01X1566236Y569347D02*
X1569436D01*
G01X1566236Y575547D02*
Y569347D01*
G01X1575600Y570100D02*
X1572400D01*
G01X1564263Y590771D02*
X1571563D01*
G01D02*
Y608369D01*
G01X1564263D02*
Y590771D01*
G01X1562136Y600653D02*
Y612465D01*
G01X1571563Y608369D02*
X1564263D01*
G01X1564587Y668098D02*
Y674098D01*
G01X1567394Y661305D02*
X1573394D01*
G01X1567394Y673305D02*
Y661305D01*
G01X1558464Y676657D02*
X1564464D01*
G01D02*
Y688657D01*
G01X1558464D02*
Y676657D01*
G01X1573394Y673305D02*
X1567394D01*
G01X1566741Y703285D02*
Y700859D01*
G01X1559194Y704011D02*
Y692011D01*
G01D02*
X1565194D01*
G01D02*
Y704011D01*
G01X1564464Y688657D02*
X1558464D01*
G01X1565194Y704011D02*
X1559194D01*
G01X1567764Y747988D02*
X1565524D01*
G01X1566737Y749613D02*
Y746363D01*
G01X1565483Y751787D02*
X1568583D01*
Y752707D01*
X1568428Y753014D01*
X1568066Y753244D01*
X1567653Y753321D01*
X1567240Y753244D01*
X1566930Y753052D01*
X1566775Y752707D01*
Y751787D01*
G01X1568325Y756497D02*
X1568480Y756267D01*
X1568583Y755999D01*
Y755692D01*
X1568428Y755347D01*
X1568170Y755079D01*
X1567860Y754887D01*
X1567343Y754734D01*
X1566878Y754696D01*
X1566413Y754772D01*
X1566103Y754887D01*
X1565793Y755117D01*
X1565586Y755386D01*
X1565483Y755654D01*
Y755922D01*
X1565586Y756191D01*
X1565741Y756421D01*
X1565948Y756612D01*
G01X1566775Y758026D02*
X1567136Y758294D01*
X1567343Y758524D01*
X1567446Y758831D01*
X1567343Y759099D01*
X1567136Y759291D01*
X1566826Y759444D01*
X1566465Y759482D01*
X1566155Y759444D01*
X1565845Y759291D01*
X1565586Y759061D01*
X1565483Y758792D01*
X1565586Y758486D01*
X1565896Y758217D01*
X1566361Y758064D01*
X1566878Y758026D01*
X1567550Y758102D01*
X1567911Y758217D01*
X1568273Y758409D01*
X1568531Y758677D01*
X1568583Y758946D01*
X1568480Y759214D01*
X1568221Y759406D01*
G01X1568583Y761854D02*
X1568480Y761547D01*
X1568221Y761317D01*
X1567911Y761164D01*
X1567498Y761049D01*
X1567033Y761011D01*
X1566568Y761049D01*
X1566155Y761164D01*
X1565845Y761317D01*
X1565586Y761547D01*
X1565483Y761854D01*
X1565586Y762161D01*
X1565845Y762391D01*
X1566155Y762544D01*
X1566568Y762659D01*
X1567033Y762697D01*
X1567498Y762659D01*
X1567911Y762544D01*
X1568221Y762391D01*
X1568480Y762161D01*
X1568583Y761854D01*
G01X1565483Y764954D02*
X1568583D01*
X1567963Y764494D01*
G01X1565483D02*
Y765414D01*
G01X1569198Y790952D02*
Y794152D01*
G01X1562998Y790952D02*
X1569198D01*
G01X1562998Y794152D02*
Y790952D01*
G01X1561218Y787274D02*
Y793474D01*
G01X1558018Y787274D02*
X1561218D01*
G01X1558018Y793474D02*
Y787274D01*
G01X1567993Y802463D02*
X1574193D01*
G01X1567993Y805663D02*
Y802463D01*
G01X1574193Y805663D02*
X1567993D01*
G01X1569198Y794152D02*
X1562998D01*
G01X1569198Y794952D02*
Y798152D01*
G01X1562998Y794952D02*
X1569198D01*
G01X1562998Y798152D02*
Y794952D01*
G01X1569198Y798152D02*
X1562998D01*
G01X1561218Y793474D02*
X1558018D01*
G01X1557711Y799587D02*
Y805787D01*
G01X1558317Y799577D02*
X1561517D01*
G01X1558317Y805777D02*
Y799577D01*
G01X1561517Y805777D02*
X1558317D01*
G01X1561517Y799577D02*
Y805777D01*
G01X1562363Y1236062D02*
Y1239262D01*
G01X1563163D02*
Y1236062D01*
G01X1569363D02*
Y1239262D01*
G01X1563163Y1236062D02*
X1569363D01*
G01X1562777Y1232562D02*
Y1235762D01*
G01X1569777Y1232562D02*
Y1235762D01*
G01X1563577Y1232562D02*
X1569777D01*
G01X1563577Y1235762D02*
Y1232562D01*
G01X1569777Y1235762D02*
X1563577D01*
G01X1569363Y1239262D02*
X1563163D01*
G01X1571929Y1240604D02*
Y1252720D01*
G01X1575472Y1255646D02*
Y1257041D01*
X1576239Y1258746D01*
G01X1574705D02*
X1575472Y1257041D01*
G01X1573215Y1256266D02*
X1572985Y1255904D01*
X1572679Y1255698D01*
X1572334Y1255646D01*
X1572027Y1255698D01*
X1571720Y1255956D01*
X1571529Y1256266D01*
X1571490Y1256576D01*
X1571567Y1256938D01*
X1571835Y1257196D01*
X1572104Y1257299D01*
X1572449D01*
G01X1572104D02*
X1571874Y1257454D01*
X1571682Y1257713D01*
X1571605Y1258023D01*
X1571682Y1258333D01*
X1571874Y1258591D01*
X1572219Y1258746D01*
X1572564Y1258694D01*
X1572909Y1258488D01*
G01X1567065Y1256829D02*
Y1258224D01*
X1567832Y1259929D01*
G01X1566298D02*
X1567065Y1258224D01*
G01X1564693Y1259412D02*
X1564463Y1259722D01*
X1564195Y1259877D01*
X1563888Y1259929D01*
X1563505Y1259826D01*
X1563237Y1259567D01*
X1563160Y1259257D01*
X1563198Y1258947D01*
X1563352Y1258689D01*
X1564118Y1258172D01*
X1564463Y1257811D01*
X1564693Y1257294D01*
X1564770Y1256829D01*
X1563160D01*
G01X1565277Y1282508D02*
Y1285708D01*
G01X1559077Y1282508D02*
X1565277D01*
G01X1559077Y1285708D02*
Y1282508D01*
G01X1566507Y1277188D02*
X1572707D01*
Y1280388D01*
X1566507D01*
Y1277188D01*
G01X1569557Y1280388D02*
X1563357D01*
Y1277188D01*
X1569557D01*
Y1280388D01*
G01X1558107Y1292018D02*
Y1288818D01*
G01X1564307Y1292018D02*
X1558107D01*
G01X1564307Y1288818D02*
Y1292018D01*
G01X1558107Y1288818D02*
X1564307D01*
G01X1558107Y1295518D02*
Y1292318D01*
G01X1564307Y1295518D02*
X1558107D01*
G01X1564307Y1292318D02*
Y1295518D01*
G01X1558107Y1292318D02*
X1564307D01*
G01X1565277Y1285708D02*
X1559077D01*
G01X1565577Y1287708D02*
Y1284508D01*
G01X1571777Y1287708D02*
X1565577D01*
G01X1571777Y1284508D02*
Y1287708D01*
G01X1565577Y1284508D02*
X1571777D01*
G01X1567902Y1297968D02*
X1574102D01*
G01X1567902Y1301168D02*
Y1297968D01*
G01X1574102Y1301168D02*
X1567902D01*
G01X1567548Y1340098D02*
X1570748D01*
G01D02*
Y1346298D01*
G01X1567548D02*
Y1340098D01*
G01X1563902Y1340084D02*
X1567102D01*
G01X1563902Y1346284D02*
Y1340084D01*
G01X1567102D02*
Y1346284D01*
G01X1571324Y1340098D02*
X1574524D01*
G01X1571324Y1346298D02*
Y1340098D01*
G01X1571306Y1354578D02*
X1574506D01*
G01X1571306Y1360778D02*
Y1354578D01*
G01X1567306D02*
X1570506D01*
G01X1567306Y1360778D02*
Y1354578D01*
G01X1570506D02*
Y1360778D01*
G01X1570748Y1346298D02*
X1567548D01*
G01X1567102Y1346284D02*
X1563902D01*
G01X1574524Y1346298D02*
X1571324D01*
G01X1574506Y1360778D02*
X1571306D01*
G01X1570506D02*
X1567306D01*
G01X1558118Y1552522D02*
X1561318D01*
G01X1558118Y1558722D02*
Y1552522D01*
G01X1561318Y1558722D02*
X1558118D01*
G01X1561318Y1552522D02*
Y1558722D01*
G01X1561089Y1560892D02*
X1573089D01*
G01X1561089Y1566892D02*
Y1560892D01*
G01X1560333Y1561146D02*
Y1573146D01*
G01X1562251Y1578899D02*
Y1583499D01*
G01X1557851D02*
Y1578899D01*
G01X1568051D02*
Y1583499D01*
G01X1557851Y1578899D02*
X1568051D01*
G01X1573089Y1566892D02*
X1561089D01*
G01X1573115Y1573746D02*
X1561115D01*
G01Y1567746D02*
X1573115D01*
G01X1561115Y1573746D02*
Y1567746D01*
G01X1568051Y1583499D02*
X1557851D01*
G01X1573300Y1646023D02*
X1567500D01*
G01X1573300D02*
X1567500D01*
G01X1571515Y1668212D02*
X1568415D01*
X1569035Y1668672D01*
G01X1571515D02*
Y1667752D01*
G01X1566762Y1673177D02*
X1563662D01*
X1566762Y1671413D01*
X1563662D01*
G01X1566762Y1678016D02*
X1563662D01*
X1566245Y1677019D01*
X1563662Y1676022D01*
X1566762D01*
G01X1563662Y1682510D02*
X1566762D01*
Y1680976D01*
G01Y1687311D02*
X1563662D01*
G01Y1685855D02*
X1565574Y1687311D01*
G01X1566762Y1685625D02*
X1564695Y1686660D01*
G01X1566142Y1691959D02*
X1566452Y1691767D01*
X1566659Y1691537D01*
X1566762Y1691269D01*
X1566659Y1690962D01*
X1566452Y1690732D01*
X1566142Y1690502D01*
X1565729Y1690425D01*
X1563662D01*
G01Y1696377D02*
Y1695457D01*
G01Y1695917D02*
X1566762D01*
G01Y1696377D02*
Y1695457D01*
G01X1566756Y1701017D02*
X1563656D01*
G01Y1699407D02*
X1566756D01*
G01X1565206D02*
Y1701017D01*
G01X1565106Y1704782D02*
Y1704015D01*
X1566036D01*
X1566346Y1704245D01*
X1566553Y1704514D01*
X1566656Y1704897D01*
X1566553Y1705280D01*
X1566346Y1705549D01*
X1566036Y1705779D01*
X1565674Y1705932D01*
X1565261Y1706009D01*
X1564899D01*
X1564589Y1705932D01*
X1564228Y1705779D01*
X1563918Y1705549D01*
X1563711Y1705319D01*
X1563556Y1705012D01*
Y1704744D01*
X1563659Y1704437D01*
X1563866Y1704207D01*
G01X1566762Y1710818D02*
X1563662D01*
Y1709362D01*
G01X1565160Y1709898D02*
Y1710818D01*
G01X1566762Y1714047D02*
Y1715581D01*
X1563662D01*
Y1714047D01*
G01X1565160Y1714661D02*
Y1715581D01*
G01X1566762Y1720382D02*
X1563662D01*
Y1719616D01*
X1563817Y1719309D01*
X1564024Y1719079D01*
X1564334Y1718887D01*
X1564695Y1718734D01*
X1565212Y1718696D01*
X1565729Y1718734D01*
X1566090Y1718887D01*
X1566400Y1719079D01*
X1566607Y1719309D01*
X1566762Y1719616D01*
Y1720382D01*
G01X1563920Y1723420D02*
X1563765Y1723650D01*
X1563662Y1723918D01*
Y1724225D01*
X1563817Y1724570D01*
X1564075Y1724838D01*
X1564385Y1725030D01*
X1564902Y1725183D01*
X1565367Y1725221D01*
X1565832Y1725145D01*
X1566142Y1725030D01*
X1566452Y1724800D01*
X1566659Y1724531D01*
X1566762Y1724263D01*
Y1723995D01*
X1566659Y1723726D01*
X1566504Y1723496D01*
X1566297Y1723305D01*
G01X1565109Y1728681D02*
X1564954Y1728528D01*
X1564695Y1728413D01*
X1564334Y1728336D01*
X1564024Y1728413D01*
X1563817Y1728566D01*
X1563662Y1728835D01*
Y1729870D01*
X1566762D01*
Y1728605D01*
X1566555Y1728336D01*
X1566245Y1728183D01*
X1565884Y1728106D01*
X1565522Y1728183D01*
X1565212Y1728413D01*
X1565109Y1728681D01*
Y1729870D01*
G01X1566556Y1735170D02*
X1563456Y1734212D01*
X1566556Y1733254D01*
G01X1565471Y1733599D02*
Y1734825D01*
G01X1575600Y563900D02*
Y570100D01*
G01X1572563Y590771D02*
X1579863D01*
G01D02*
Y608369D01*
G01X1572563D02*
Y590771D01*
G01X1580863D02*
X1588163D01*
G01X1580863Y608369D02*
Y590771D01*
G01X1579863Y608369D02*
X1572563D01*
G01X1588163D02*
X1580863D01*
G01X1583067Y670258D02*
X1577067D01*
G01D02*
Y658258D01*
G01D02*
X1583067D01*
G01D02*
Y670258D01*
G01X1589964Y670242D02*
X1583964D01*
G01D02*
Y658242D01*
G01D02*
X1589964D01*
G01X1573394Y661305D02*
Y673305D01*
G01X1579052Y690131D02*
Y683931D01*
G01D02*
X1582252D01*
G01D02*
Y690131D01*
G01D02*
X1579052D01*
G01X1573735Y696454D02*
Y690254D01*
G01D02*
X1576935D01*
G01D02*
Y696454D01*
G01D02*
X1573735D01*
G01X1584320Y697830D02*
X1590320D01*
G01X1584320Y709830D02*
Y697830D01*
G01X1575299Y706124D02*
Y741820D01*
G01X1590320Y709830D02*
X1584320D01*
G01X1577154Y736840D02*
Y724840D01*
G01X1583154D02*
Y736840D01*
G01X1577154Y724840D02*
X1583154D01*
G01Y736840D02*
X1577154D01*
G01X1576255Y790746D02*
X1592455D01*
G01X1576255Y803746D02*
Y790746D01*
G01X1574193Y802463D02*
Y805663D01*
G01X1592048Y808313D02*
Y806091D01*
X1591895Y805626D01*
X1591588Y805316D01*
X1591205Y805213D01*
X1590822Y805316D01*
X1590515Y805626D01*
X1590362Y806091D01*
Y808313D01*
G01X1588948Y805833D02*
X1588718Y805471D01*
X1588412Y805265D01*
X1588067Y805213D01*
X1587760Y805265D01*
X1587453Y805523D01*
X1587262Y805833D01*
X1587223Y806143D01*
X1587300Y806505D01*
X1587568Y806763D01*
X1587837Y806866D01*
X1588182D01*
G01X1587837D02*
X1587607Y807021D01*
X1587415Y807280D01*
X1587338Y807590D01*
X1587415Y807900D01*
X1587607Y808158D01*
X1587952Y808313D01*
X1588297Y808261D01*
X1588642Y808055D01*
G01X1582855Y803746D02*
X1576255D01*
G01X1584355Y801246D02*
X1582855Y803746D01*
G01X1585855D02*
X1584355Y801246D01*
G01X1592455Y803746D02*
X1585855D01*
G01X1580903Y1238266D02*
Y1241466D01*
G01X1574703Y1238266D02*
X1580903D01*
G01X1574703Y1241466D02*
Y1238266D01*
G01X1581703Y1241466D02*
Y1238266D01*
G01D02*
X1587903D01*
G01X1574703Y1236966D02*
Y1233766D01*
G01X1580903Y1236966D02*
X1574703D01*
G01X1580903Y1233766D02*
Y1236966D01*
G01X1574703Y1233766D02*
X1580903D01*
G01Y1241466D02*
X1574703D01*
G01X1587903D02*
X1581703D01*
G01X1588803Y1243607D02*
X1573803D01*
G01Y1251807D02*
X1588803D01*
G01X1573803Y1243607D02*
Y1251807D01*
G01X1580847Y1266088D02*
Y1262888D01*
G01X1587047Y1266088D02*
X1580847D01*
G01X1587047Y1262888D02*
Y1266088D01*
G01X1580847Y1262888D02*
X1587047D01*
G01X1580847Y1262188D02*
Y1258988D01*
G01X1587047Y1262188D02*
X1580847D01*
G01X1587047Y1258988D02*
Y1262188D01*
G01X1580847Y1258988D02*
X1587047D01*
G01Y1255088D02*
Y1258288D01*
G01X1580847Y1255088D02*
X1587047D01*
G01X1580847Y1258288D02*
Y1255088D01*
G01X1587047Y1258288D02*
X1580847D01*
G01X1587047Y1266788D02*
Y1269988D01*
G01X1580847Y1266788D02*
X1587047D01*
G01X1580847Y1269988D02*
Y1266788D01*
G01X1587047Y1269988D02*
X1580847D01*
G01X1590957Y1276768D02*
X1584757D01*
Y1273568D01*
X1590957D01*
Y1276768D01*
G01X1587377Y1293688D02*
X1593577D01*
G01X1587377Y1296888D02*
Y1293688D01*
G01X1593577Y1296888D02*
X1587377D01*
G01Y1289688D02*
X1593577D01*
G01X1587377Y1292888D02*
Y1289688D01*
G01X1593577Y1292888D02*
X1587377D01*
G01X1581102Y1297968D02*
Y1301168D01*
G01X1574902Y1297968D02*
X1581102D01*
G01X1574902Y1301168D02*
Y1297968D01*
G01X1578737Y1284488D02*
Y1287688D01*
G01X1572537Y1284488D02*
X1578737D01*
G01X1572537Y1287688D02*
Y1284488D01*
G01X1578737Y1287688D02*
X1572537D01*
G01X1574102Y1297968D02*
Y1301168D01*
G01X1581102D02*
X1574902D01*
G01X1580805Y1307669D02*
X1577605D01*
G01X1580805Y1301469D02*
Y1307669D01*
G01X1577605Y1301469D02*
X1580805D01*
G01X1577605Y1307669D02*
Y1301469D01*
G01X1582524Y1340098D02*
Y1346298D01*
G01X1579324Y1340098D02*
X1582524D01*
G01X1579324Y1346298D02*
Y1340098D01*
G01X1574524D02*
Y1346298D01*
G01X1584324Y1347533D02*
Y1334533D01*
G01D02*
X1600524D01*
G01X1582524Y1346298D02*
X1579324D01*
G01X1582524Y1354578D02*
Y1360778D01*
G01X1579324Y1354578D02*
X1582524D01*
G01X1579324Y1360778D02*
Y1354578D01*
G01X1574506D02*
Y1360778D01*
G01X1582524Y1353298D02*
X1579324D01*
G01Y1347098D02*
X1582524D01*
G01X1579324Y1353298D02*
Y1347098D01*
G01X1582524D02*
Y1353298D01*
G01X1590924Y1347533D02*
X1584324D01*
G01Y1362013D02*
Y1349013D01*
G01D02*
X1600524D01*
G01X1582524Y1360778D02*
X1579324D01*
G01X1579581Y1371773D02*
X1582781D01*
G01X1579581Y1377973D02*
Y1371773D01*
G01X1582781D02*
Y1377973D01*
G01X1584400Y1371776D02*
X1587600D01*
G01X1584400Y1377976D02*
Y1371776D01*
G01X1590924Y1362013D02*
X1584324D01*
G01X1582781Y1377973D02*
X1579581D01*
G01X1587600Y1377976D02*
X1584400D01*
G01X1576999Y1392332D02*
X1580199D01*
G01X1576999Y1398532D02*
Y1392332D01*
G01X1580199Y1398532D02*
X1576999D01*
G01X1580199Y1392332D02*
Y1398532D01*
G01X1581811Y1392332D02*
X1585011D01*
G01X1581811Y1398532D02*
Y1392332D01*
G01X1585011Y1398532D02*
X1581811D01*
G01X1585011Y1392332D02*
Y1398532D01*
G01X1586499Y1392332D02*
X1589699D01*
G01X1586499Y1398532D02*
Y1392332D01*
G01X1589699Y1398532D02*
X1586499D01*
G01X1573492Y1538571D02*
Y1532571D01*
X1585492D01*
Y1538571D01*
X1573492D01*
G01X1573089Y1560892D02*
Y1566892D01*
G01X1581530Y1570612D02*
X1584730D01*
G01X1581530Y1576812D02*
Y1570612D01*
G01X1584730Y1576812D02*
X1581530D01*
G01X1584730Y1570612D02*
Y1576812D01*
G01X1588288Y1573738D02*
X1585088D01*
G01Y1567538D02*
X1588288D01*
G01X1585088Y1573738D02*
Y1567538D01*
G01X1573115Y1567746D02*
Y1573746D01*
G01X1585600Y1646023D02*
X1579700D01*
G01X1576377Y1667030D02*
Y1648300D01*
G01X1586643Y1669055D02*
X1587005Y1668825D01*
X1587211Y1668519D01*
X1587263Y1668174D01*
X1587211Y1667867D01*
X1586953Y1667560D01*
X1586643Y1667369D01*
X1586333Y1667330D01*
X1585971Y1667407D01*
X1585713Y1667675D01*
X1585610Y1667944D01*
Y1668289D01*
G01Y1667944D02*
X1585455Y1667714D01*
X1585196Y1667522D01*
X1584886Y1667445D01*
X1584576Y1667522D01*
X1584318Y1667714D01*
X1584163Y1668059D01*
X1584215Y1668404D01*
X1584421Y1668749D01*
G01X1576806Y1668940D02*
X1576496Y1668710D01*
X1576341Y1668442D01*
X1576289Y1668135D01*
X1576392Y1667752D01*
X1576651Y1667484D01*
X1576961Y1667407D01*
X1577271Y1667445D01*
X1577529Y1667599D01*
X1578046Y1668365D01*
X1578407Y1668710D01*
X1578924Y1668940D01*
X1579389Y1669017D01*
Y1667407D01*
G01X1576377Y1781456D02*
Y1738110D01*
G01X1588163Y590771D02*
Y608369D01*
G01X1589163Y590771D02*
X1596463D01*
G01D02*
Y608369D01*
G01X1589163D02*
Y590771D01*
G01X1596463Y608369D02*
X1589163D01*
G01X1601501Y632732D02*
X1607501D01*
G01X1601501Y644732D02*
Y632732D01*
G01X1591184Y642838D02*
X1597184D01*
G01D02*
Y654838D01*
G01D02*
X1591184D01*
G01D02*
Y642838D01*
G01X1607501Y644732D02*
X1601501D01*
G01X1589964Y658242D02*
Y670242D01*
G01X1597964D02*
X1591964D01*
G01D02*
Y658242D01*
G01D02*
X1597964D01*
G01D02*
Y670242D01*
G01X1592193Y708198D02*
Y672502D01*
G01D02*
X1609909D01*
G01X1590320Y697830D02*
Y709830D01*
G01X1597603Y717149D02*
X1600703D01*
Y718069D01*
X1600548Y718376D01*
X1600186Y718606D01*
X1599773Y718683D01*
X1599360Y718606D01*
X1599050Y718414D01*
X1598895Y718069D01*
Y717149D01*
G01X1600445Y721859D02*
X1600600Y721629D01*
X1600703Y721361D01*
Y721054D01*
X1600548Y720709D01*
X1600290Y720441D01*
X1599980Y720249D01*
X1599463Y720096D01*
X1598998Y720058D01*
X1598533Y720134D01*
X1598223Y720249D01*
X1597913Y720479D01*
X1597706Y720748D01*
X1597603Y721016D01*
Y721284D01*
X1597706Y721553D01*
X1597861Y721783D01*
X1598068Y721974D01*
G01Y723273D02*
X1597810Y723503D01*
X1597655Y723771D01*
X1597603Y724116D01*
X1597706Y724461D01*
X1597913Y724729D01*
X1598275Y724921D01*
X1598688Y724959D01*
X1599101Y724883D01*
X1599360Y724691D01*
X1599566Y724423D01*
X1599618Y724154D01*
X1599566Y723886D01*
X1599360Y723541D01*
X1600703Y723656D01*
Y724691D01*
G01X1597965Y726564D02*
X1597706Y726833D01*
X1597603Y727139D01*
X1597706Y727446D01*
X1598016Y727714D01*
X1598481Y727906D01*
X1598946Y727983D01*
X1599515D01*
X1599980Y727906D01*
X1600393Y727714D01*
X1600600Y727484D01*
X1600703Y727216D01*
X1600600Y726909D01*
X1600393Y726679D01*
X1600083Y726526D01*
X1599670Y726449D01*
X1599308Y726526D01*
X1598946Y726718D01*
X1598740Y726948D01*
X1598688Y727216D01*
X1598791Y727523D01*
X1599050Y727753D01*
X1599515Y727983D01*
G01X1597603Y730316D02*
X1597655Y730584D01*
X1597810Y730891D01*
X1598068Y731083D01*
X1598430Y731159D01*
X1598791Y731083D01*
X1599101Y730853D01*
X1599256Y730508D01*
Y730124D01*
X1599360Y729894D01*
X1599618Y729703D01*
X1599980Y729626D01*
X1600341Y729741D01*
X1600600Y730009D01*
X1600703Y730316D01*
X1600600Y730623D01*
X1600341Y730891D01*
X1599980Y731006D01*
X1599618Y730929D01*
X1599360Y730738D01*
X1599256Y730508D01*
Y730124D01*
X1599101Y729779D01*
X1598791Y729549D01*
X1598430Y729473D01*
X1598068Y729549D01*
X1597810Y729741D01*
X1597655Y730048D01*
X1597603Y730316D01*
G01X1602374Y714366D02*
X1600134D01*
G01X1601347Y715991D02*
Y712741D01*
G01X1609909Y708198D02*
X1592193D01*
G01X1592455Y790746D02*
Y803746D01*
G01X1593755Y795684D02*
X1596955D01*
G01X1593755Y801884D02*
Y795684D01*
G01X1596955Y801884D02*
X1593755D01*
G01X1596955Y795684D02*
Y801884D01*
G01X1590819Y810552D02*
G03X1600661Y820394I0J9842D01*
G01D02*
Y985748D01*
G01D02*
X1606700Y991592D01*
G01X1600661Y1052678D02*
Y1218032D01*
G01X1606700Y1046834D02*
X1600661Y1052678D01*
G01Y1218032D02*
G03X1590819Y1227874I-9842J0D01*
G01X1587903Y1238266D02*
Y1241466D01*
G01X1588803Y1251807D02*
Y1243607D01*
G01X1589227Y1255754D02*
X1592427D01*
G01X1589227Y1261954D02*
Y1255754D01*
G01X1592427Y1261954D02*
X1589227D01*
G01X1592427Y1255754D02*
Y1261954D01*
G01X1593227Y1255754D02*
X1596427D01*
G01X1593227Y1261954D02*
Y1255754D01*
G01X1596427Y1261954D02*
X1593227D01*
G01X1596427Y1255754D02*
Y1261954D01*
G01X1598077Y1273388D02*
X1604277D01*
G01X1598077Y1276588D02*
Y1273388D01*
G01X1604277Y1276588D02*
X1598077D01*
G01Y1284588D02*
Y1281388D01*
G01D02*
X1604277D01*
G01X1598077Y1277388D02*
X1604277D01*
G01X1598077Y1280588D02*
Y1277388D01*
G01X1604277Y1280588D02*
X1598077D01*
G01X1587907Y1273568D02*
X1594107D01*
Y1276768D01*
X1587907D01*
Y1273568D01*
G01X1593577Y1293688D02*
Y1296888D01*
G01Y1289688D02*
Y1292888D01*
G01X1604277Y1284588D02*
X1598077D01*
G01Y1292588D02*
Y1289388D01*
G01X1604277Y1292588D02*
X1598077D01*
G01Y1289388D02*
X1604277D01*
G01X1598077Y1285388D02*
X1604277D01*
G01X1598077Y1288588D02*
Y1285388D01*
G01X1604277Y1288588D02*
X1598077D01*
G01Y1300588D02*
Y1297388D01*
G01D02*
X1604277D01*
G01X1598077Y1296588D02*
Y1293388D01*
G01X1604277Y1296588D02*
X1598077D01*
G01Y1293388D02*
X1604277D01*
G01Y1300588D02*
X1598077D01*
G01X1594452Y1305658D02*
X1591252D01*
G01X1594452Y1299458D02*
Y1305658D01*
G01X1591252Y1299458D02*
X1594452D01*
G01X1591252Y1305658D02*
Y1299458D01*
G01X1598151Y1301295D02*
X1604351D01*
G01X1598151Y1304495D02*
Y1301295D01*
G01X1604351Y1304495D02*
X1598151D01*
G01X1600524Y1334533D02*
Y1347533D01*
G01D02*
X1593924D01*
G01X1592424Y1345033D02*
X1590924Y1347533D01*
G01X1593924D02*
X1592424Y1345033D01*
G01X1600524Y1349013D02*
Y1362013D01*
G01X1587600Y1371776D02*
Y1377976D01*
G01X1593838Y1371686D02*
X1597038D01*
G01X1593838Y1377886D02*
Y1371686D01*
G01X1597038D02*
Y1377886D01*
G01X1589123Y1371766D02*
X1592323D01*
G01X1589123Y1377966D02*
Y1371766D01*
G01X1592323D02*
Y1377966D01*
G01X1598057Y1371741D02*
X1601257D01*
G01X1598057Y1377941D02*
Y1371741D01*
G01X1601257D02*
Y1377941D01*
G01X1600524Y1362013D02*
X1593924D01*
G01X1592424Y1359513D02*
X1590924Y1362013D01*
G01X1593924D02*
X1592424Y1359513D01*
G01X1597038Y1377886D02*
X1593838D01*
G01X1592323Y1377966D02*
X1589123D01*
G01X1601257Y1377941D02*
X1598057D01*
G01X1589699Y1392332D02*
Y1398532D01*
G01X1591188Y1392332D02*
X1594388D01*
G01X1591188Y1398532D02*
Y1392332D01*
G01X1594388Y1398532D02*
X1591188D01*
G01X1594388Y1392332D02*
Y1398532D01*
G01X1596074Y1392332D02*
X1599274D01*
G01X1596074Y1398532D02*
Y1392332D01*
G01X1599274Y1398532D02*
X1596074D01*
G01X1599274Y1392332D02*
Y1398532D01*
G01X1591066Y1522313D02*
X1593306D01*
G01X1592093Y1520688D02*
Y1523938D01*
G01X1610156Y1522494D02*
X1610386Y1522649D01*
X1610654Y1522752D01*
X1610961D01*
X1611306Y1522597D01*
X1611574Y1522339D01*
X1611766Y1522029D01*
X1611919Y1521512D01*
X1611957Y1521047D01*
X1611881Y1520582D01*
X1611766Y1520272D01*
X1611536Y1519962D01*
X1611267Y1519755D01*
X1610999Y1519652D01*
X1610731D01*
X1610462Y1519755D01*
X1610232Y1519910D01*
X1610041Y1520117D01*
G01X1607976Y1519652D02*
X1607899Y1520324D01*
X1607784Y1520892D01*
X1607631Y1521409D01*
X1607439Y1521977D01*
X1607132Y1522752D01*
X1608666D01*
G01X1604799D02*
X1605106Y1522649D01*
X1605336Y1522390D01*
X1605489Y1522080D01*
X1605604Y1521667D01*
X1605642Y1521202D01*
X1605604Y1520737D01*
X1605489Y1520324D01*
X1605336Y1520014D01*
X1605106Y1519755D01*
X1604799Y1519652D01*
X1604492Y1519755D01*
X1604262Y1520014D01*
X1604109Y1520324D01*
X1603994Y1520737D01*
X1603956Y1521202D01*
X1603994Y1521667D01*
X1604109Y1522080D01*
X1604262Y1522390D01*
X1604492Y1522649D01*
X1604799Y1522752D01*
G01X1601699Y1519652D02*
Y1522752D01*
X1602159Y1522132D01*
G01Y1519652D02*
X1601239D01*
G01X1599442Y1520117D02*
X1599212Y1519859D01*
X1598944Y1519704D01*
X1598599Y1519652D01*
X1598254Y1519755D01*
X1597986Y1519962D01*
X1597794Y1520324D01*
X1597756Y1520737D01*
X1597832Y1521150D01*
X1598024Y1521409D01*
X1598292Y1521615D01*
X1598561Y1521667D01*
X1598829Y1521615D01*
X1599174Y1521409D01*
X1599059Y1522752D01*
X1598024D01*
G01X1588921Y1524980D02*
X1624661D01*
Y1541910D01*
X1588921D01*
Y1524980D01*
G01X1587721Y1524978D02*
X1588921D01*
G01X1587721D02*
X1587727Y1541961D01*
G01X1588321Y1524978D02*
X1588317Y1541953D01*
G01X1588921Y1524978D02*
X1588918Y1541918D01*
G01X1587771Y1541911D02*
X1589280Y1541907D01*
G01X1597738Y1573738D02*
X1594538D01*
G01X1597738Y1567538D02*
Y1573738D01*
G01X1594538Y1567538D02*
X1597738D01*
G01X1594538Y1573738D02*
Y1567538D01*
G01X1588288D02*
Y1573738D01*
G01X1602462D02*
X1599262D01*
G01Y1567538D02*
X1602462D01*
G01X1599262Y1573738D02*
Y1567538D01*
G01X1589813Y1573738D02*
Y1567538D01*
X1593013D01*
Y1573738D01*
X1589813D01*
G01X1597700Y1646023D02*
X1591400D01*
G01X1602546Y1669055D02*
X1602804Y1668825D01*
X1602959Y1668557D01*
X1603011Y1668212D01*
X1602908Y1667867D01*
X1602701Y1667599D01*
X1602339Y1667407D01*
X1601926Y1667369D01*
X1601513Y1667445D01*
X1601254Y1667637D01*
X1601048Y1667905D01*
X1600996Y1668174D01*
X1601048Y1668442D01*
X1601254Y1668787D01*
X1599911Y1668672D01*
Y1667637D01*
G01X1595137Y1667752D02*
X1592037D01*
X1594259Y1669170D01*
Y1667254D01*
G01X1612044Y555130D02*
Y558330D01*
G01X1605844Y555130D02*
X1612044D01*
G01X1605844Y558330D02*
Y555130D01*
G01X1612044Y558330D02*
X1605844D01*
G01X1610741Y593806D02*
Y600006D01*
G01X1607541D02*
Y593806D01*
G01D02*
X1610741D01*
G01Y600006D02*
X1607541D01*
G01X1609692Y645797D02*
Y633797D01*
G01D02*
X1615692D01*
G01D02*
Y645797D01*
G01X1616964Y651242D02*
Y639242D01*
G01D02*
X1622964D01*
G01X1607501Y632732D02*
Y644732D01*
G01X1611822Y656362D02*
Y650162D01*
G01D02*
X1615022D01*
G01D02*
Y656362D01*
G01D02*
X1611822D01*
G01X1606505Y662685D02*
Y656485D01*
G01D02*
X1609705D01*
G01D02*
Y662685D01*
G01X1615692Y645797D02*
X1609692D01*
G01X1622964Y651242D02*
X1616964D01*
G01X1612657Y672776D02*
Y670350D01*
G01X1609705Y662685D02*
X1606505D01*
G01X1609909Y672502D02*
Y708198D01*
G01X1611804Y691738D02*
X1617804D01*
G01X1611804Y703738D02*
Y691738D01*
G01X1617804Y703738D02*
X1611804D01*
G01X1604277Y1273388D02*
Y1276588D01*
G01Y1281388D02*
Y1284588D01*
G01Y1277388D02*
Y1280588D01*
G01Y1289388D02*
Y1292588D01*
G01Y1285388D02*
Y1288588D01*
G01Y1297388D02*
Y1300588D01*
G01Y1293388D02*
Y1296588D01*
G01X1610252Y1293913D02*
X1607052D01*
G01X1610252Y1287713D02*
Y1293913D01*
G01X1607052Y1287713D02*
X1610252D01*
G01X1607052Y1293913D02*
Y1287713D01*
G01X1610252Y1296063D02*
Y1302263D01*
G01X1607052Y1296063D02*
X1610252D01*
G01X1607052Y1302263D02*
Y1296063D01*
G01X1604351Y1301295D02*
Y1304495D01*
G01X1610252Y1302263D02*
X1607052D01*
G01X1604446Y1309153D02*
Y1305953D01*
G01X1610646Y1309153D02*
X1604446D01*
G01X1610646Y1305953D02*
Y1309153D01*
G01X1604446Y1305953D02*
X1610646D01*
G01X1615617Y1346600D02*
Y1344378D01*
X1615464Y1343913D01*
X1615157Y1343603D01*
X1614774Y1343500D01*
X1614391Y1343603D01*
X1614084Y1343913D01*
X1613931Y1344378D01*
Y1346600D01*
G01X1611674Y1343500D02*
X1611406Y1343552D01*
X1611099Y1343707D01*
X1610907Y1343965D01*
X1610831Y1344327D01*
X1610907Y1344688D01*
X1611137Y1344998D01*
X1611482Y1345153D01*
X1611866D01*
X1612096Y1345257D01*
X1612287Y1345515D01*
X1612364Y1345877D01*
X1612249Y1346238D01*
X1611981Y1346497D01*
X1611674Y1346600D01*
X1611367Y1346497D01*
X1611099Y1346238D01*
X1610984Y1345877D01*
X1611061Y1345515D01*
X1611252Y1345257D01*
X1611482Y1345153D01*
X1611866D01*
X1612211Y1344998D01*
X1612441Y1344688D01*
X1612517Y1344327D01*
X1612441Y1343965D01*
X1612249Y1343707D01*
X1611942Y1343552D01*
X1611674Y1343500D01*
G01X1609302Y1346083D02*
X1609072Y1346393D01*
X1608804Y1346548D01*
X1608497Y1346600D01*
X1608114Y1346497D01*
X1607846Y1346238D01*
X1607769Y1345928D01*
X1607807Y1345618D01*
X1607961Y1345360D01*
X1608727Y1344843D01*
X1609072Y1344482D01*
X1609302Y1343965D01*
X1609379Y1343500D01*
X1607769D01*
G01X1615617Y1361080D02*
Y1358858D01*
X1615464Y1358393D01*
X1615157Y1358083D01*
X1614774Y1357980D01*
X1614391Y1358083D01*
X1614084Y1358393D01*
X1613931Y1358858D01*
Y1361080D01*
G01X1611674Y1357980D02*
Y1361080D01*
X1612134Y1360460D01*
G01Y1357980D02*
X1611214D01*
G01X1608574Y1361080D02*
X1608881Y1360977D01*
X1609111Y1360718D01*
X1609264Y1360408D01*
X1609379Y1359995D01*
X1609417Y1359530D01*
X1609379Y1359065D01*
X1609264Y1358652D01*
X1609111Y1358342D01*
X1608881Y1358083D01*
X1608574Y1357980D01*
X1608267Y1358083D01*
X1608037Y1358342D01*
X1607884Y1358652D01*
X1607769Y1359065D01*
X1607731Y1359530D01*
X1607769Y1359995D01*
X1607884Y1360408D01*
X1608037Y1360718D01*
X1608267Y1360977D01*
X1608574Y1361080D01*
G01X1605474Y1357980D02*
Y1361080D01*
X1605934Y1360460D01*
G01Y1357980D02*
X1605014D01*
G01X1611911Y1573738D02*
X1608711D01*
G01X1611911Y1567538D02*
Y1573738D01*
G01X1608711Y1567538D02*
X1611911D01*
G01X1608711Y1573738D02*
Y1567538D01*
G01X1616635Y1573738D02*
X1613435D01*
G01X1616635Y1567538D02*
Y1573738D01*
G01X1613435Y1567538D02*
X1616635D01*
G01X1613435Y1573738D02*
Y1567538D01*
G01X1602462D02*
Y1573738D01*
G01X1603987D02*
Y1567538D01*
X1607187D01*
Y1573738D01*
X1603987D01*
G01X1621900Y1646023D02*
X1616000D01*
G01X1609600D02*
X1604100D01*
G01X1618759Y1668289D02*
X1618087Y1668212D01*
X1617519Y1668097D01*
X1617002Y1667944D01*
X1616434Y1667752D01*
X1615659Y1667445D01*
Y1668979D01*
G01X1609593Y1668940D02*
X1609232Y1668672D01*
X1609025Y1668442D01*
X1608922Y1668135D01*
X1609025Y1667867D01*
X1609232Y1667675D01*
X1609542Y1667522D01*
X1609903Y1667484D01*
X1610213Y1667522D01*
X1610523Y1667675D01*
X1610782Y1667905D01*
X1610885Y1668174D01*
X1610782Y1668480D01*
X1610472Y1668749D01*
X1610007Y1668902D01*
X1609490Y1668940D01*
X1608818Y1668864D01*
X1608457Y1668749D01*
X1608095Y1668557D01*
X1607837Y1668289D01*
X1607785Y1668020D01*
X1607888Y1667752D01*
X1608147Y1667560D01*
G01X1621979Y552035D02*
X1618779D01*
G01X1621979Y545835D02*
Y552035D01*
G01X1618779Y545835D02*
X1621979D01*
G01X1618779Y552035D02*
Y545835D01*
G01X1626059Y589854D02*
Y601854D01*
G01X1620059D02*
Y589854D01*
G01D02*
X1626059D01*
G01X1627259Y601815D02*
Y589815D01*
G01D02*
X1633259D01*
G01X1626059Y601854D02*
X1620059D01*
G01X1633259Y601815D02*
X1627259D01*
G01X1624184Y623878D02*
X1630184D01*
G01D02*
Y635878D01*
G01X1624184D02*
Y623878D01*
G01X1624964Y651242D02*
Y639242D01*
G01D02*
X1630964D01*
G01D02*
Y651242D01*
G01X1630184Y635878D02*
X1624184D01*
G01X1622964Y639242D02*
Y651242D01*
G01X1627243Y689068D02*
Y653372D01*
G01D02*
X1644959D01*
G01X1630964Y651242D02*
X1624964D01*
G01X1619300Y672768D02*
X1625300D01*
G01D02*
Y684768D01*
G01D02*
X1619300D01*
G01D02*
Y672768D01*
G01X1629643Y694929D02*
X1632743D01*
Y695849D01*
X1632588Y696156D01*
X1632226Y696386D01*
X1631813Y696463D01*
X1631400Y696386D01*
X1631090Y696194D01*
X1630935Y695849D01*
Y694929D01*
G01X1632485Y699639D02*
X1632640Y699409D01*
X1632743Y699141D01*
Y698834D01*
X1632588Y698489D01*
X1632330Y698221D01*
X1632020Y698029D01*
X1631503Y697876D01*
X1631038Y697838D01*
X1630573Y697914D01*
X1630263Y698029D01*
X1629953Y698259D01*
X1629746Y698528D01*
X1629643Y698796D01*
Y699064D01*
X1629746Y699333D01*
X1629901Y699563D01*
X1630108Y699754D01*
G01Y701053D02*
X1629850Y701283D01*
X1629695Y701551D01*
X1629643Y701896D01*
X1629746Y702241D01*
X1629953Y702509D01*
X1630315Y702701D01*
X1630728Y702739D01*
X1631141Y702663D01*
X1631400Y702471D01*
X1631606Y702203D01*
X1631658Y701934D01*
X1631606Y701666D01*
X1631400Y701321D01*
X1632743Y701436D01*
Y702471D01*
G01X1630005Y704344D02*
X1629746Y704613D01*
X1629643Y704919D01*
X1629746Y705226D01*
X1630056Y705494D01*
X1630521Y705686D01*
X1630986Y705763D01*
X1631555D01*
X1632020Y705686D01*
X1632433Y705494D01*
X1632640Y705264D01*
X1632743Y704996D01*
X1632640Y704689D01*
X1632433Y704459D01*
X1632123Y704306D01*
X1631710Y704229D01*
X1631348Y704306D01*
X1630986Y704498D01*
X1630780Y704728D01*
X1630728Y704996D01*
X1630831Y705303D01*
X1631090Y705533D01*
X1631555Y705763D01*
G01X1629643Y708019D02*
X1630315Y708096D01*
X1630883Y708211D01*
X1631400Y708364D01*
X1631968Y708556D01*
X1632743Y708863D01*
Y707329D01*
G01X1644959Y689068D02*
X1627243D01*
G01X1617804Y691738D02*
Y703738D01*
G01X1619701Y754365D02*
Y751165D01*
G01X1625901Y754365D02*
X1619701D01*
G01X1625901Y751165D02*
Y754365D01*
G01X1619701Y751165D02*
X1625901D01*
G01X1627201D02*
X1633401D01*
G01X1627201Y754365D02*
Y751165D01*
G01X1633401Y754365D02*
X1627201D01*
G01X1617496Y755504D02*
X1629496D01*
G01X1617496Y761504D02*
Y755504D01*
G01X1629496Y761504D02*
X1617496D01*
G01X1629496Y755504D02*
Y761504D01*
G01X1629571Y762165D02*
Y765365D01*
G01X1623371Y762165D02*
X1629571D01*
G01X1623371Y765365D02*
Y762165D01*
G01X1629571Y765365D02*
X1623371D01*
G01Y768865D02*
Y765665D01*
G01X1629571Y768865D02*
X1623371D01*
G01X1629571Y765665D02*
Y768865D01*
G01X1623371Y765665D02*
X1629571D01*
G01X1628226Y1419841D02*
X1631426D01*
G01X1628226Y1426041D02*
Y1419841D01*
G01X1631426Y1426041D02*
X1628226D01*
G01X1631426Y1419841D02*
Y1426041D01*
G01X1630899Y1523752D02*
X1628473D01*
G01X1619329Y1522988D02*
X1621755D01*
G01X1661947Y1541910D02*
X1626207D01*
Y1524980D01*
X1661947D01*
Y1541910D01*
G01X1626084Y1573738D02*
X1622884D01*
G01X1626084Y1567538D02*
Y1573738D01*
G01X1622884Y1567538D02*
X1626084D01*
G01X1622884Y1573738D02*
Y1567538D01*
G01X1621360Y1573738D02*
X1618160D01*
G01X1621360Y1567538D02*
Y1573738D01*
G01X1618160Y1567538D02*
X1621360D01*
G01X1618160Y1573738D02*
Y1567538D01*
G01X1627609Y1573738D02*
Y1567538D01*
X1630809D01*
Y1573738D01*
X1627609D01*
G01X1633900Y1646023D02*
X1628100D01*
G01X1626633Y1668212D02*
X1626581Y1667944D01*
X1626426Y1667637D01*
X1626168Y1667445D01*
X1625806Y1667369D01*
X1625445Y1667445D01*
X1625135Y1667675D01*
X1624980Y1668020D01*
Y1668404D01*
X1624876Y1668634D01*
X1624618Y1668825D01*
X1624256Y1668902D01*
X1623895Y1668787D01*
X1623636Y1668519D01*
X1623533Y1668212D01*
X1623636Y1667905D01*
X1623895Y1667637D01*
X1624256Y1667522D01*
X1624618Y1667599D01*
X1624876Y1667790D01*
X1624980Y1668020D01*
Y1668404D01*
X1625135Y1668749D01*
X1625445Y1668979D01*
X1625806Y1669055D01*
X1626168Y1668979D01*
X1626426Y1668787D01*
X1626581Y1668480D01*
X1626633Y1668212D01*
G01X1633259Y589815D02*
Y601815D01*
G01X1644822Y637362D02*
Y631162D01*
G01D02*
X1648022D01*
G01Y637362D02*
X1644822D01*
G01X1639505Y643685D02*
Y637485D01*
G01D02*
X1642705D01*
G01D02*
Y643685D01*
G01X1642646Y651591D02*
Y649165D01*
G01X1644959Y653372D02*
Y689068D01*
G01X1642705Y643685D02*
X1639505D01*
G01X1646854Y672768D02*
X1652854D01*
G01Y684768D02*
X1646854D01*
G01D02*
Y672768D01*
G01X1637424Y695236D02*
X1635184D01*
G01X1636397Y696861D02*
Y693611D01*
G01X1657437Y701220D02*
Y698120D01*
G01X1658319Y701220D02*
X1656555D01*
G01X1655104Y698120D02*
Y701220D01*
X1654184D01*
X1653877Y701065D01*
X1653647Y700703D01*
X1653570Y700290D01*
X1653647Y699877D01*
X1653839Y699567D01*
X1654184Y699412D01*
X1655104D01*
G01X1651237Y698120D02*
Y701220D01*
X1651697Y700600D01*
G01Y698120D02*
X1650777D01*
G01X1648137Y701220D02*
X1648444Y701117D01*
X1648674Y700858D01*
X1648827Y700548D01*
X1648942Y700135D01*
X1648980Y699670D01*
X1648942Y699205D01*
X1648827Y698792D01*
X1648674Y698482D01*
X1648444Y698223D01*
X1648137Y698120D01*
X1647830Y698223D01*
X1647600Y698482D01*
X1647447Y698792D01*
X1647332Y699205D01*
X1647294Y699670D01*
X1647332Y700135D01*
X1647447Y700548D01*
X1647600Y700858D01*
X1647830Y701117D01*
X1648137Y701220D01*
G01X1633401Y751165D02*
Y754365D01*
G01X1645638Y761504D02*
X1633638D01*
G01X1645638Y755504D02*
Y761504D01*
G01X1633638Y755504D02*
X1645638D01*
G01X1633638Y761504D02*
Y755504D01*
G01X1639763Y762165D02*
Y765365D01*
G01X1633563Y762165D02*
X1639763D01*
G01X1633563Y765365D02*
Y762165D01*
G01X1639763Y765365D02*
X1633563D01*
G01Y768865D02*
Y765665D01*
G01X1639763Y768865D02*
X1633563D01*
G01X1639763Y765665D02*
Y768865D01*
G01X1633563Y765665D02*
X1639763D01*
G01X1633563Y769465D02*
X1639763D01*
Y772665D01*
X1633563D01*
Y769465D01*
G01X1638813Y959365D02*
Y962565D01*
G01X1632613Y959365D02*
X1638813D01*
G01X1632613Y962565D02*
Y959365D01*
G01X1638813Y962565D02*
X1632613D01*
G01X1643177Y1340488D02*
X1649177D01*
G01X1643177Y1352488D02*
Y1340488D01*
G01X1649177Y1352488D02*
X1643177D01*
G01X1650994Y1523124D02*
X1651224Y1523279D01*
X1651492Y1523382D01*
X1651799D01*
X1652144Y1523227D01*
X1652412Y1522969D01*
X1652604Y1522659D01*
X1652757Y1522142D01*
X1652795Y1521677D01*
X1652719Y1521212D01*
X1652604Y1520902D01*
X1652374Y1520592D01*
X1652105Y1520385D01*
X1651837Y1520282D01*
X1651569D01*
X1651300Y1520385D01*
X1651070Y1520540D01*
X1650879Y1520747D01*
G01X1648814Y1520282D02*
X1648737Y1520954D01*
X1648622Y1521522D01*
X1648469Y1522039D01*
X1648277Y1522607D01*
X1647970Y1523382D01*
X1649504D01*
G01X1645637D02*
X1645944Y1523279D01*
X1646174Y1523020D01*
X1646327Y1522710D01*
X1646442Y1522297D01*
X1646480Y1521832D01*
X1646442Y1521367D01*
X1646327Y1520954D01*
X1646174Y1520644D01*
X1645944Y1520385D01*
X1645637Y1520282D01*
X1645330Y1520385D01*
X1645100Y1520644D01*
X1644947Y1520954D01*
X1644832Y1521367D01*
X1644794Y1521832D01*
X1644832Y1522297D01*
X1644947Y1522710D01*
X1645100Y1523020D01*
X1645330Y1523279D01*
X1645637Y1523382D01*
G01X1642537Y1520282D02*
Y1523382D01*
X1642997Y1522762D01*
G01Y1520282D02*
X1642077D01*
G01X1638977D02*
Y1523382D01*
X1640395Y1521160D01*
X1638479D01*
G01X1641782Y1573738D02*
Y1567538D01*
X1644982D01*
Y1573738D01*
X1641782D01*
G01X1637057D02*
Y1567538D01*
X1640257D01*
Y1573738D01*
X1637057D01*
G01X1646506D02*
Y1567538D01*
X1649706D01*
Y1573738D01*
X1646506D01*
G01X1643307Y1646023D02*
X1639700D01*
G01X1643307Y1781456D02*
Y1646023D01*
G01X1641122Y1733579D02*
X1633622D01*
Y1731339D01*
X1633997Y1730592D01*
X1634872Y1730032D01*
X1635872Y1729845D01*
X1636872Y1730032D01*
X1637622Y1730499D01*
X1637997Y1731339D01*
Y1733579D01*
G01X1641122Y1726079D02*
X1633622D01*
Y1723745D01*
X1633997Y1722999D01*
X1634497Y1722532D01*
X1635497Y1722345D01*
X1636497Y1722532D01*
X1637122Y1723092D01*
X1637497Y1723745D01*
Y1726079D01*
G01Y1723745D02*
X1641122Y1722345D01*
G01Y1714845D02*
Y1718579D01*
X1633622D01*
Y1714845D01*
G01X1637247Y1716339D02*
Y1718579D01*
G01X1640122Y1711172D02*
X1640747Y1710425D01*
X1641122Y1709585D01*
Y1708839D01*
X1640747Y1708092D01*
X1640122Y1707532D01*
X1639247Y1707252D01*
X1638372Y1707439D01*
X1637622Y1707905D01*
X1637122Y1708745D01*
X1636872Y1709865D01*
X1636372Y1710519D01*
X1635497Y1710799D01*
X1634622Y1710612D01*
X1633997Y1710145D01*
X1633622Y1709492D01*
Y1708839D01*
X1633872Y1708185D01*
X1634497Y1707625D01*
G01X1640122Y1703672D02*
X1640747Y1702925D01*
X1641122Y1702085D01*
Y1701339D01*
X1640747Y1700592D01*
X1640122Y1700032D01*
X1639247Y1699752D01*
X1638372Y1699939D01*
X1637622Y1700405D01*
X1637122Y1701245D01*
X1636872Y1702365D01*
X1636372Y1703019D01*
X1635497Y1703299D01*
X1634622Y1703112D01*
X1633997Y1702645D01*
X1633622Y1701992D01*
Y1701339D01*
X1633872Y1700685D01*
X1634497Y1700125D01*
G01X1638622Y1695425D02*
Y1692999D01*
G01X1641122Y1688485D02*
X1633622D01*
Y1684939D01*
G01X1637247Y1686245D02*
Y1688485D01*
G01X1633622Y1680332D02*
Y1678092D01*
G01Y1679212D02*
X1641122D01*
G01Y1680332D02*
Y1678092D01*
G01X1633622Y1671712D02*
X1641122D01*
G01X1633622Y1673859D02*
Y1669565D01*
G01X1648022Y631162D02*
Y637362D01*
G01X1653547Y681408D02*
Y675208D01*
G01D02*
X1656747D01*
G01D02*
Y681408D01*
G01D02*
X1653547D01*
G01X1652854Y672768D02*
Y684768D01*
G01X1657327Y695620D02*
Y692520D01*
G01X1658209Y695620D02*
X1656445D01*
G01X1654994Y692520D02*
Y695620D01*
X1654074D01*
X1653767Y695465D01*
X1653537Y695103D01*
X1653460Y694690D01*
X1653537Y694277D01*
X1653729Y693967D01*
X1654074Y693812D01*
X1654994D01*
G01X1651127Y692520D02*
Y695620D01*
X1651587Y695000D01*
G01Y692520D02*
X1650667D01*
G01X1649201Y754865D02*
Y751665D01*
G01X1655401Y754865D02*
X1649201D01*
G01X1655401Y751665D02*
Y754865D01*
G01X1649201Y751665D02*
X1655401D01*
G01X1647197Y755504D02*
X1659197D01*
G01X1647197Y761504D02*
Y755504D01*
G01X1659197Y761504D02*
X1647197D01*
G01X1659197Y755504D02*
Y761504D01*
G01X1659272Y762165D02*
Y765365D01*
G01X1653072Y762165D02*
X1659272D01*
G01X1653072Y765365D02*
Y762165D01*
G01X1659272Y765365D02*
X1653072D01*
G01Y768865D02*
Y765665D01*
G01X1659272Y768865D02*
X1653072D01*
G01X1659272Y765665D02*
Y768865D01*
G01X1653072Y765665D02*
X1659272D01*
G01X1659129Y1336330D02*
X1676845D01*
G01X1659129Y1372026D02*
Y1336330D01*
G01X1649177Y1340488D02*
Y1352488D01*
G01X1657177Y1340488D02*
Y1352488D01*
G01X1651177Y1340488D02*
X1657177D01*
G01X1651177Y1352488D02*
Y1340488D01*
G01X1657177Y1352488D02*
X1651177D01*
G01X1676845Y1372026D02*
X1659129D01*
G01X1657192Y1383412D02*
X1660392D01*
G01X1657192Y1389612D02*
Y1383412D01*
G01X1660392D02*
Y1389612D01*
G01D02*
X1657192D01*
G01X1651875Y1389735D02*
X1655075D01*
G01X1651875Y1395935D02*
Y1389735D01*
G01X1655075Y1395935D02*
X1651875D01*
G01X1655075Y1389735D02*
Y1395935D01*
G01X1658670Y1414684D02*
Y1417884D01*
G01X1652470Y1414684D02*
X1658670D01*
G01X1652470Y1417884D02*
Y1414684D01*
G01X1656294Y1425345D02*
X1662494D01*
G01X1656294Y1428545D02*
Y1425345D01*
G01X1662494Y1428545D02*
X1656294D01*
G01X1658670Y1417884D02*
X1652470D01*
G01X1663097Y1524979D02*
X1661588Y1524983D01*
G01X1661947Y1541912D02*
X1661950Y1524972D01*
G01X1663147Y1541912D02*
X1661947D01*
G01X1659155Y1573738D02*
X1655955D01*
G01X1659155Y1567538D02*
Y1573738D01*
G01X1655955Y1567538D02*
X1659155D01*
G01X1655955Y1573738D02*
Y1567538D01*
G01X1651231Y1573738D02*
Y1567538D01*
X1654431D01*
Y1573738D01*
X1651231D01*
G01X1661286D02*
Y1567538D01*
X1664486D01*
Y1573738D01*
X1661286D01*
G01X1656965Y1675124D02*
X1665105D01*
G01X1656965Y1685238D02*
Y1675124D01*
G01X1665105Y1685238D02*
X1656965D01*
G01X1658959Y1693449D02*
Y1691227D01*
X1658806Y1690762D01*
X1658499Y1690452D01*
X1658116Y1690349D01*
X1657733Y1690452D01*
X1657426Y1690762D01*
X1657273Y1691227D01*
Y1693449D01*
G01X1654556Y1690349D02*
Y1693449D01*
X1655974Y1691227D01*
X1654058D01*
G01X1651993Y1690349D02*
X1651916Y1691021D01*
X1651801Y1691589D01*
X1651648Y1692106D01*
X1651456Y1692674D01*
X1651149Y1693449D01*
X1652683D01*
G01X1676175Y123362D02*
Y120162D01*
G01D02*
X1682375D01*
G01X1676175Y135162D02*
X1682375D01*
G01X1676175Y138362D02*
Y135162D01*
G01Y130162D02*
X1682375D01*
G01Y133362D02*
X1676175D01*
G01D02*
Y130162D01*
G01X1682375Y123362D02*
X1676175D01*
G01X1682375Y138362D02*
X1676175D01*
G01X1675339Y761504D02*
X1663339D01*
G01X1675339Y755504D02*
Y761504D01*
G01X1663339Y755504D02*
X1675339D01*
G01X1663339Y761504D02*
Y755504D01*
G01X1669464Y762165D02*
Y765365D01*
G01X1663264Y762165D02*
X1669464D01*
G01X1663264Y765365D02*
Y762165D01*
G01X1669464Y765365D02*
X1663264D01*
G01Y768865D02*
Y765665D01*
G01X1669464Y768865D02*
X1663264D01*
G01X1669464Y765665D02*
Y768865D01*
G01X1663264Y765665D02*
X1669464D01*
G01X1663264Y769465D02*
X1669464D01*
Y772665D01*
X1663264D01*
Y769465D01*
G01X1668514Y959365D02*
Y962565D01*
G01X1662314Y959365D02*
X1668514D01*
G01X1662314Y962565D02*
Y959365D01*
G01X1668514Y962565D02*
X1662314D01*
G01X1666664Y1330162D02*
X1668904D01*
G01X1667691Y1328537D02*
Y1331787D01*
G01X1676845Y1336330D02*
Y1372026D01*
G01X1667687Y1374865D02*
Y1377291D01*
G01X1668931Y1388019D02*
Y1376019D01*
G01X1674931D02*
Y1388019D01*
G01X1668931Y1376019D02*
X1674931D01*
G01Y1388019D02*
X1668931D01*
G01X1675633Y1391135D02*
Y1403135D01*
G01X1669633Y1391135D02*
X1675633D01*
G01X1669633Y1403135D02*
Y1391135D01*
G01X1670935Y1415110D02*
Y1418310D01*
G01X1664735Y1415110D02*
X1670935D01*
G01X1664735Y1418310D02*
Y1415110D01*
G01X1675633Y1403135D02*
X1669633D01*
G01X1682758Y1414694D02*
X1670758D01*
G01Y1408694D02*
X1682758D01*
G01X1670758Y1414694D02*
Y1408694D01*
G01X1670935Y1418310D02*
X1664735D01*
G01X1674937Y1425086D02*
Y1428286D01*
G01X1668737Y1425086D02*
X1674937D01*
G01X1668737Y1428286D02*
Y1425086D01*
G01X1674937Y1428286D02*
X1668737D01*
G01X1662494Y1425345D02*
Y1428545D01*
G01X1666772Y1533897D02*
X1664532D01*
G01X1665745Y1535522D02*
Y1532272D01*
G01X1663147Y1541912D02*
X1663141Y1524929D01*
G01X1662547Y1541912D02*
X1662551Y1524937D01*
G01X1665105Y1675124D02*
Y1685238D01*
G01X1682375Y120162D02*
Y123362D01*
G01X1685825Y117162D02*
X1692025D01*
G01Y120362D02*
X1685825D01*
G01D02*
Y117162D01*
G01X1682375Y135162D02*
Y138362D01*
G01Y130162D02*
Y133362D01*
G01X1685825Y130162D02*
X1692025D01*
G01Y133362D02*
X1685825D01*
G01D02*
Y130162D01*
G01Y125162D02*
X1692025D01*
G01Y128362D02*
X1685825D01*
G01D02*
Y125162D01*
G01Y135162D02*
X1692025D01*
G01X1685825Y138362D02*
Y135162D01*
G01Y121162D02*
X1692025D01*
G01Y124362D02*
X1685825D01*
G01D02*
Y121162D01*
G01Y140162D02*
X1692025D01*
G01Y143362D02*
X1685825D01*
G01D02*
Y140162D01*
G01X1692025Y138362D02*
X1685825D01*
G01Y148162D02*
X1692025D01*
G01X1685825Y151362D02*
Y148162D01*
G01Y144162D02*
X1692025D01*
G01Y147362D02*
X1685825D01*
G01D02*
Y144162D01*
G01Y165162D02*
X1692025D01*
G01X1685825Y168362D02*
Y165162D01*
G01Y156162D02*
X1692025D01*
G01Y159362D02*
X1685825D01*
G01D02*
Y156162D01*
G01X1692025Y155362D02*
X1685825D01*
G01D02*
Y152162D01*
G01D02*
X1692025D01*
G01Y151362D02*
X1685825D01*
G01X1692025Y163362D02*
X1685825D01*
G01D02*
Y160162D01*
G01D02*
X1692025D01*
G01Y168362D02*
X1685825D01*
G01X1688960Y431712D02*
Y425512D01*
G01D02*
X1692160D01*
G01Y431712D02*
X1688960D01*
G01X1680201Y754865D02*
Y751665D01*
G01X1686401Y754865D02*
X1680201D01*
G01X1686401Y751665D02*
Y754865D01*
G01X1680201Y751665D02*
X1686401D01*
G01X1676898Y755504D02*
X1688898D01*
G01X1676898Y761504D02*
Y755504D01*
G01X1688898Y761504D02*
X1676898D01*
G01X1688898Y755504D02*
Y761504D01*
G01X1688973Y762165D02*
Y765365D01*
G01X1682773Y762165D02*
X1688973D01*
G01X1682773Y765365D02*
Y762165D01*
G01X1688973Y765365D02*
X1682773D01*
G01Y768865D02*
Y765665D01*
G01X1688973Y768865D02*
X1682773D01*
G01X1688973Y765665D02*
Y768865D01*
G01X1682773Y765665D02*
X1688973D01*
G01X1681747Y1312658D02*
X1678547D01*
G01X1681747Y1306458D02*
Y1312658D01*
G01X1678547Y1306458D02*
X1681747D01*
G01X1678547Y1312658D02*
Y1306458D01*
G01X1680101Y1324427D02*
X1683201D01*
Y1325347D01*
X1683046Y1325654D01*
X1682684Y1325884D01*
X1682271Y1325961D01*
X1681858Y1325884D01*
X1681548Y1325692D01*
X1681393Y1325347D01*
Y1324427D01*
G01X1682943Y1329137D02*
X1683098Y1328907D01*
X1683201Y1328639D01*
Y1328332D01*
X1683046Y1327987D01*
X1682788Y1327719D01*
X1682478Y1327527D01*
X1681961Y1327374D01*
X1681496Y1327336D01*
X1681031Y1327412D01*
X1680721Y1327527D01*
X1680411Y1327757D01*
X1680204Y1328026D01*
X1680101Y1328294D01*
Y1328562D01*
X1680204Y1328831D01*
X1680359Y1329061D01*
X1680566Y1329252D01*
G01X1682684Y1330666D02*
X1682994Y1330896D01*
X1683149Y1331164D01*
X1683201Y1331471D01*
X1683098Y1331854D01*
X1682839Y1332122D01*
X1682529Y1332199D01*
X1682219Y1332161D01*
X1681961Y1332007D01*
X1681444Y1331241D01*
X1681083Y1330896D01*
X1680566Y1330666D01*
X1680101Y1330589D01*
Y1332199D01*
G01X1682684Y1333766D02*
X1682994Y1333996D01*
X1683149Y1334264D01*
X1683201Y1334571D01*
X1683098Y1334954D01*
X1682839Y1335222D01*
X1682529Y1335299D01*
X1682219Y1335261D01*
X1681961Y1335107D01*
X1681444Y1334341D01*
X1681083Y1333996D01*
X1680566Y1333766D01*
X1680101Y1333689D01*
Y1335299D01*
G01X1680721Y1336751D02*
X1680359Y1336981D01*
X1680153Y1337287D01*
X1680101Y1337632D01*
X1680153Y1337939D01*
X1680411Y1338246D01*
X1680721Y1338437D01*
X1681031Y1338476D01*
X1681393Y1338399D01*
X1681651Y1338131D01*
X1681754Y1337862D01*
Y1337517D01*
G01Y1337862D02*
X1681909Y1338092D01*
X1682168Y1338284D01*
X1682478Y1338361D01*
X1682788Y1338284D01*
X1683046Y1338092D01*
X1683201Y1337747D01*
X1683149Y1337402D01*
X1682943Y1337057D01*
G01X1691609Y1336510D02*
X1709325D01*
G01X1691609Y1372206D02*
Y1336510D01*
G01X1686177Y1340488D02*
Y1352488D01*
G01X1680177Y1340488D02*
X1686177D01*
G01X1680177Y1352488D02*
Y1340488D01*
G01X1686177Y1352488D02*
X1680177D01*
G01X1689880Y1373334D02*
Y1375760D01*
G01X1709325Y1372206D02*
X1691609D01*
G01X1689974Y1383512D02*
X1693174D01*
G01X1689974Y1389712D02*
Y1383512D01*
G01X1676931Y1388019D02*
Y1376019D01*
G01D02*
X1682931D01*
G01D02*
Y1388019D01*
G01X1693174Y1389712D02*
X1689974D01*
G01X1684657Y1389835D02*
X1687857D01*
G01X1684657Y1396035D02*
Y1389835D01*
G01X1687857Y1396035D02*
X1684657D01*
G01X1687857Y1389835D02*
Y1396035D01*
G01X1682931Y1388019D02*
X1676931D01*
G01X1682758Y1408694D02*
Y1414694D01*
G01X1687783Y1721268D02*
Y1715068D01*
G01X1690983D02*
Y1721268D01*
G01X1687783Y1715068D02*
X1690983D01*
G01X1686983D02*
Y1721268D01*
G01X1683783D02*
Y1715068D01*
G01D02*
X1686983D01*
G01X1690983Y1722068D02*
Y1728268D01*
G01D02*
X1687783D01*
G01D02*
Y1722068D01*
G01D02*
X1690983D01*
G01Y1721268D02*
X1687783D01*
G01X1686983D02*
X1683783D01*
G01X1686983Y1728268D02*
X1683783D01*
G01X1686983Y1722068D02*
Y1728268D01*
G01X1683783Y1722068D02*
X1686983D01*
G01X1683783Y1728268D02*
Y1722068D01*
G01X1692025Y117162D02*
Y120362D01*
G01Y130162D02*
Y133362D01*
G01Y125162D02*
Y128362D01*
G01Y135162D02*
Y138362D01*
G01Y121162D02*
Y124362D01*
G01Y140162D02*
Y143362D01*
G01Y148162D02*
Y151362D01*
G01Y144162D02*
Y147362D01*
G01Y165162D02*
Y168362D01*
G01Y156162D02*
Y159362D01*
G01Y152162D02*
Y155362D01*
G01Y160162D02*
Y163362D01*
G01X1692160Y425512D02*
Y431712D01*
G01X1706599Y755504D02*
X1718599D01*
G01X1706599Y761504D02*
Y755504D01*
G01X1718599Y761504D02*
X1706599D01*
G01X1705040D02*
X1693040D01*
G01X1705040Y755504D02*
Y761504D01*
G01X1693040Y755504D02*
X1705040D01*
G01X1693040Y761504D02*
Y755504D01*
G01X1699165Y762165D02*
Y765365D01*
G01X1692965Y762165D02*
X1699165D01*
G01X1692965Y765365D02*
Y762165D01*
G01X1699165Y765365D02*
X1692965D01*
G01Y768865D02*
Y765665D01*
G01X1699165Y768865D02*
X1692965D01*
G01X1699165Y765665D02*
Y768865D01*
G01X1692965Y765665D02*
X1699165D01*
G01X1692965Y769465D02*
X1699165D01*
Y772665D01*
X1692965D01*
Y769465D01*
G01X1698215Y959365D02*
Y962565D01*
G01X1692015Y959365D02*
X1698215D01*
G01X1692015Y962565D02*
Y959365D01*
G01X1698215Y962565D02*
X1692015D01*
G01X1699815Y1327932D02*
X1702055D01*
G01X1700842Y1326307D02*
Y1329557D01*
G01X1693174Y1383512D02*
Y1389712D01*
G01X1701713Y1388119D02*
Y1376119D01*
G01D02*
X1707713D01*
G01Y1388119D02*
X1701713D01*
G01X1702652Y1391235D02*
X1708652D01*
G01X1702652Y1403235D02*
Y1391235D01*
G01X1708652Y1403235D02*
X1702652D01*
G01X1706782Y1707030D02*
X1707089Y1707082D01*
X1707357Y1707288D01*
X1707587Y1707598D01*
X1707740Y1707960D01*
X1707817Y1708373D01*
Y1708787D01*
X1707740Y1709200D01*
X1707587Y1709562D01*
X1707357Y1709872D01*
X1707089Y1710078D01*
X1706782Y1710130D01*
X1706475Y1710078D01*
X1706207Y1709872D01*
X1705977Y1709562D01*
X1705824Y1709200D01*
X1705747Y1708787D01*
Y1708373D01*
X1705824Y1707960D01*
X1705977Y1707598D01*
X1706207Y1707288D01*
X1706475Y1707082D01*
X1706782Y1707030D01*
G01X1706475Y1707857D02*
X1706015Y1707030D01*
G01X1703682D02*
Y1710130D01*
X1704142Y1709510D01*
G01Y1707030D02*
X1703222D01*
G01X1701425Y1707650D02*
X1701195Y1707288D01*
X1700889Y1707082D01*
X1700544Y1707030D01*
X1700237Y1707082D01*
X1699930Y1707340D01*
X1699739Y1707650D01*
X1699700Y1707960D01*
X1699777Y1708322D01*
X1700045Y1708580D01*
X1700314Y1708683D01*
X1700659D01*
G01X1700314D02*
X1700084Y1708838D01*
X1699892Y1709097D01*
X1699815Y1709407D01*
X1699892Y1709717D01*
X1700084Y1709975D01*
X1700429Y1710130D01*
X1700774Y1710078D01*
X1701119Y1709872D01*
G01X1697559Y1707030D02*
X1697482Y1707702D01*
X1697367Y1708270D01*
X1697214Y1708787D01*
X1697022Y1709355D01*
X1696715Y1710130D01*
X1698249D01*
G01X1691783Y1718918D02*
X1694983D01*
G01X1691783Y1725118D02*
Y1718918D01*
G01X1694983Y1725118D02*
X1691783D01*
G01X1694983Y1718918D02*
Y1725118D01*
G01X1696383Y1725365D02*
Y1716703D01*
G01X1706877Y1725365D02*
X1696383D01*
G01X1701630Y1718903D02*
X1703530Y1716703D01*
G01X1699730D02*
X1701630Y1718903D01*
G01X1703530Y1716703D02*
X1706877D01*
G01X1696383D02*
X1699730D01*
G01X1714773Y29644D02*
Y35844D01*
G01X1711573D02*
Y29644D01*
G01D02*
X1714773D01*
G01X1711663Y46054D02*
X1717863D01*
G01D02*
Y49254D01*
G01X1711663D02*
Y46054D01*
G01Y42054D02*
X1717863D01*
G01D02*
Y45254D01*
G01D02*
X1711663D01*
G01D02*
Y42054D01*
G01Y38054D02*
X1717863D01*
G01D02*
Y41254D01*
G01D02*
X1711663D01*
G01D02*
Y38054D01*
G01X1714773Y35844D02*
X1711573D01*
G01X1711663Y50054D02*
X1717863D01*
G01D02*
Y53254D01*
G01D02*
X1711663D01*
G01D02*
Y50054D01*
G01X1717863Y49254D02*
X1711663D01*
G01X1718862Y72005D02*
X1722062D01*
G01X1718862Y78205D02*
Y72005D01*
G01X1722062Y78205D02*
X1718862D01*
G01X1711199Y108952D02*
Y102752D01*
G01D02*
X1714399D01*
G01D02*
Y108952D01*
G01D02*
X1711199D01*
G01X1762645Y605411D02*
G02I-22900J0D01*
G01X1708701Y754365D02*
Y751165D01*
G01X1714901Y754365D02*
X1708701D01*
G01X1714901Y751165D02*
Y754365D01*
G01X1708701Y751165D02*
X1714901D01*
G01X1718599Y755504D02*
Y761504D01*
G01X1718674Y762165D02*
Y765365D01*
G01X1712474Y762165D02*
X1718674D01*
G01X1712474Y765365D02*
Y762165D01*
G01X1718674Y765365D02*
X1712474D01*
G01Y768865D02*
Y765665D01*
G01X1718674Y768865D02*
X1712474D01*
G01X1718674Y765665D02*
Y768865D01*
G01X1712474Y765665D02*
X1718674D01*
G01X1712581Y1324607D02*
X1715681D01*
Y1325527D01*
X1715526Y1325834D01*
X1715164Y1326064D01*
X1714751Y1326141D01*
X1714338Y1326064D01*
X1714028Y1325872D01*
X1713873Y1325527D01*
Y1324607D01*
G01X1715423Y1329317D02*
X1715578Y1329087D01*
X1715681Y1328819D01*
Y1328512D01*
X1715526Y1328167D01*
X1715268Y1327899D01*
X1714958Y1327707D01*
X1714441Y1327554D01*
X1713976Y1327516D01*
X1713511Y1327592D01*
X1713201Y1327707D01*
X1712891Y1327937D01*
X1712684Y1328206D01*
X1712581Y1328474D01*
Y1328742D01*
X1712684Y1329011D01*
X1712839Y1329241D01*
X1713046Y1329432D01*
G01X1715164Y1330846D02*
X1715474Y1331076D01*
X1715629Y1331344D01*
X1715681Y1331651D01*
X1715578Y1332034D01*
X1715319Y1332302D01*
X1715009Y1332379D01*
X1714699Y1332341D01*
X1714441Y1332187D01*
X1713924Y1331421D01*
X1713563Y1331076D01*
X1713046Y1330846D01*
X1712581Y1330769D01*
Y1332379D01*
G01X1715164Y1333946D02*
X1715474Y1334176D01*
X1715629Y1334444D01*
X1715681Y1334751D01*
X1715578Y1335134D01*
X1715319Y1335402D01*
X1715009Y1335479D01*
X1714699Y1335441D01*
X1714441Y1335287D01*
X1713924Y1334521D01*
X1713563Y1334176D01*
X1713046Y1333946D01*
X1712581Y1333869D01*
Y1335479D01*
G01X1713873Y1337046D02*
X1714234Y1337314D01*
X1714441Y1337544D01*
X1714544Y1337851D01*
X1714441Y1338119D01*
X1714234Y1338311D01*
X1713924Y1338464D01*
X1713563Y1338502D01*
X1713253Y1338464D01*
X1712943Y1338311D01*
X1712684Y1338081D01*
X1712581Y1337812D01*
X1712684Y1337506D01*
X1712994Y1337237D01*
X1713459Y1337084D01*
X1713976Y1337046D01*
X1714648Y1337122D01*
X1715009Y1337237D01*
X1715371Y1337429D01*
X1715629Y1337697D01*
X1715681Y1337966D01*
X1715578Y1338234D01*
X1715319Y1338426D01*
G01X1719109Y1335130D02*
X1736825D01*
G01X1719109Y1370826D02*
Y1335130D01*
G01X1709325Y1336510D02*
Y1372206D01*
G01X1717198Y1340149D02*
Y1352149D01*
G01X1711198Y1340149D02*
X1717198D01*
G01X1711198Y1352149D02*
Y1340149D01*
G01X1717198Y1352149D02*
X1711198D01*
G01X1736825Y1370826D02*
X1719109D01*
G01X1707713Y1376119D02*
Y1388119D01*
G01X1709713D02*
Y1376119D01*
G01X1715713D02*
Y1388119D01*
G01X1709713Y1376119D02*
X1715713D01*
G01X1716841Y1388267D02*
Y1376267D01*
G01D02*
X1722841D01*
G01X1708652Y1391235D02*
Y1403235D01*
G01X1715713Y1388119D02*
X1709713D01*
G01X1722841Y1388267D02*
X1716841D01*
G01X1726110Y1434230D02*
X1720110D01*
Y1422230D01*
X1726110D01*
Y1434230D01*
G01X1711830Y1727950D02*
X1708630D01*
G01Y1721750D02*
X1711830D01*
G01X1708630Y1727950D02*
Y1721750D01*
G01X1711830D02*
Y1727950D01*
G01X1706877Y1716703D02*
Y1725365D01*
G01X1730575Y-26072D02*
Y-42352D01*
X1740175D01*
Y-26072D01*
X1730575D01*
G01X1730765Y52051D02*
X1736965D01*
G01X1730765Y55251D02*
Y52051D01*
G01X1736965Y55251D02*
X1730765D01*
G01Y56051D02*
X1736965D01*
G01X1730765Y59251D02*
Y56051D01*
G01X1736965Y59251D02*
X1730765D01*
G01X1727596Y60051D02*
X1739596D01*
G01X1727596Y66051D02*
Y60051D01*
G01X1722862Y72005D02*
X1726062D01*
G01X1722862Y78205D02*
Y72005D01*
G01X1726062D02*
Y78205D01*
G01X1722062Y72005D02*
Y78205D01*
G01X1739596Y66051D02*
X1727596D01*
G01X1726062Y78205D02*
X1722862D01*
G01X1738889Y89348D02*
X1726889D01*
G01Y83348D02*
X1738889D01*
G01X1726889Y89348D02*
Y83348D01*
G01X1734741Y761504D02*
X1722741D01*
G01X1734741Y755504D02*
Y761504D01*
G01X1722741Y755504D02*
X1734741D01*
G01X1722741Y761504D02*
Y755504D01*
G01X1736299D02*
X1748299D01*
G01X1736299Y761504D02*
Y755504D01*
G01X1748299Y761504D02*
X1736299D01*
G01X1728866Y762165D02*
Y765365D01*
G01X1722666Y762165D02*
X1728866D01*
G01X1722666Y765365D02*
Y762165D01*
G01X1728866Y765365D02*
X1722666D01*
G01Y768899D02*
Y765699D01*
G01X1728866Y768899D02*
X1722666D01*
G01X1728866Y765699D02*
Y768899D01*
G01X1722666Y765699D02*
X1728866D01*
G01X1722666Y769499D02*
X1728866D01*
Y772699D01*
X1722666D01*
Y769499D01*
G01X1727916Y959365D02*
Y962565D01*
G01X1721716Y959365D02*
X1727916D01*
G01X1721716Y962565D02*
Y959365D01*
G01X1727916Y962565D02*
X1721716D01*
G01X1726644Y1328962D02*
X1728884D01*
G01X1727671Y1327337D02*
Y1330587D01*
G01X1726913Y1372747D02*
Y1375173D01*
G01X1722841Y1376267D02*
Y1388267D01*
G01X1724000Y1399500D02*
X1736000D01*
G01X1724000Y1405500D02*
Y1399500D01*
G01X1736000D02*
Y1405500D01*
G01D02*
X1724000D01*
G01X1740070Y1517995D02*
Y1515755D01*
G01X1738445Y1516968D02*
X1741695D01*
G01X1725329Y1656056D02*
Y1652856D01*
G01X1731529Y1656056D02*
X1725329D01*
G01X1731529Y1652856D02*
Y1656056D01*
G01X1725329Y1652856D02*
X1731529D01*
G01X1725829Y1670856D02*
X1729029D01*
G01X1725829Y1677056D02*
Y1670856D01*
G01X1729029D02*
Y1677056D01*
G01X1729829Y1670856D02*
X1733029D01*
G01X1729829Y1677056D02*
Y1670856D01*
G01X1733029D02*
Y1677056D01*
G01X1731563Y1661865D02*
Y1665065D01*
G01X1725363Y1661865D02*
X1731563D01*
G01X1725363Y1665065D02*
Y1661865D01*
G01X1731563Y1665065D02*
X1725363D01*
G01X1731563Y1666365D02*
Y1669565D01*
G01X1725363Y1666365D02*
X1731563D01*
G01X1725363Y1669565D02*
Y1666365D01*
G01X1731563Y1669565D02*
X1725363D01*
G01X1731563Y1657365D02*
Y1660565D01*
G01X1725363Y1657365D02*
X1731563D01*
G01X1725363Y1660565D02*
Y1657365D01*
G01X1731563Y1660565D02*
X1725363D01*
G01X1725329Y1683056D02*
Y1679856D01*
G01X1731529Y1683056D02*
X1725329D01*
G01X1731529Y1679856D02*
Y1683056D01*
G01X1725329Y1679856D02*
X1731529D01*
G01X1729029Y1677056D02*
X1725829D01*
G01X1733029D02*
X1729829D01*
G01X1752184Y-41669D02*
X1751874Y-41477D01*
X1751667Y-41247D01*
X1751564Y-40979D01*
X1751667Y-40672D01*
X1751874Y-40442D01*
X1752184Y-40212D01*
X1752597Y-40135D01*
X1754664D01*
G01X1751564Y-37802D02*
X1751616Y-37534D01*
X1751771Y-37227D01*
X1752029Y-37035D01*
X1752391Y-36959D01*
X1752752Y-37035D01*
X1753062Y-37265D01*
X1753217Y-37610D01*
Y-37994D01*
X1753321Y-38224D01*
X1753579Y-38415D01*
X1753941Y-38492D01*
X1754302Y-38377D01*
X1754561Y-38109D01*
X1754664Y-37802D01*
X1754561Y-37495D01*
X1754302Y-37227D01*
X1753941Y-37112D01*
X1753579Y-37189D01*
X1753321Y-37380D01*
X1753217Y-37610D01*
Y-37994D01*
X1753062Y-38339D01*
X1752752Y-38569D01*
X1752391Y-38645D01*
X1752029Y-38569D01*
X1751771Y-38377D01*
X1751616Y-38070D01*
X1751564Y-37802D01*
G01X1754664Y-34702D02*
X1754561Y-35009D01*
X1754302Y-35239D01*
X1753992Y-35392D01*
X1753579Y-35507D01*
X1753114Y-35545D01*
X1752649Y-35507D01*
X1752236Y-35392D01*
X1751926Y-35239D01*
X1751667Y-35009D01*
X1751564Y-34702D01*
X1751667Y-34395D01*
X1751926Y-34165D01*
X1752236Y-34012D01*
X1752649Y-33897D01*
X1753114Y-33859D01*
X1753579Y-33897D01*
X1753992Y-34012D01*
X1754302Y-34165D01*
X1754561Y-34395D01*
X1754664Y-34702D01*
G01X1752856Y-32330D02*
X1753217Y-32062D01*
X1753424Y-31832D01*
X1753527Y-31525D01*
X1753424Y-31257D01*
X1753217Y-31065D01*
X1752907Y-30912D01*
X1752546Y-30874D01*
X1752236Y-30912D01*
X1751926Y-31065D01*
X1751667Y-31295D01*
X1751564Y-31564D01*
X1751667Y-31870D01*
X1751977Y-32139D01*
X1752442Y-32292D01*
X1752959Y-32330D01*
X1753631Y-32254D01*
X1753992Y-32139D01*
X1754354Y-31947D01*
X1754612Y-31679D01*
X1754664Y-31410D01*
X1754561Y-31142D01*
X1754302Y-30950D01*
G01X1751564Y-28502D02*
X1751616Y-28234D01*
X1751771Y-27927D01*
X1752029Y-27735D01*
X1752391Y-27659D01*
X1752752Y-27735D01*
X1753062Y-27965D01*
X1753217Y-28310D01*
Y-28694D01*
X1753321Y-28924D01*
X1753579Y-29115D01*
X1753941Y-29192D01*
X1754302Y-29077D01*
X1754561Y-28809D01*
X1754664Y-28502D01*
X1754561Y-28195D01*
X1754302Y-27927D01*
X1753941Y-27812D01*
X1753579Y-27889D01*
X1753321Y-28080D01*
X1753217Y-28310D01*
Y-28694D01*
X1753062Y-29039D01*
X1752752Y-29269D01*
X1752391Y-29345D01*
X1752029Y-29269D01*
X1751771Y-29077D01*
X1751616Y-28770D01*
X1751564Y-28502D01*
G01X1736965Y52051D02*
Y55251D01*
G01Y56051D02*
Y59251D01*
G01X1739596Y60051D02*
Y66051D01*
G01X1738889Y83348D02*
Y89348D01*
G01X1738201Y754365D02*
Y751165D01*
G01X1744401Y754365D02*
X1738201D01*
G01X1744401Y751165D02*
Y754365D01*
G01X1738201Y751165D02*
X1744401D01*
G01X1748299Y755504D02*
Y761504D01*
G01X1748375Y762165D02*
Y765365D01*
G01X1742175Y762165D02*
X1748375D01*
G01X1742175Y765365D02*
Y762165D01*
G01X1748375Y765365D02*
X1742175D01*
G01Y768865D02*
Y765665D01*
G01X1748375Y768865D02*
X1742175D01*
G01X1748375Y765665D02*
Y768865D01*
G01X1742175Y765665D02*
X1748375D01*
G01X1740081Y1323227D02*
X1743181D01*
Y1324147D01*
X1743026Y1324454D01*
X1742664Y1324684D01*
X1742251Y1324761D01*
X1741838Y1324684D01*
X1741528Y1324492D01*
X1741373Y1324147D01*
Y1323227D01*
G01X1742923Y1327937D02*
X1743078Y1327707D01*
X1743181Y1327439D01*
Y1327132D01*
X1743026Y1326787D01*
X1742768Y1326519D01*
X1742458Y1326327D01*
X1741941Y1326174D01*
X1741476Y1326136D01*
X1741011Y1326212D01*
X1740701Y1326327D01*
X1740391Y1326557D01*
X1740184Y1326826D01*
X1740081Y1327094D01*
Y1327362D01*
X1740184Y1327631D01*
X1740339Y1327861D01*
X1740546Y1328052D01*
G01X1740081Y1330194D02*
X1740133Y1330462D01*
X1740288Y1330769D01*
X1740546Y1330961D01*
X1740908Y1331037D01*
X1741269Y1330961D01*
X1741579Y1330731D01*
X1741734Y1330386D01*
Y1330002D01*
X1741838Y1329772D01*
X1742096Y1329581D01*
X1742458Y1329504D01*
X1742819Y1329619D01*
X1743078Y1329887D01*
X1743181Y1330194D01*
X1743078Y1330501D01*
X1742819Y1330769D01*
X1742458Y1330884D01*
X1742096Y1330807D01*
X1741838Y1330616D01*
X1741734Y1330386D01*
Y1330002D01*
X1741579Y1329657D01*
X1741269Y1329427D01*
X1740908Y1329351D01*
X1740546Y1329427D01*
X1740288Y1329619D01*
X1740133Y1329926D01*
X1740081Y1330194D01*
G01X1743181Y1333294D02*
X1743078Y1332987D01*
X1742819Y1332757D01*
X1742509Y1332604D01*
X1742096Y1332489D01*
X1741631Y1332451D01*
X1741166Y1332489D01*
X1740753Y1332604D01*
X1740443Y1332757D01*
X1740184Y1332987D01*
X1740081Y1333294D01*
X1740184Y1333601D01*
X1740443Y1333831D01*
X1740753Y1333984D01*
X1741166Y1334099D01*
X1741631Y1334137D01*
X1742096Y1334099D01*
X1742509Y1333984D01*
X1742819Y1333831D01*
X1743078Y1333601D01*
X1743181Y1333294D01*
G01Y1336394D02*
X1743078Y1336087D01*
X1742819Y1335857D01*
X1742509Y1335704D01*
X1742096Y1335589D01*
X1741631Y1335551D01*
X1741166Y1335589D01*
X1740753Y1335704D01*
X1740443Y1335857D01*
X1740184Y1336087D01*
X1740081Y1336394D01*
X1740184Y1336701D01*
X1740443Y1336931D01*
X1740753Y1337084D01*
X1741166Y1337199D01*
X1741631Y1337237D01*
X1742096Y1337199D01*
X1742509Y1337084D01*
X1742819Y1336931D01*
X1743078Y1336701D01*
X1743181Y1336394D01*
G01X1736825Y1335130D02*
Y1370826D01*
G01X1757117Y1470000D02*
Y1473100D01*
X1756197D01*
X1755890Y1472945D01*
X1755660Y1472583D01*
X1755583Y1472170D01*
X1755660Y1471757D01*
X1755852Y1471447D01*
X1756197Y1471292D01*
X1757117D01*
G01X1752407Y1472842D02*
X1752637Y1472997D01*
X1752905Y1473100D01*
X1753212D01*
X1753557Y1472945D01*
X1753825Y1472687D01*
X1754017Y1472377D01*
X1754170Y1471860D01*
X1754208Y1471395D01*
X1754132Y1470930D01*
X1754017Y1470620D01*
X1753787Y1470310D01*
X1753518Y1470103D01*
X1753250Y1470000D01*
X1752982D01*
X1752713Y1470103D01*
X1752483Y1470258D01*
X1752292Y1470465D01*
G01X1750878Y1471292D02*
X1750610Y1471653D01*
X1750380Y1471860D01*
X1750073Y1471963D01*
X1749805Y1471860D01*
X1749613Y1471653D01*
X1749460Y1471343D01*
X1749422Y1470982D01*
X1749460Y1470672D01*
X1749613Y1470362D01*
X1749843Y1470103D01*
X1750112Y1470000D01*
X1750418Y1470103D01*
X1750687Y1470413D01*
X1750840Y1470878D01*
X1750878Y1471395D01*
X1750802Y1472067D01*
X1750687Y1472428D01*
X1750495Y1472790D01*
X1750227Y1473048D01*
X1749958Y1473100D01*
X1749690Y1472997D01*
X1749498Y1472738D01*
G01X1747893Y1470465D02*
X1747663Y1470207D01*
X1747395Y1470052D01*
X1747050Y1470000D01*
X1746705Y1470103D01*
X1746437Y1470310D01*
X1746245Y1470672D01*
X1746207Y1471085D01*
X1746283Y1471498D01*
X1746475Y1471757D01*
X1746743Y1471963D01*
X1747012Y1472015D01*
X1747280Y1471963D01*
X1747625Y1471757D01*
X1747510Y1473100D01*
X1746475D01*
G01X1744678Y1471292D02*
X1744410Y1471653D01*
X1744180Y1471860D01*
X1743873Y1471963D01*
X1743605Y1471860D01*
X1743413Y1471653D01*
X1743260Y1471343D01*
X1743222Y1470982D01*
X1743260Y1470672D01*
X1743413Y1470362D01*
X1743643Y1470103D01*
X1743912Y1470000D01*
X1744218Y1470103D01*
X1744487Y1470413D01*
X1744640Y1470878D01*
X1744678Y1471395D01*
X1744602Y1472067D01*
X1744487Y1472428D01*
X1744295Y1472790D01*
X1744027Y1473048D01*
X1743758Y1473100D01*
X1743490Y1472997D01*
X1743298Y1472738D01*
G01X1740850Y1470000D02*
X1740582Y1470052D01*
X1740275Y1470207D01*
X1740083Y1470465D01*
X1740007Y1470827D01*
X1740083Y1471188D01*
X1740313Y1471498D01*
X1740658Y1471653D01*
X1741042D01*
X1741272Y1471757D01*
X1741463Y1472015D01*
X1741540Y1472377D01*
X1741425Y1472738D01*
X1741157Y1472997D01*
X1740850Y1473100D01*
X1740543Y1472997D01*
X1740275Y1472738D01*
X1740160Y1472377D01*
X1740237Y1472015D01*
X1740428Y1471757D01*
X1740658Y1471653D01*
X1741042D01*
X1741387Y1471498D01*
X1741617Y1471188D01*
X1741693Y1470827D01*
X1741617Y1470465D01*
X1741425Y1470207D01*
X1741118Y1470052D01*
X1740850Y1470000D01*
G01X1749191Y1477603D02*
Y1475177D01*
G01X1740223Y1478301D02*
X1757153D01*
G01X1740223Y1514041D02*
Y1478301D01*
G01X1740221Y1514041D02*
X1757161Y1514044D01*
G01X1740221Y1514641D02*
X1757196Y1514645D01*
G01X1740221Y1515241D02*
X1757204Y1515235D01*
G01X1740221Y1515241D02*
Y1514041D01*
G01X1757153D02*
X1740223D01*
G01X1766655Y1519161D02*
X1749715Y1519158D01*
G01X1766655Y1518561D02*
X1749680Y1518557D01*
G01X1766655Y1517961D02*
X1749672Y1517967D01*
G01X1749722Y1518011D02*
X1749726Y1519520D01*
G01X1749723Y1519161D02*
X1766653D01*
G01X1749723Y1554901D02*
Y1519161D01*
G01X1747148Y1526080D02*
Y1538080D01*
G01X1741148Y1526080D02*
X1747148D01*
G01X1741148Y1538080D02*
Y1526080D01*
G01X1747148Y1538080D02*
X1741148D01*
G01X1745000Y1540383D02*
X1748100D01*
Y1541303D01*
X1747945Y1541610D01*
X1747583Y1541840D01*
X1747170Y1541917D01*
X1746757Y1541840D01*
X1746447Y1541648D01*
X1746292Y1541303D01*
Y1540383D01*
G01X1747842Y1545093D02*
X1747997Y1544863D01*
X1748100Y1544595D01*
Y1544288D01*
X1747945Y1543943D01*
X1747687Y1543675D01*
X1747377Y1543483D01*
X1746860Y1543330D01*
X1746395Y1543292D01*
X1745930Y1543368D01*
X1745620Y1543483D01*
X1745310Y1543713D01*
X1745103Y1543982D01*
X1745000Y1544250D01*
Y1544518D01*
X1745103Y1544787D01*
X1745258Y1545017D01*
X1745465Y1545208D01*
G01X1746292Y1546622D02*
X1746653Y1546890D01*
X1746860Y1547120D01*
X1746963Y1547427D01*
X1746860Y1547695D01*
X1746653Y1547887D01*
X1746343Y1548040D01*
X1745982Y1548078D01*
X1745672Y1548040D01*
X1745362Y1547887D01*
X1745103Y1547657D01*
X1745000Y1547388D01*
X1745103Y1547082D01*
X1745413Y1546813D01*
X1745878Y1546660D01*
X1746395Y1546622D01*
X1747067Y1546698D01*
X1747428Y1546813D01*
X1747790Y1547005D01*
X1748048Y1547273D01*
X1748100Y1547542D01*
X1747997Y1547810D01*
X1747738Y1548002D01*
G01X1745000Y1550450D02*
X1745052Y1550718D01*
X1745207Y1551025D01*
X1745465Y1551217D01*
X1745827Y1551293D01*
X1746188Y1551217D01*
X1746498Y1550987D01*
X1746653Y1550642D01*
Y1550258D01*
X1746757Y1550028D01*
X1747015Y1549837D01*
X1747377Y1549760D01*
X1747738Y1549875D01*
X1747997Y1550143D01*
X1748100Y1550450D01*
X1747997Y1550757D01*
X1747738Y1551025D01*
X1747377Y1551140D01*
X1747015Y1551063D01*
X1746757Y1550872D01*
X1746653Y1550642D01*
Y1550258D01*
X1746498Y1549913D01*
X1746188Y1549683D01*
X1745827Y1549607D01*
X1745465Y1549683D01*
X1745207Y1549875D01*
X1745052Y1550182D01*
X1745000Y1550450D01*
G01Y1553550D02*
X1748100D01*
X1747480Y1553090D01*
G01X1745000D02*
Y1554010D01*
G01Y1556650D02*
X1748100D01*
X1747480Y1556190D01*
G01X1745000D02*
Y1557110D01*
G01X1766653Y1554901D02*
X1749723D01*
G01X1739919Y1569985D02*
X1743119D01*
G01X1739919Y1576185D02*
Y1569985D01*
G01X1743119Y1576185D02*
X1739919D01*
G01X1743119Y1569985D02*
Y1576185D01*
G01X1752063Y1651065D02*
X1748863D01*
G01Y1644865D02*
X1752063D01*
G01X1748863Y1651065D02*
Y1644865D01*
G01X1767662Y44703D02*
X1764462D01*
G01D02*
Y38503D01*
G01D02*
X1767662D01*
G01X1760462Y44703D02*
Y38503D01*
G01D02*
X1763662D01*
G01D02*
Y44703D01*
G01D02*
X1760462D01*
G01X1760983Y203465D02*
X1766983D01*
G01X1760983Y215465D02*
Y203465D01*
G01X1759923Y203402D02*
Y215402D01*
G01X1753923Y203402D02*
X1759923D01*
G01X1753923Y215402D02*
Y203402D01*
G01X1766983Y215465D02*
X1760983D01*
G01X1759923Y215402D02*
X1753923D01*
G01X1764441Y761504D02*
X1752441D01*
G01X1764441Y755504D02*
Y761504D01*
G01X1752441Y755504D02*
X1764441D01*
G01X1752441Y761504D02*
Y755504D01*
G01X1766000D02*
X1778000D01*
G01X1766000Y761504D02*
Y755504D01*
G01X1778000Y761504D02*
X1766000D01*
G01X1758567Y762165D02*
Y765365D01*
G01X1752367Y762165D02*
X1758567D01*
G01X1752367Y765365D02*
Y762165D01*
G01X1758567Y765365D02*
X1752367D01*
G01X1752366Y768905D02*
Y765705D01*
G01X1758566Y768905D02*
X1752366D01*
G01X1758566Y765705D02*
Y768905D01*
G01X1752366Y765705D02*
X1758566D01*
G01X1752366Y769505D02*
X1758566D01*
Y772705D01*
X1752366D01*
Y769505D01*
G01X1757617Y959365D02*
Y962565D01*
G01X1751417Y959365D02*
X1757617D01*
G01X1751417Y962565D02*
Y959365D01*
G01X1757617Y962565D02*
X1751417D01*
G01X1780117Y1470000D02*
Y1473100D01*
X1779197D01*
X1778890Y1472945D01*
X1778660Y1472583D01*
X1778583Y1472170D01*
X1778660Y1471757D01*
X1778852Y1471447D01*
X1779197Y1471292D01*
X1780117D01*
G01X1775407Y1472842D02*
X1775637Y1472997D01*
X1775905Y1473100D01*
X1776212D01*
X1776557Y1472945D01*
X1776825Y1472687D01*
X1777017Y1472377D01*
X1777170Y1471860D01*
X1777208Y1471395D01*
X1777132Y1470930D01*
X1777017Y1470620D01*
X1776787Y1470310D01*
X1776518Y1470103D01*
X1776250Y1470000D01*
X1775982D01*
X1775713Y1470103D01*
X1775483Y1470258D01*
X1775292Y1470465D01*
G01X1773878Y1471292D02*
X1773610Y1471653D01*
X1773380Y1471860D01*
X1773073Y1471963D01*
X1772805Y1471860D01*
X1772613Y1471653D01*
X1772460Y1471343D01*
X1772422Y1470982D01*
X1772460Y1470672D01*
X1772613Y1470362D01*
X1772843Y1470103D01*
X1773112Y1470000D01*
X1773418Y1470103D01*
X1773687Y1470413D01*
X1773840Y1470878D01*
X1773878Y1471395D01*
X1773802Y1472067D01*
X1773687Y1472428D01*
X1773495Y1472790D01*
X1773227Y1473048D01*
X1772958Y1473100D01*
X1772690Y1472997D01*
X1772498Y1472738D01*
G01X1770893Y1470465D02*
X1770663Y1470207D01*
X1770395Y1470052D01*
X1770050Y1470000D01*
X1769705Y1470103D01*
X1769437Y1470310D01*
X1769245Y1470672D01*
X1769207Y1471085D01*
X1769283Y1471498D01*
X1769475Y1471757D01*
X1769743Y1471963D01*
X1770012Y1472015D01*
X1770280Y1471963D01*
X1770625Y1471757D01*
X1770510Y1473100D01*
X1769475D01*
G01X1767027Y1470000D02*
X1766950Y1470672D01*
X1766835Y1471240D01*
X1766682Y1471757D01*
X1766490Y1472325D01*
X1766183Y1473100D01*
X1767717D01*
G01X1763850D02*
X1764157Y1472997D01*
X1764387Y1472738D01*
X1764540Y1472428D01*
X1764655Y1472015D01*
X1764693Y1471550D01*
X1764655Y1471085D01*
X1764540Y1470672D01*
X1764387Y1470362D01*
X1764157Y1470103D01*
X1763850Y1470000D01*
X1763543Y1470103D01*
X1763313Y1470362D01*
X1763160Y1470672D01*
X1763045Y1471085D01*
X1763007Y1471550D01*
X1763045Y1472015D01*
X1763160Y1472428D01*
X1763313Y1472738D01*
X1763543Y1472997D01*
X1763850Y1473100D01*
G01X1762923Y1478301D02*
X1779853D01*
G01X1762923Y1514041D02*
Y1478301D01*
G01X1757153D02*
Y1514041D01*
G01X1762921D02*
X1779861Y1514044D01*
G01X1762921Y1514641D02*
X1779896Y1514645D01*
G01X1762921Y1515241D02*
X1779904Y1515235D01*
G01X1762921Y1515241D02*
Y1514041D01*
G01X1779853D02*
X1762923D01*
G01X1757154Y1515191D02*
X1757150Y1513682D01*
G01X1759991Y1513886D02*
Y1516126D01*
G01X1761616Y1514913D02*
X1758366D01*
G01X1762310Y1569205D02*
Y1557205D01*
G01D02*
X1768310D01*
G01X1753904Y1569205D02*
Y1557205D01*
G01X1759904D02*
Y1569205D01*
G01X1753904Y1557205D02*
X1759904D01*
G01X1770603Y1557246D02*
Y1559672D01*
G01X1768310Y1569205D02*
X1762310D01*
G01X1759904D02*
X1753904D01*
G01X1754779Y1594550D02*
X1766779D01*
G01X1754779Y1600550D02*
Y1594550D01*
G01X1766779Y1600550D02*
X1754779D01*
G01X1766779Y1607950D02*
X1754779D01*
G01Y1601950D02*
X1766779D01*
G01X1754779Y1607950D02*
Y1601950D01*
G01X1757063Y1651065D02*
X1753863D01*
G01X1757063Y1644865D02*
Y1651065D01*
G01X1753863Y1644865D02*
X1757063D01*
G01X1753863Y1651065D02*
Y1644865D01*
G01X1759329Y1649856D02*
X1762529D01*
G01X1759329Y1656056D02*
Y1649856D01*
G01X1762529Y1656056D02*
X1759329D01*
G01X1762529Y1649856D02*
Y1656056D01*
G01X1752063Y1644865D02*
Y1651065D01*
G01X1765529Y1657356D02*
Y1660556D01*
G01X1759329Y1657356D02*
X1765529D01*
G01X1759329Y1660556D02*
Y1657356D01*
G01X1765529Y1660556D02*
X1759329D01*
G01X1777279Y1714960D02*
G02I-10350J0D01*
G01X1772157Y36000D02*
Y29800D01*
G01D02*
X1775357D01*
G01D02*
Y36000D01*
G01X1771357Y29800D02*
Y36000D01*
G01X1768157D02*
Y29800D01*
G01D02*
X1771357D01*
G01X1767662Y38503D02*
Y44703D01*
G01X1775357Y36000D02*
X1772157D01*
G01X1771357D02*
X1768157D01*
G01X1776154Y44969D02*
Y38769D01*
G01D02*
X1779354D01*
G01D02*
Y44969D01*
G01D02*
X1776154D01*
G01X1771954Y44809D02*
Y38609D01*
G01D02*
X1775154D01*
G01D02*
Y44809D01*
G01D02*
X1771954D01*
G01X1768300D02*
Y38609D01*
G01D02*
X1771500D01*
G01D02*
Y44809D01*
G01D02*
X1768300D01*
G01X1780390Y44855D02*
Y38655D01*
G01D02*
X1783590D01*
G01Y44855D02*
X1780390D01*
G01X1826399Y126194D02*
G02I-25950J0D01*
G01X1769354Y181029D02*
X1775354D01*
G01D02*
Y193029D01*
G01D02*
X1769354D01*
G01D02*
Y181029D01*
G01X1774864Y214069D02*
Y202069D01*
G01D02*
X1780864D01*
G01D02*
Y214069D01*
G01X1767824Y214059D02*
Y202059D01*
G01D02*
X1773824D01*
G01D02*
Y214059D01*
G01X1766983Y203465D02*
Y215465D01*
G01X1780864Y214069D02*
X1774864D01*
G01X1773824Y214059D02*
X1767824D01*
G01X1780296Y252933D02*
X1786296D01*
G01X1780296Y264933D02*
Y252933D01*
G01X1786296Y264933D02*
X1780296D01*
G01X1768201Y754865D02*
Y751665D01*
G01X1774401Y754865D02*
X1768201D01*
G01X1774401Y751665D02*
Y754865D01*
G01X1768201Y751665D02*
X1774401D01*
G01X1778000Y755504D02*
Y761504D01*
G01X1778075Y762165D02*
Y765365D01*
G01X1771875Y762165D02*
X1778075D01*
G01X1771875Y765365D02*
Y762165D01*
G01X1778075Y765365D02*
X1771875D01*
G01Y768865D02*
Y765665D01*
G01X1778075Y768865D02*
X1771875D01*
G01X1778075Y765665D02*
Y768865D01*
G01X1771875Y765665D02*
X1778075D01*
G01X1781117Y959365D02*
X1787317D01*
G01X1781117Y962565D02*
Y959365D01*
G01X1787317Y962565D02*
X1781117D01*
G01X1771891Y1477603D02*
Y1475177D01*
G01X1779853Y1478301D02*
Y1514041D01*
G01X1784041Y1515011D02*
Y1512771D01*
G01X1782416Y1513984D02*
X1785666D01*
G01X1772500Y1518727D02*
Y1516487D01*
G01X1770875Y1517700D02*
X1774125D01*
G01X1779854Y1515191D02*
X1779850Y1513682D01*
G01X1795560Y1519207D02*
X1778620Y1519204D01*
G01X1795560Y1518607D02*
X1778585Y1518603D01*
G01X1795560Y1518007D02*
X1778577Y1518013D01*
G01X1778627Y1518057D02*
X1778631Y1519566D01*
G01X1778628Y1519207D02*
X1795558D01*
G01X1778628Y1554947D02*
Y1519207D01*
G01X1766655Y1517961D02*
Y1519161D01*
G01X1766653D02*
Y1554901D01*
G01X1776352Y1527861D02*
Y1539861D01*
G01X1770352Y1527861D02*
X1776352D01*
G01X1770352Y1539861D02*
Y1527861D01*
G01X1776352Y1539861D02*
X1770352D01*
G01X1772679Y1563505D02*
X1775879D01*
G01X1772679Y1569705D02*
Y1563505D01*
G01X1775879D02*
Y1569705D01*
G01X1768310Y1557205D02*
Y1569205D01*
G01X1778178Y1556718D02*
Y1559144D01*
G01X1795558Y1554947D02*
X1778628D01*
G01X1775879Y1569705D02*
X1772679D01*
G01X1766779Y1594550D02*
Y1600550D01*
G01Y1601950D02*
Y1607950D01*
G01X1767765Y1670637D02*
Y1667437D01*
G01X1773965Y1670637D02*
X1767765D01*
G01Y1667437D02*
X1773965D01*
G01D02*
Y1670637D01*
G01X1766363Y1663065D02*
Y1659865D01*
G01X1772563Y1663065D02*
X1766363D01*
G01X1772563Y1659865D02*
Y1663065D01*
G01X1766363Y1659865D02*
X1772563D01*
G01X1830600Y1667292D02*
G02I-25950J0D01*
G01X1773363Y1675265D02*
Y1678465D01*
G01X1767163Y1675265D02*
X1773363D01*
G01X1767163Y1678465D02*
Y1675265D01*
G01X1773363Y1678465D02*
X1767163D01*
G01X1766563Y1674565D02*
Y1671365D01*
G01X1772763Y1674565D02*
X1766563D01*
G01X1772763Y1671365D02*
Y1674565D01*
G01X1766563Y1671365D02*
X1772763D01*
G01X1784390Y47686D02*
Y44486D01*
G01D02*
X1790590D01*
G01D02*
Y47686D01*
G01X1783590Y38655D02*
Y44855D01*
G01X1790590Y47686D02*
X1784390D01*
G01X1786072Y54686D02*
Y48486D01*
G01D02*
X1789272D01*
G01D02*
Y54686D01*
G01D02*
X1786072D01*
G01X1790072D02*
Y48486D01*
G01D02*
X1793272D01*
G01D02*
Y54686D01*
G01D02*
X1790072D01*
G01X1793245Y186297D02*
Y192497D01*
G01D02*
X1790045D01*
G01D02*
Y186297D01*
G01D02*
X1793245D01*
G01X1788776Y252933D02*
X1794776D01*
G01D02*
Y264933D01*
G01X1788776D02*
Y252933D01*
G01X1786296D02*
Y264933D01*
G01X1794776D02*
X1788776D01*
G01X1794142Y761504D02*
X1782142D01*
G01X1794142Y755504D02*
Y761504D01*
G01X1782142Y755504D02*
X1794142D01*
G01X1782142Y761504D02*
Y755504D01*
G01X1788267Y762165D02*
Y765365D01*
G01X1782067Y762165D02*
X1788267D01*
G01X1782067Y765365D02*
Y762165D01*
G01X1788267Y765365D02*
X1782067D01*
G01Y769165D02*
Y765965D01*
G01X1788267Y769165D02*
X1782067D01*
G01X1788267Y765965D02*
Y769165D01*
G01X1782067Y765965D02*
X1788267D01*
G01X1782067Y769765D02*
X1788267D01*
Y772965D01*
X1782067D01*
Y769765D01*
G01X1787317Y959365D02*
Y962565D01*
G01X1804617Y1470000D02*
Y1473100D01*
X1803697D01*
X1803390Y1472945D01*
X1803160Y1472583D01*
X1803083Y1472170D01*
X1803160Y1471757D01*
X1803352Y1471447D01*
X1803697Y1471292D01*
X1804617D01*
G01X1799907Y1472842D02*
X1800137Y1472997D01*
X1800405Y1473100D01*
X1800712D01*
X1801057Y1472945D01*
X1801325Y1472687D01*
X1801517Y1472377D01*
X1801670Y1471860D01*
X1801708Y1471395D01*
X1801632Y1470930D01*
X1801517Y1470620D01*
X1801287Y1470310D01*
X1801018Y1470103D01*
X1800750Y1470000D01*
X1800482D01*
X1800213Y1470103D01*
X1799983Y1470258D01*
X1799792Y1470465D01*
G01X1798378Y1471292D02*
X1798110Y1471653D01*
X1797880Y1471860D01*
X1797573Y1471963D01*
X1797305Y1471860D01*
X1797113Y1471653D01*
X1796960Y1471343D01*
X1796922Y1470982D01*
X1796960Y1470672D01*
X1797113Y1470362D01*
X1797343Y1470103D01*
X1797612Y1470000D01*
X1797918Y1470103D01*
X1798187Y1470413D01*
X1798340Y1470878D01*
X1798378Y1471395D01*
X1798302Y1472067D01*
X1798187Y1472428D01*
X1797995Y1472790D01*
X1797727Y1473048D01*
X1797458Y1473100D01*
X1797190Y1472997D01*
X1796998Y1472738D01*
G01X1795393Y1470465D02*
X1795163Y1470207D01*
X1794895Y1470052D01*
X1794550Y1470000D01*
X1794205Y1470103D01*
X1793937Y1470310D01*
X1793745Y1470672D01*
X1793707Y1471085D01*
X1793783Y1471498D01*
X1793975Y1471757D01*
X1794243Y1471963D01*
X1794512Y1472015D01*
X1794780Y1471963D01*
X1795125Y1471757D01*
X1795010Y1473100D01*
X1793975D01*
G01X1792178Y1471292D02*
X1791910Y1471653D01*
X1791680Y1471860D01*
X1791373Y1471963D01*
X1791105Y1471860D01*
X1790913Y1471653D01*
X1790760Y1471343D01*
X1790722Y1470982D01*
X1790760Y1470672D01*
X1790913Y1470362D01*
X1791143Y1470103D01*
X1791412Y1470000D01*
X1791718Y1470103D01*
X1791987Y1470413D01*
X1792140Y1470878D01*
X1792178Y1471395D01*
X1792102Y1472067D01*
X1791987Y1472428D01*
X1791795Y1472790D01*
X1791527Y1473048D01*
X1791258Y1473100D01*
X1790990Y1472997D01*
X1790798Y1472738D01*
G01X1789002Y1470362D02*
X1788733Y1470103D01*
X1788427Y1470000D01*
X1788120Y1470103D01*
X1787852Y1470413D01*
X1787660Y1470878D01*
X1787583Y1471343D01*
Y1471912D01*
X1787660Y1472377D01*
X1787852Y1472790D01*
X1788082Y1472997D01*
X1788350Y1473100D01*
X1788657Y1472997D01*
X1788887Y1472790D01*
X1789040Y1472480D01*
X1789117Y1472067D01*
X1789040Y1471705D01*
X1788848Y1471343D01*
X1788618Y1471137D01*
X1788350Y1471085D01*
X1788043Y1471188D01*
X1787813Y1471447D01*
X1787583Y1471912D01*
G01X1795891Y1477603D02*
Y1475177D01*
G01X1786923Y1478301D02*
X1803853D01*
G01X1786923Y1514041D02*
Y1478301D01*
G01X1786921Y1514041D02*
X1803861Y1514044D01*
G01X1786921Y1514641D02*
X1803896Y1514645D01*
G01X1786921Y1515241D02*
X1803904Y1515235D01*
G01X1786921Y1515241D02*
Y1514041D01*
G01X1803853D02*
X1786923D01*
G01X1795560Y1518007D02*
Y1519207D01*
G01X1795558D02*
Y1554947D01*
G01X1789179Y1569205D02*
Y1557205D01*
G01X1795179D02*
Y1569205D01*
G01X1789179Y1557205D02*
X1795179D01*
G01Y1569205D02*
X1789179D01*
G01X1815722Y176469D02*
X1809522D01*
G01D02*
Y173269D01*
G01D02*
X1815722D01*
G01X1799594Y177919D02*
Y184119D01*
G01X1796394D02*
Y177919D01*
G01D02*
X1799594D01*
G01X1809522Y169269D02*
X1815722D01*
G01Y172469D02*
X1809522D01*
G01D02*
Y169269D01*
G01X1799594Y184119D02*
X1796394D01*
G01X1796796Y252933D02*
X1802796D01*
G01D02*
Y264933D01*
G01X1796796D02*
Y252933D01*
G01X1805696Y262133D02*
Y255933D01*
G01D02*
X1808896D01*
G01D02*
Y262133D01*
G01D02*
X1805696D01*
G01X1802796Y264933D02*
X1796796D01*
G01X1810923Y1478301D02*
X1826800D01*
G01X1810923Y1514041D02*
Y1478301D01*
G01X1803853D02*
Y1514041D01*
G01X1810921D02*
X1827861Y1514044D01*
G01X1810921Y1514641D02*
X1827896Y1514645D01*
G01X1810921Y1515241D02*
X1827904Y1515235D01*
G01X1810921Y1515241D02*
Y1514041D01*
G01X1827853D02*
X1810923D01*
G01X1803854Y1515191D02*
X1803850Y1513682D01*
G01X1803320Y1516911D02*
Y1519151D01*
G01X1804945Y1517938D02*
X1801695D01*
G01X1800379Y1529305D02*
X1803579D01*
G01X1800379Y1535505D02*
Y1529305D01*
G01X1803579Y1535505D02*
X1800379D01*
G01X1803579Y1529305D02*
Y1535505D01*
G01X1805422Y1526016D02*
X1811422D01*
G01X1805422Y1538016D02*
Y1526016D01*
G01X1811422Y1538016D02*
X1805422D01*
G01X1797500Y1537883D02*
X1800600D01*
Y1538803D01*
X1800445Y1539110D01*
X1800083Y1539340D01*
X1799670Y1539417D01*
X1799257Y1539340D01*
X1798947Y1539148D01*
X1798792Y1538803D01*
Y1537883D01*
G01X1800342Y1542593D02*
X1800497Y1542363D01*
X1800600Y1542095D01*
Y1541788D01*
X1800445Y1541443D01*
X1800187Y1541175D01*
X1799877Y1540983D01*
X1799360Y1540830D01*
X1798895Y1540792D01*
X1798430Y1540868D01*
X1798120Y1540983D01*
X1797810Y1541213D01*
X1797603Y1541482D01*
X1797500Y1541750D01*
Y1542018D01*
X1797603Y1542287D01*
X1797758Y1542517D01*
X1797965Y1542708D01*
G01X1798792Y1544122D02*
X1799153Y1544390D01*
X1799360Y1544620D01*
X1799463Y1544927D01*
X1799360Y1545195D01*
X1799153Y1545387D01*
X1798843Y1545540D01*
X1798482Y1545578D01*
X1798172Y1545540D01*
X1797862Y1545387D01*
X1797603Y1545157D01*
X1797500Y1544888D01*
X1797603Y1544582D01*
X1797913Y1544313D01*
X1798378Y1544160D01*
X1798895Y1544122D01*
X1799567Y1544198D01*
X1799928Y1544313D01*
X1800290Y1544505D01*
X1800548Y1544773D01*
X1800600Y1545042D01*
X1800497Y1545310D01*
X1800238Y1545502D01*
G01X1797500Y1547950D02*
X1797552Y1548218D01*
X1797707Y1548525D01*
X1797965Y1548717D01*
X1798327Y1548793D01*
X1798688Y1548717D01*
X1798998Y1548487D01*
X1799153Y1548142D01*
Y1547758D01*
X1799257Y1547528D01*
X1799515Y1547337D01*
X1799877Y1547260D01*
X1800238Y1547375D01*
X1800497Y1547643D01*
X1800600Y1547950D01*
X1800497Y1548257D01*
X1800238Y1548525D01*
X1799877Y1548640D01*
X1799515Y1548563D01*
X1799257Y1548372D01*
X1799153Y1548142D01*
Y1547758D01*
X1798998Y1547413D01*
X1798688Y1547183D01*
X1798327Y1547107D01*
X1797965Y1547183D01*
X1797707Y1547375D01*
X1797552Y1547682D01*
X1797500Y1547950D01*
G01Y1551050D02*
X1800600D01*
X1799980Y1550590D01*
G01X1797500D02*
Y1551510D01*
G01X1800083Y1553422D02*
X1800393Y1553652D01*
X1800548Y1553920D01*
X1800600Y1554227D01*
X1800497Y1554610D01*
X1800238Y1554878D01*
X1799928Y1554955D01*
X1799618Y1554917D01*
X1799360Y1554763D01*
X1798843Y1553997D01*
X1798482Y1553652D01*
X1797965Y1553422D01*
X1797500Y1553345D01*
Y1554955D01*
G01X1797579Y1569205D02*
Y1557205D01*
G01X1803579D02*
Y1569205D01*
G01X1797579Y1557205D02*
X1803579D01*
G01Y1569205D02*
X1797579D01*
G01X1798513Y1595316D02*
X1810513D01*
G01X1798513Y1601316D02*
Y1595316D01*
G01X1810513D02*
Y1601316D01*
G01X1798513Y1602816D02*
X1810513D01*
G01X1798513Y1608816D02*
Y1602816D01*
G01X1810513Y1608816D02*
X1798513D01*
G01X1810513Y1602816D02*
Y1608816D01*
G01Y1601316D02*
X1798513D01*
G01X1815722Y173269D02*
Y176469D01*
G01Y169269D02*
Y172469D01*
G01X1826617Y1470000D02*
Y1473100D01*
X1825697D01*
X1825390Y1472945D01*
X1825160Y1472583D01*
X1825083Y1472170D01*
X1825160Y1471757D01*
X1825352Y1471447D01*
X1825697Y1471292D01*
X1826617D01*
G01X1821907Y1472842D02*
X1822137Y1472997D01*
X1822405Y1473100D01*
X1822712D01*
X1823057Y1472945D01*
X1823325Y1472687D01*
X1823517Y1472377D01*
X1823670Y1471860D01*
X1823708Y1471395D01*
X1823632Y1470930D01*
X1823517Y1470620D01*
X1823287Y1470310D01*
X1823018Y1470103D01*
X1822750Y1470000D01*
X1822482D01*
X1822213Y1470103D01*
X1821983Y1470258D01*
X1821792Y1470465D01*
G01X1820493D02*
X1820263Y1470207D01*
X1819995Y1470052D01*
X1819650Y1470000D01*
X1819305Y1470103D01*
X1819037Y1470310D01*
X1818845Y1470672D01*
X1818807Y1471085D01*
X1818883Y1471498D01*
X1819075Y1471757D01*
X1819343Y1471963D01*
X1819612Y1472015D01*
X1819880Y1471963D01*
X1820225Y1471757D01*
X1820110Y1473100D01*
X1819075D01*
G01X1817393Y1470620D02*
X1817163Y1470258D01*
X1816857Y1470052D01*
X1816512Y1470000D01*
X1816205Y1470052D01*
X1815898Y1470310D01*
X1815707Y1470620D01*
X1815668Y1470930D01*
X1815745Y1471292D01*
X1816013Y1471550D01*
X1816282Y1471653D01*
X1816627D01*
G01X1816282D02*
X1816052Y1471808D01*
X1815860Y1472067D01*
X1815783Y1472377D01*
X1815860Y1472687D01*
X1816052Y1472945D01*
X1816397Y1473100D01*
X1816742Y1473048D01*
X1817087Y1472842D01*
G01X1812990Y1470000D02*
Y1473100D01*
X1814408Y1470878D01*
X1812492D01*
G01X1819891Y1477603D02*
Y1475177D01*
G01X1818936Y1518866D02*
Y1516626D01*
G01X1817311Y1517839D02*
X1820561D01*
G01X1821214Y1526893D02*
X1825814D01*
G01X1821214Y1537093D02*
Y1526893D01*
G01X1825814D02*
Y1537093D01*
G01X1819922Y1526016D02*
Y1538016D01*
G01X1813922Y1526016D02*
X1819922D01*
G01X1813922Y1538016D02*
Y1526016D01*
G01X1811422D02*
Y1538016D01*
G01X1825814Y1537093D02*
X1821214D01*
G01X1819922Y1538016D02*
X1813922D01*
G01X1827853Y1480200D02*
Y1514041D01*
G01X1827854Y1515191D02*
X1827850Y1513682D01*
G01X1853677Y482173D02*
X1866790Y447597D01*
G01X1879903Y482173D02*
X1853677D01*
G01X1854631Y763988D02*
X1857731D01*
Y764754D01*
X1857576Y765061D01*
X1857369Y765291D01*
X1857059Y765483D01*
X1856698Y765636D01*
X1856181Y765674D01*
X1855664Y765636D01*
X1855303Y765483D01*
X1854993Y765291D01*
X1854786Y765061D01*
X1854631Y764754D01*
Y763988D01*
G01X1856284Y768238D02*
X1856439Y768391D01*
X1856698Y768506D01*
X1857059Y768583D01*
X1857369Y768506D01*
X1857576Y768353D01*
X1857731Y768084D01*
Y767049D01*
X1854631D01*
Y768314D01*
X1854838Y768583D01*
X1855148Y768736D01*
X1855509Y768813D01*
X1855871Y768736D01*
X1856181Y768506D01*
X1856284Y768238D01*
Y767049D01*
G01X1854631Y771031D02*
X1857731D01*
X1857111Y770571D01*
G01X1854631D02*
Y771491D01*
G01X1855251Y773288D02*
X1854889Y773518D01*
X1854683Y773824D01*
X1854631Y774169D01*
X1854683Y774476D01*
X1854941Y774783D01*
X1855251Y774974D01*
X1855561Y775013D01*
X1855923Y774936D01*
X1856181Y774668D01*
X1856284Y774399D01*
Y774054D01*
G01Y774399D02*
X1856439Y774629D01*
X1856698Y774821D01*
X1857008Y774898D01*
X1857318Y774821D01*
X1857576Y774629D01*
X1857731Y774284D01*
X1857679Y773939D01*
X1857473Y773594D01*
G01X1852535Y778129D02*
X1878761D01*
G01X1865648Y812705D02*
X1852535Y778129D01*
G01X1854182Y856367D02*
X1867295Y821791D01*
G01X1880408Y856367D02*
X1854182D01*
G01X1854193Y1141000D02*
X1857293D01*
Y1141766D01*
X1857138Y1142073D01*
X1856931Y1142303D01*
X1856621Y1142495D01*
X1856260Y1142648D01*
X1855743Y1142686D01*
X1855226Y1142648D01*
X1854865Y1142495D01*
X1854555Y1142303D01*
X1854348Y1142073D01*
X1854193Y1141766D01*
Y1141000D01*
G01X1855846Y1145250D02*
X1856001Y1145403D01*
X1856260Y1145518D01*
X1856621Y1145595D01*
X1856931Y1145518D01*
X1857138Y1145365D01*
X1857293Y1145096D01*
Y1144061D01*
X1854193D01*
Y1145326D01*
X1854400Y1145595D01*
X1854710Y1145748D01*
X1855071Y1145825D01*
X1855433Y1145748D01*
X1855743Y1145518D01*
X1855846Y1145250D01*
Y1144061D01*
G01X1855485Y1147315D02*
X1855846Y1147583D01*
X1856053Y1147813D01*
X1856156Y1148120D01*
X1856053Y1148388D01*
X1855846Y1148580D01*
X1855536Y1148733D01*
X1855175Y1148771D01*
X1854865Y1148733D01*
X1854555Y1148580D01*
X1854296Y1148350D01*
X1854193Y1148081D01*
X1854296Y1147775D01*
X1854606Y1147506D01*
X1855071Y1147353D01*
X1855588Y1147315D01*
X1856260Y1147391D01*
X1856621Y1147506D01*
X1856983Y1147698D01*
X1857241Y1147966D01*
X1857293Y1148235D01*
X1857190Y1148503D01*
X1856931Y1148695D01*
G01X1853677Y1152471D02*
X1879903D01*
G01X1866790Y1187047D02*
X1853677Y1152471D01*
G01X1866790Y447597D02*
X1877919Y476942D01*
G01X1878761Y778129D02*
X1865648Y812705D01*
G01X1867295Y821791D02*
X1880408Y856367D01*
G01X1879903Y1152471D02*
X1866790Y1187047D01*
G01X1875571Y486408D02*
X1878671D01*
Y487174D01*
X1878516Y487481D01*
X1878309Y487711D01*
X1877999Y487903D01*
X1877638Y488056D01*
X1877121Y488094D01*
X1876604Y488056D01*
X1876243Y487903D01*
X1875933Y487711D01*
X1875726Y487481D01*
X1875571Y487174D01*
Y486408D01*
G01X1877224Y490658D02*
X1877379Y490811D01*
X1877638Y490926D01*
X1877999Y491003D01*
X1878309Y490926D01*
X1878516Y490773D01*
X1878671Y490504D01*
Y489469D01*
X1875571D01*
Y490734D01*
X1875778Y491003D01*
X1876088Y491156D01*
X1876449Y491233D01*
X1876811Y491156D01*
X1877121Y490926D01*
X1877224Y490658D01*
Y489469D01*
G01X1876036Y492608D02*
X1875778Y492838D01*
X1875623Y493106D01*
X1875571Y493451D01*
X1875674Y493796D01*
X1875881Y494064D01*
X1876243Y494256D01*
X1876656Y494294D01*
X1877069Y494218D01*
X1877328Y494026D01*
X1877534Y493758D01*
X1877586Y493489D01*
X1877534Y493221D01*
X1877328Y492876D01*
X1878671Y492991D01*
Y494026D01*
G01X1879325Y480648D02*
X1879903Y482173D01*
G01X1876293Y860060D02*
X1879393D01*
Y860826D01*
X1879238Y861133D01*
X1879031Y861363D01*
X1878721Y861555D01*
X1878360Y861708D01*
X1877843Y861746D01*
X1877326Y861708D01*
X1876965Y861555D01*
X1876655Y861363D01*
X1876448Y861133D01*
X1876293Y860826D01*
Y860060D01*
G01X1877946Y864310D02*
X1878101Y864463D01*
X1878360Y864578D01*
X1878721Y864655D01*
X1879031Y864578D01*
X1879238Y864425D01*
X1879393Y864156D01*
Y863121D01*
X1876293D01*
Y864386D01*
X1876500Y864655D01*
X1876810Y864808D01*
X1877171Y864885D01*
X1877533Y864808D01*
X1877843Y864578D01*
X1877946Y864310D01*
Y863121D01*
G01X1876293Y867103D02*
X1879393D01*
X1878773Y866643D01*
G01X1876293D02*
Y867563D01*
G01Y870663D02*
X1879393D01*
X1877171Y869245D01*
Y871161D01*
G01X1873110Y1410067D02*
X1886223Y1375491D01*
G01X1899336Y1410067D02*
X1873110D01*
G01X1874619Y1690055D02*
X1877719D01*
Y1690821D01*
X1877564Y1691128D01*
X1877357Y1691358D01*
X1877047Y1691550D01*
X1876686Y1691703D01*
X1876169Y1691741D01*
X1875652Y1691703D01*
X1875291Y1691550D01*
X1874981Y1691358D01*
X1874774Y1691128D01*
X1874619Y1690821D01*
Y1690055D01*
G01X1876272Y1694305D02*
X1876427Y1694458D01*
X1876686Y1694573D01*
X1877047Y1694650D01*
X1877357Y1694573D01*
X1877564Y1694420D01*
X1877719Y1694151D01*
Y1693116D01*
X1874619D01*
Y1694381D01*
X1874826Y1694650D01*
X1875136Y1694803D01*
X1875497Y1694880D01*
X1875859Y1694803D01*
X1876169Y1694573D01*
X1876272Y1694305D01*
Y1693116D01*
G01X1874619Y1697098D02*
X1877719D01*
X1877099Y1696638D01*
G01X1874619D02*
Y1697558D01*
G01Y1700198D02*
X1877719D01*
X1877099Y1699738D01*
G01X1874619D02*
Y1700658D01*
G01X1886177Y1738299D02*
X1873064Y1703723D01*
G01D02*
X1899290D01*
G01X1895275Y-29973D02*
X1897775D01*
G01X1895825Y-39973D02*
X1895275D01*
G01D02*
Y-29973D01*
G01X1892855Y-25938D02*
X1895955Y-24328D01*
G01Y-25938D02*
X1892855Y-24328D01*
G01Y-22033D02*
X1892907Y-21765D01*
X1893062Y-21458D01*
X1893320Y-21266D01*
X1893682Y-21190D01*
X1894043Y-21266D01*
X1894353Y-21496D01*
X1894508Y-21841D01*
Y-22225D01*
X1894612Y-22455D01*
X1894870Y-22646D01*
X1895232Y-22723D01*
X1895593Y-22608D01*
X1895852Y-22340D01*
X1895955Y-22033D01*
X1895852Y-21726D01*
X1895593Y-21458D01*
X1895232Y-21343D01*
X1894870Y-21420D01*
X1894612Y-21611D01*
X1894508Y-21841D01*
Y-22225D01*
X1894353Y-22570D01*
X1894043Y-22800D01*
X1893682Y-22876D01*
X1893320Y-22800D01*
X1893062Y-22608D01*
X1892907Y-22301D01*
X1892855Y-22033D01*
G01X1895955Y-18933D02*
X1895852Y-19240D01*
X1895593Y-19470D01*
X1895283Y-19623D01*
X1894870Y-19738D01*
X1894405Y-19776D01*
X1893940Y-19738D01*
X1893527Y-19623D01*
X1893217Y-19470D01*
X1892958Y-19240D01*
X1892855Y-18933D01*
X1892958Y-18626D01*
X1893217Y-18396D01*
X1893527Y-18243D01*
X1893940Y-18128D01*
X1894405Y-18090D01*
X1894870Y-18128D01*
X1895283Y-18243D01*
X1895593Y-18396D01*
X1895852Y-18626D01*
X1895955Y-18933D01*
G01Y-15833D02*
X1895852Y-16140D01*
X1895593Y-16370D01*
X1895283Y-16523D01*
X1894870Y-16638D01*
X1894405Y-16676D01*
X1893940Y-16638D01*
X1893527Y-16523D01*
X1893217Y-16370D01*
X1892958Y-16140D01*
X1892855Y-15833D01*
X1892958Y-15526D01*
X1893217Y-15296D01*
X1893527Y-15143D01*
X1893940Y-15028D01*
X1894405Y-14990D01*
X1894870Y-15028D01*
X1895283Y-15143D01*
X1895593Y-15296D01*
X1895852Y-15526D01*
X1895955Y-15833D01*
G01X1894147Y-13461D02*
X1894508Y-13193D01*
X1894715Y-12963D01*
X1894818Y-12656D01*
X1894715Y-12388D01*
X1894508Y-12196D01*
X1894198Y-12043D01*
X1893837Y-12005D01*
X1893527Y-12043D01*
X1893217Y-12196D01*
X1892958Y-12426D01*
X1892855Y-12695D01*
X1892958Y-13001D01*
X1893268Y-13270D01*
X1893733Y-13423D01*
X1894250Y-13461D01*
X1894922Y-13385D01*
X1895283Y-13270D01*
X1895645Y-13078D01*
X1895903Y-12810D01*
X1895955Y-12541D01*
X1895852Y-12273D01*
X1895593Y-12081D01*
G01X1897775Y562227D02*
X1895275D01*
G01D02*
Y572227D01*
G01D02*
X1895825D01*
G01X1886223Y1375491D02*
X1899336Y1410067D01*
G01X1894469Y1412655D02*
X1897569D01*
Y1413421D01*
X1897414Y1413728D01*
X1897207Y1413958D01*
X1896897Y1414150D01*
X1896536Y1414303D01*
X1896019Y1414341D01*
X1895502Y1414303D01*
X1895141Y1414150D01*
X1894831Y1413958D01*
X1894624Y1413728D01*
X1894469Y1413421D01*
Y1412655D01*
G01X1896122Y1416905D02*
X1896277Y1417058D01*
X1896536Y1417173D01*
X1896897Y1417250D01*
X1897207Y1417173D01*
X1897414Y1417020D01*
X1897569Y1416751D01*
Y1415716D01*
X1894469D01*
Y1416981D01*
X1894676Y1417250D01*
X1894986Y1417403D01*
X1895347Y1417480D01*
X1895709Y1417403D01*
X1896019Y1417173D01*
X1896122Y1416905D01*
Y1415716D01*
G01X1894469Y1419698D02*
X1897569D01*
X1896949Y1419238D01*
G01X1894469D02*
Y1420158D01*
G01X1894934Y1421955D02*
X1894676Y1422185D01*
X1894521Y1422453D01*
X1894469Y1422798D01*
X1894572Y1423143D01*
X1894779Y1423411D01*
X1895141Y1423603D01*
X1895554Y1423641D01*
X1895967Y1423565D01*
X1896226Y1423373D01*
X1896432Y1423105D01*
X1896484Y1422836D01*
X1896432Y1422568D01*
X1896226Y1422223D01*
X1897569Y1422338D01*
Y1423373D01*
G01X1899290Y1703723D02*
X1886177Y1738299D01*
G01X1902775Y-29973D02*
X1907775D01*
G01X1905825Y-39973D02*
X1904725D01*
G01X1912775Y-29973D02*
X1915275D01*
G01D02*
Y-39973D01*
G01D02*
X1914725D01*
G01X1914805Y545022D02*
X1917905Y546632D01*
G01Y545022D02*
X1914805Y546632D01*
G01Y548927D02*
X1914857Y549195D01*
X1915012Y549502D01*
X1915270Y549694D01*
X1915632Y549770D01*
X1915993Y549694D01*
X1916303Y549464D01*
X1916458Y549119D01*
Y548735D01*
X1916562Y548505D01*
X1916820Y548314D01*
X1917182Y548237D01*
X1917543Y548352D01*
X1917802Y548620D01*
X1917905Y548927D01*
X1917802Y549234D01*
X1917543Y549502D01*
X1917182Y549617D01*
X1916820Y549540D01*
X1916562Y549349D01*
X1916458Y549119D01*
Y548735D01*
X1916303Y548390D01*
X1915993Y548160D01*
X1915632Y548084D01*
X1915270Y548160D01*
X1915012Y548352D01*
X1914857Y548659D01*
X1914805Y548927D01*
G01X1917905Y552027D02*
X1917802Y551720D01*
X1917543Y551490D01*
X1917233Y551337D01*
X1916820Y551222D01*
X1916355Y551184D01*
X1915890Y551222D01*
X1915477Y551337D01*
X1915167Y551490D01*
X1914908Y551720D01*
X1914805Y552027D01*
X1914908Y552334D01*
X1915167Y552564D01*
X1915477Y552717D01*
X1915890Y552832D01*
X1916355Y552870D01*
X1916820Y552832D01*
X1917233Y552717D01*
X1917543Y552564D01*
X1917802Y552334D01*
X1917905Y552027D01*
G01X1914805Y555127D02*
X1917905D01*
X1917285Y554667D01*
G01X1914805D02*
Y555587D01*
G01X1917388Y557499D02*
X1917698Y557729D01*
X1917853Y557997D01*
X1917905Y558304D01*
X1917802Y558687D01*
X1917543Y558955D01*
X1917233Y559032D01*
X1916923Y558994D01*
X1916665Y558840D01*
X1916148Y558074D01*
X1915787Y557729D01*
X1915270Y557499D01*
X1914805Y557422D01*
Y559032D01*
G01X1915275Y562227D02*
X1912775D01*
G01X1907775D02*
X1902775D01*
G01X1915275Y572227D02*
Y562227D01*
G01X1914725Y572227D02*
X1915275D01*
G01X1904725D02*
X1905825D01*
G01X1915816Y1163030D02*
X1918916Y1164640D01*
G01Y1163030D02*
X1915816Y1164640D01*
G01Y1166935D02*
X1918916D01*
X1918296Y1166475D01*
G01X1915816D02*
Y1167395D01*
G01X1918399Y1169307D02*
X1918709Y1169537D01*
X1918864Y1169805D01*
X1918916Y1170112D01*
X1918813Y1170495D01*
X1918554Y1170763D01*
X1918244Y1170840D01*
X1917934Y1170802D01*
X1917676Y1170648D01*
X1917159Y1169882D01*
X1916798Y1169537D01*
X1916281Y1169307D01*
X1915816Y1169230D01*
Y1170840D01*
G01X1914766Y1198160D02*
Y1208160D01*
G01X1915316Y1198160D02*
X1914766D01*
G01Y1208160D02*
X1917266D01*
G01X1915026Y1226005D02*
X1911926Y1224395D01*
G01Y1226005D02*
X1915026Y1224395D01*
G01X1914664Y1222752D02*
X1914923Y1222483D01*
X1915026Y1222177D01*
X1914923Y1221870D01*
X1914613Y1221602D01*
X1914148Y1221410D01*
X1913683Y1221333D01*
X1913114D01*
X1912649Y1221410D01*
X1912236Y1221602D01*
X1912029Y1221832D01*
X1911926Y1222100D01*
X1912029Y1222407D01*
X1912236Y1222637D01*
X1912546Y1222790D01*
X1912959Y1222867D01*
X1913321Y1222790D01*
X1913683Y1222598D01*
X1913889Y1222368D01*
X1913941Y1222100D01*
X1913838Y1221793D01*
X1913579Y1221563D01*
X1913114Y1221333D01*
G01X1911926Y1219000D02*
X1912029Y1219307D01*
X1912288Y1219537D01*
X1912598Y1219690D01*
X1913011Y1219805D01*
X1913476Y1219843D01*
X1913941Y1219805D01*
X1914354Y1219690D01*
X1914664Y1219537D01*
X1914923Y1219307D01*
X1915026Y1219000D01*
X1914923Y1218693D01*
X1914664Y1218463D01*
X1914354Y1218310D01*
X1913941Y1218195D01*
X1913476Y1218157D01*
X1913011Y1218195D01*
X1912598Y1218310D01*
X1912288Y1218463D01*
X1912029Y1218693D01*
X1911926Y1219000D01*
G01X1912443Y1216628D02*
X1912133Y1216398D01*
X1911978Y1216130D01*
X1911926Y1215823D01*
X1912029Y1215440D01*
X1912288Y1215172D01*
X1912598Y1215095D01*
X1912908Y1215133D01*
X1913166Y1215287D01*
X1913683Y1216053D01*
X1914044Y1216398D01*
X1914561Y1216628D01*
X1915026Y1216705D01*
Y1215095D01*
G01Y1212800D02*
X1914974Y1212532D01*
X1914819Y1212225D01*
X1914561Y1212033D01*
X1914199Y1211957D01*
X1913838Y1212033D01*
X1913528Y1212263D01*
X1913373Y1212608D01*
Y1212992D01*
X1913269Y1213222D01*
X1913011Y1213413D01*
X1912649Y1213490D01*
X1912288Y1213375D01*
X1912029Y1213107D01*
X1911926Y1212800D01*
X1912029Y1212493D01*
X1912288Y1212225D01*
X1912649Y1212110D01*
X1913011Y1212187D01*
X1913269Y1212378D01*
X1913373Y1212608D01*
Y1212992D01*
X1913528Y1213337D01*
X1913838Y1213567D01*
X1914199Y1213643D01*
X1914561Y1213567D01*
X1914819Y1213375D01*
X1914974Y1213068D01*
X1915026Y1212800D01*
G01X1914766Y1800360D02*
Y1810360D01*
G01X1917266Y1800360D02*
X1914766D01*
G01Y1810360D02*
X1915316D01*
G01X1916395Y572237D02*
Y582237D01*
G01X1923895D02*
X1928895D01*
G01X1916395D02*
X1918895D01*
G01X1926945Y572237D02*
X1925845D01*
G01X1916945D02*
X1916395D01*
G01X1930256Y586960D02*
X1933356Y588570D01*
G01Y586960D02*
X1930256Y588570D01*
G01X1931548Y590137D02*
X1931909Y590405D01*
X1932116Y590635D01*
X1932219Y590942D01*
X1932116Y591210D01*
X1931909Y591402D01*
X1931599Y591555D01*
X1931238Y591593D01*
X1930928Y591555D01*
X1930618Y591402D01*
X1930359Y591172D01*
X1930256Y590903D01*
X1930359Y590597D01*
X1930669Y590328D01*
X1931134Y590175D01*
X1931651Y590137D01*
X1932323Y590213D01*
X1932684Y590328D01*
X1933046Y590520D01*
X1933304Y590788D01*
X1933356Y591057D01*
X1933253Y591325D01*
X1932994Y591517D01*
G01X1928895Y1174437D02*
X1923895D01*
G01X1918895D02*
X1916395D01*
G01D02*
Y1184437D01*
G01X1925845D02*
X1926945D01*
G01X1916395D02*
X1916945D01*
G01X1925316Y1198160D02*
X1924216D01*
G01X1922266Y1208160D02*
X1927266D01*
G01Y1800360D02*
X1922266D01*
G01X1924216Y1810360D02*
X1925316D01*
G01X1937395Y-29783D02*
X1939895D01*
G01X1944895D02*
X1949895D01*
G01X1937945Y-39783D02*
X1937395D01*
G01D02*
Y-29783D01*
G01X1934975Y-25748D02*
X1938075Y-24138D01*
G01Y-25748D02*
X1934975Y-24138D01*
G01Y-21843D02*
X1935027Y-21575D01*
X1935182Y-21268D01*
X1935440Y-21076D01*
X1935802Y-21000D01*
X1936163Y-21076D01*
X1936473Y-21306D01*
X1936628Y-21651D01*
Y-22035D01*
X1936732Y-22265D01*
X1936990Y-22456D01*
X1937352Y-22533D01*
X1937713Y-22418D01*
X1937972Y-22150D01*
X1938075Y-21843D01*
X1937972Y-21536D01*
X1937713Y-21268D01*
X1937352Y-21153D01*
X1936990Y-21230D01*
X1936732Y-21421D01*
X1936628Y-21651D01*
Y-22035D01*
X1936473Y-22380D01*
X1936163Y-22610D01*
X1935802Y-22686D01*
X1935440Y-22610D01*
X1935182Y-22418D01*
X1935027Y-22111D01*
X1934975Y-21843D01*
G01X1938075Y-18743D02*
X1937972Y-19050D01*
X1937713Y-19280D01*
X1937403Y-19433D01*
X1936990Y-19548D01*
X1936525Y-19586D01*
X1936060Y-19548D01*
X1935647Y-19433D01*
X1935337Y-19280D01*
X1935078Y-19050D01*
X1934975Y-18743D01*
X1935078Y-18436D01*
X1935337Y-18206D01*
X1935647Y-18053D01*
X1936060Y-17938D01*
X1936525Y-17900D01*
X1936990Y-17938D01*
X1937403Y-18053D01*
X1937713Y-18206D01*
X1937972Y-18436D01*
X1938075Y-18743D01*
G01X1937558Y-16371D02*
X1937868Y-16141D01*
X1938023Y-15873D01*
X1938075Y-15566D01*
X1937972Y-15183D01*
X1937713Y-14915D01*
X1937403Y-14838D01*
X1937093Y-14876D01*
X1936835Y-15030D01*
X1936318Y-15796D01*
X1935957Y-16141D01*
X1935440Y-16371D01*
X1934975Y-16448D01*
Y-14838D01*
G01X1936267Y-13271D02*
X1936628Y-13003D01*
X1936835Y-12773D01*
X1936938Y-12466D01*
X1936835Y-12198D01*
X1936628Y-12006D01*
X1936318Y-11853D01*
X1935957Y-11815D01*
X1935647Y-11853D01*
X1935337Y-12006D01*
X1935078Y-12236D01*
X1934975Y-12505D01*
X1935078Y-12811D01*
X1935388Y-13080D01*
X1935853Y-13233D01*
X1936370Y-13271D01*
X1937042Y-13195D01*
X1937403Y-13080D01*
X1937765Y-12888D01*
X1938023Y-12620D01*
X1938075Y-12351D01*
X1937972Y-12083D01*
X1937713Y-11891D01*
G01X1949895Y562417D02*
X1944895D01*
G01X1939895D02*
X1937395D01*
G01D02*
Y572417D01*
G01X1933895Y582237D02*
X1936395D01*
G01D02*
Y572237D01*
G01D02*
X1935845D01*
G01X1937395Y572417D02*
X1937945D01*
G01X1936395Y1174437D02*
X1933895D01*
G01X1936395Y1184437D02*
Y1174437D01*
G01X1935845Y1184437D02*
X1936395D01*
G01X1934766Y1198160D02*
X1934216D01*
G01X1934766Y1208160D02*
Y1198160D01*
G01X1932266Y1208160D02*
X1934766D01*
G01X1934716Y1782105D02*
X1937816Y1783715D01*
G01Y1782105D02*
X1934716Y1783715D01*
G01X1935078Y1785358D02*
X1934819Y1785627D01*
X1934716Y1785933D01*
X1934819Y1786240D01*
X1935129Y1786508D01*
X1935594Y1786700D01*
X1936059Y1786777D01*
X1936628D01*
X1937093Y1786700D01*
X1937506Y1786508D01*
X1937713Y1786278D01*
X1937816Y1786010D01*
X1937713Y1785703D01*
X1937506Y1785473D01*
X1937196Y1785320D01*
X1936783Y1785243D01*
X1936421Y1785320D01*
X1936059Y1785512D01*
X1935853Y1785742D01*
X1935801Y1786010D01*
X1935904Y1786317D01*
X1936163Y1786547D01*
X1936628Y1786777D01*
G01X1937816Y1789110D02*
X1937713Y1788803D01*
X1937454Y1788573D01*
X1937144Y1788420D01*
X1936731Y1788305D01*
X1936266Y1788267D01*
X1935801Y1788305D01*
X1935388Y1788420D01*
X1935078Y1788573D01*
X1934819Y1788803D01*
X1934716Y1789110D01*
X1934819Y1789417D01*
X1935078Y1789647D01*
X1935388Y1789800D01*
X1935801Y1789915D01*
X1936266Y1789953D01*
X1936731Y1789915D01*
X1937144Y1789800D01*
X1937454Y1789647D01*
X1937713Y1789417D01*
X1937816Y1789110D01*
G01X1937299Y1791482D02*
X1937609Y1791712D01*
X1937764Y1791980D01*
X1937816Y1792287D01*
X1937713Y1792670D01*
X1937454Y1792938D01*
X1937144Y1793015D01*
X1936834Y1792977D01*
X1936576Y1792823D01*
X1936059Y1792057D01*
X1935698Y1791712D01*
X1935181Y1791482D01*
X1934716Y1791405D01*
Y1793015D01*
G01X1936008Y1794582D02*
X1936369Y1794850D01*
X1936576Y1795080D01*
X1936679Y1795387D01*
X1936576Y1795655D01*
X1936369Y1795847D01*
X1936059Y1796000D01*
X1935698Y1796038D01*
X1935388Y1796000D01*
X1935078Y1795847D01*
X1934819Y1795617D01*
X1934716Y1795348D01*
X1934819Y1795042D01*
X1935129Y1794773D01*
X1935594Y1794620D01*
X1936111Y1794582D01*
X1936783Y1794658D01*
X1937144Y1794773D01*
X1937506Y1794965D01*
X1937764Y1795233D01*
X1937816Y1795502D01*
X1937713Y1795770D01*
X1937454Y1795962D01*
G01X1934766Y1810360D02*
Y1800360D01*
G01D02*
X1932266D01*
G01X1934216Y1810360D02*
X1934766D01*
G01X1947945Y-39783D02*
X1946845D01*
G01X1954895Y-29783D02*
X1957395D01*
G01D02*
Y-39783D01*
G01D02*
X1956845D01*
G01X1956925Y545212D02*
X1960025Y546822D01*
G01Y545212D02*
X1956925Y546822D01*
G01Y549117D02*
X1956977Y549385D01*
X1957132Y549692D01*
X1957390Y549884D01*
X1957752Y549960D01*
X1958113Y549884D01*
X1958423Y549654D01*
X1958578Y549309D01*
Y548925D01*
X1958682Y548695D01*
X1958940Y548504D01*
X1959302Y548427D01*
X1959663Y548542D01*
X1959922Y548810D01*
X1960025Y549117D01*
X1959922Y549424D01*
X1959663Y549692D01*
X1959302Y549807D01*
X1958940Y549730D01*
X1958682Y549539D01*
X1958578Y549309D01*
Y548925D01*
X1958423Y548580D01*
X1958113Y548350D01*
X1957752Y548274D01*
X1957390Y548350D01*
X1957132Y548542D01*
X1956977Y548849D01*
X1956925Y549117D01*
G01X1960025Y552217D02*
X1959922Y551910D01*
X1959663Y551680D01*
X1959353Y551527D01*
X1958940Y551412D01*
X1958475Y551374D01*
X1958010Y551412D01*
X1957597Y551527D01*
X1957287Y551680D01*
X1957028Y551910D01*
X1956925Y552217D01*
X1957028Y552524D01*
X1957287Y552754D01*
X1957597Y552907D01*
X1958010Y553022D01*
X1958475Y553060D01*
X1958940Y553022D01*
X1959353Y552907D01*
X1959663Y552754D01*
X1959922Y552524D01*
X1960025Y552217D01*
G01X1959508Y554589D02*
X1959818Y554819D01*
X1959973Y555087D01*
X1960025Y555394D01*
X1959922Y555777D01*
X1959663Y556045D01*
X1959353Y556122D01*
X1959043Y556084D01*
X1958785Y555930D01*
X1958268Y555164D01*
X1957907Y554819D01*
X1957390Y554589D01*
X1956925Y554512D01*
Y556122D01*
G01Y558417D02*
X1956977Y558685D01*
X1957132Y558992D01*
X1957390Y559184D01*
X1957752Y559260D01*
X1958113Y559184D01*
X1958423Y558954D01*
X1958578Y558609D01*
Y558225D01*
X1958682Y557995D01*
X1958940Y557804D01*
X1959302Y557727D01*
X1959663Y557842D01*
X1959922Y558110D01*
X1960025Y558417D01*
X1959922Y558724D01*
X1959663Y558992D01*
X1959302Y559107D01*
X1958940Y559030D01*
X1958682Y558839D01*
X1958578Y558609D01*
Y558225D01*
X1958423Y557880D01*
X1958113Y557650D01*
X1957752Y557574D01*
X1957390Y557650D01*
X1957132Y557842D01*
X1956977Y558149D01*
X1956925Y558417D01*
G01X1957395Y562417D02*
X1954895D01*
G01X1957395Y572417D02*
Y562417D01*
G01X1958362Y582379D02*
X1960862D01*
G01X1958362Y572379D02*
Y582379D01*
G01X1958912Y572379D02*
X1958362D01*
G01X1956845Y572417D02*
X1957395D01*
G01X1946845D02*
X1947945D01*
G01X1959240Y1162760D02*
X1962340Y1164370D01*
G01Y1162760D02*
X1959240Y1164370D01*
G01X1961823Y1165937D02*
X1962133Y1166167D01*
X1962288Y1166435D01*
X1962340Y1166742D01*
X1962237Y1167125D01*
X1961978Y1167393D01*
X1961668Y1167470D01*
X1961358Y1167432D01*
X1961100Y1167278D01*
X1960583Y1166512D01*
X1960222Y1166167D01*
X1959705Y1165937D01*
X1959240Y1165860D01*
Y1167470D01*
G01X1960532Y1169037D02*
X1960893Y1169305D01*
X1961100Y1169535D01*
X1961203Y1169842D01*
X1961100Y1170110D01*
X1960893Y1170302D01*
X1960583Y1170455D01*
X1960222Y1170493D01*
X1959912Y1170455D01*
X1959602Y1170302D01*
X1959343Y1170072D01*
X1959240Y1169803D01*
X1959343Y1169497D01*
X1959653Y1169228D01*
X1960118Y1169075D01*
X1960635Y1169037D01*
X1961307Y1169113D01*
X1961668Y1169228D01*
X1962030Y1169420D01*
X1962288Y1169688D01*
X1962340Y1169957D01*
X1962237Y1170225D01*
X1961978Y1170417D01*
G01X1960862Y1174579D02*
X1958362D01*
G01D02*
Y1184579D01*
G01D02*
X1958912D01*
G01X1956856Y1198170D02*
Y1208170D01*
G01X1957406Y1198170D02*
X1956856D01*
G01Y1208170D02*
X1959356D01*
G01X1957116Y1226015D02*
X1954016Y1224405D01*
G01Y1226015D02*
X1957116Y1224405D01*
G01X1956754Y1222762D02*
X1957013Y1222493D01*
X1957116Y1222187D01*
X1957013Y1221880D01*
X1956703Y1221612D01*
X1956238Y1221420D01*
X1955773Y1221343D01*
X1955204D01*
X1954739Y1221420D01*
X1954326Y1221612D01*
X1954119Y1221842D01*
X1954016Y1222110D01*
X1954119Y1222417D01*
X1954326Y1222647D01*
X1954636Y1222800D01*
X1955049Y1222877D01*
X1955411Y1222800D01*
X1955773Y1222608D01*
X1955979Y1222378D01*
X1956031Y1222110D01*
X1955928Y1221803D01*
X1955669Y1221573D01*
X1955204Y1221343D01*
G01X1954016Y1219010D02*
X1954119Y1219317D01*
X1954378Y1219547D01*
X1954688Y1219700D01*
X1955101Y1219815D01*
X1955566Y1219853D01*
X1956031Y1219815D01*
X1956444Y1219700D01*
X1956754Y1219547D01*
X1957013Y1219317D01*
X1957116Y1219010D01*
X1957013Y1218703D01*
X1956754Y1218473D01*
X1956444Y1218320D01*
X1956031Y1218205D01*
X1955566Y1218167D01*
X1955101Y1218205D01*
X1954688Y1218320D01*
X1954378Y1218473D01*
X1954119Y1218703D01*
X1954016Y1219010D01*
G01X1954533Y1216638D02*
X1954223Y1216408D01*
X1954068Y1216140D01*
X1954016Y1215833D01*
X1954119Y1215450D01*
X1954378Y1215182D01*
X1954688Y1215105D01*
X1954998Y1215143D01*
X1955256Y1215297D01*
X1955773Y1216063D01*
X1956134Y1216408D01*
X1956651Y1216638D01*
X1957116Y1216715D01*
Y1215105D01*
G01X1956651Y1213653D02*
X1956909Y1213423D01*
X1957064Y1213155D01*
X1957116Y1212810D01*
X1957013Y1212465D01*
X1956806Y1212197D01*
X1956444Y1212005D01*
X1956031Y1211967D01*
X1955618Y1212043D01*
X1955359Y1212235D01*
X1955153Y1212503D01*
X1955101Y1212772D01*
X1955153Y1213040D01*
X1955359Y1213385D01*
X1954016Y1213270D01*
Y1212235D01*
G01X1956856Y1800370D02*
Y1810370D01*
G01X1959356Y1800370D02*
X1956856D01*
G01Y1810370D02*
X1957406D01*
G01X1965862Y582379D02*
X1970862D01*
G01X1968912Y572379D02*
X1967812D01*
G01X1972870Y586490D02*
X1975970Y588100D01*
G01Y586490D02*
X1972870Y588100D01*
G01X1975453Y589667D02*
X1975763Y589897D01*
X1975918Y590165D01*
X1975970Y590472D01*
X1975867Y590855D01*
X1975608Y591123D01*
X1975298Y591200D01*
X1974988Y591162D01*
X1974730Y591008D01*
X1974213Y590242D01*
X1973852Y589897D01*
X1973335Y589667D01*
X1972870Y589590D01*
Y591200D01*
G01Y593495D02*
X1972922Y593763D01*
X1973077Y594070D01*
X1973335Y594262D01*
X1973697Y594338D01*
X1974058Y594262D01*
X1974368Y594032D01*
X1974523Y593687D01*
Y593303D01*
X1974627Y593073D01*
X1974885Y592882D01*
X1975247Y592805D01*
X1975608Y592920D01*
X1975867Y593188D01*
X1975970Y593495D01*
X1975867Y593802D01*
X1975608Y594070D01*
X1975247Y594185D01*
X1974885Y594108D01*
X1974627Y593917D01*
X1974523Y593687D01*
Y593303D01*
X1974368Y592958D01*
X1974058Y592728D01*
X1973697Y592652D01*
X1973335Y592728D01*
X1973077Y592920D01*
X1972922Y593227D01*
X1972870Y593495D01*
G01X1970862Y1174579D02*
X1965862D01*
G01X1967812Y1184579D02*
X1968912D01*
G01X1974356Y1208170D02*
X1976856D01*
G01X1967406Y1198170D02*
X1966306D01*
G01X1964356Y1208170D02*
X1969356D01*
G01Y1800370D02*
X1964356D01*
G01X1976856D02*
X1974356D01*
G01X1966306Y1810370D02*
X1967406D01*
G01X1979482Y-29811D02*
X1981982D01*
G01X1986982D02*
X1991982D01*
G01X1980032Y-39811D02*
X1979482D01*
G01D02*
Y-29811D01*
G01X1990032Y-39811D02*
X1988932D01*
G01X1977062Y-25776D02*
X1980162Y-24166D01*
G01Y-25776D02*
X1977062Y-24166D01*
G01Y-21871D02*
X1977114Y-21603D01*
X1977269Y-21296D01*
X1977527Y-21104D01*
X1977889Y-21028D01*
X1978250Y-21104D01*
X1978560Y-21334D01*
X1978715Y-21679D01*
Y-22063D01*
X1978819Y-22293D01*
X1979077Y-22484D01*
X1979439Y-22561D01*
X1979800Y-22446D01*
X1980059Y-22178D01*
X1980162Y-21871D01*
X1980059Y-21564D01*
X1979800Y-21296D01*
X1979439Y-21181D01*
X1979077Y-21258D01*
X1978819Y-21449D01*
X1978715Y-21679D01*
Y-22063D01*
X1978560Y-22408D01*
X1978250Y-22638D01*
X1977889Y-22714D01*
X1977527Y-22638D01*
X1977269Y-22446D01*
X1977114Y-22139D01*
X1977062Y-21871D01*
G01X1980162Y-18771D02*
X1980059Y-19078D01*
X1979800Y-19308D01*
X1979490Y-19461D01*
X1979077Y-19576D01*
X1978612Y-19614D01*
X1978147Y-19576D01*
X1977734Y-19461D01*
X1977424Y-19308D01*
X1977165Y-19078D01*
X1977062Y-18771D01*
X1977165Y-18464D01*
X1977424Y-18234D01*
X1977734Y-18081D01*
X1978147Y-17966D01*
X1978612Y-17928D01*
X1979077Y-17966D01*
X1979490Y-18081D01*
X1979800Y-18234D01*
X1980059Y-18464D01*
X1980162Y-18771D01*
G01X1979645Y-16399D02*
X1979955Y-16169D01*
X1980110Y-15901D01*
X1980162Y-15594D01*
X1980059Y-15211D01*
X1979800Y-14943D01*
X1979490Y-14866D01*
X1979180Y-14904D01*
X1978922Y-15058D01*
X1978405Y-15824D01*
X1978044Y-16169D01*
X1977527Y-16399D01*
X1977062Y-16476D01*
Y-14866D01*
G01X1977527Y-13414D02*
X1977269Y-13184D01*
X1977114Y-12916D01*
X1977062Y-12571D01*
X1977165Y-12226D01*
X1977372Y-11958D01*
X1977734Y-11766D01*
X1978147Y-11728D01*
X1978560Y-11804D01*
X1978819Y-11996D01*
X1979025Y-12264D01*
X1979077Y-12533D01*
X1979025Y-12801D01*
X1978819Y-13146D01*
X1980162Y-13031D01*
Y-11996D01*
G01X1991982Y562389D02*
X1986982D01*
G01X1981982D02*
X1979482D01*
G01D02*
Y572389D01*
G01X1975862Y582379D02*
X1978362D01*
G01D02*
Y572379D01*
G01D02*
X1977812D01*
G01X1988932Y572389D02*
X1990032D01*
G01X1979482D02*
X1980032D01*
G01X1978362Y1174579D02*
X1975862D01*
G01X1978362Y1184579D02*
Y1174579D01*
G01X1977812Y1184579D02*
X1978362D01*
G01X1976856Y1198170D02*
X1976306D01*
G01X1976856Y1208170D02*
Y1198170D01*
G01X1976806Y1782115D02*
X1979906Y1783725D01*
G01Y1782115D02*
X1976806Y1783725D01*
G01X1977168Y1785368D02*
X1976909Y1785637D01*
X1976806Y1785943D01*
X1976909Y1786250D01*
X1977219Y1786518D01*
X1977684Y1786710D01*
X1978149Y1786787D01*
X1978718D01*
X1979183Y1786710D01*
X1979596Y1786518D01*
X1979803Y1786288D01*
X1979906Y1786020D01*
X1979803Y1785713D01*
X1979596Y1785483D01*
X1979286Y1785330D01*
X1978873Y1785253D01*
X1978511Y1785330D01*
X1978149Y1785522D01*
X1977943Y1785752D01*
X1977891Y1786020D01*
X1977994Y1786327D01*
X1978253Y1786557D01*
X1978718Y1786787D01*
G01X1979906Y1789120D02*
X1979803Y1788813D01*
X1979544Y1788583D01*
X1979234Y1788430D01*
X1978821Y1788315D01*
X1978356Y1788277D01*
X1977891Y1788315D01*
X1977478Y1788430D01*
X1977168Y1788583D01*
X1976909Y1788813D01*
X1976806Y1789120D01*
X1976909Y1789427D01*
X1977168Y1789657D01*
X1977478Y1789810D01*
X1977891Y1789925D01*
X1978356Y1789963D01*
X1978821Y1789925D01*
X1979234Y1789810D01*
X1979544Y1789657D01*
X1979803Y1789427D01*
X1979906Y1789120D01*
G01X1979389Y1791492D02*
X1979699Y1791722D01*
X1979854Y1791990D01*
X1979906Y1792297D01*
X1979803Y1792680D01*
X1979544Y1792948D01*
X1979234Y1793025D01*
X1978924Y1792987D01*
X1978666Y1792833D01*
X1978149Y1792067D01*
X1977788Y1791722D01*
X1977271Y1791492D01*
X1976806Y1791415D01*
Y1793025D01*
G01Y1795243D02*
X1977478Y1795320D01*
X1978046Y1795435D01*
X1978563Y1795588D01*
X1979131Y1795780D01*
X1979906Y1796087D01*
Y1794553D01*
G01X1976856Y1810370D02*
Y1800370D01*
G01X1976306Y1810370D02*
X1976856D01*
G01X1996982Y-29811D02*
X1999482D01*
G01D02*
Y-39811D01*
G01D02*
X1998932D01*
G01X1999012Y545184D02*
X2002112Y546794D01*
G01Y545184D02*
X1999012Y546794D01*
G01Y549089D02*
X1999064Y549357D01*
X1999219Y549664D01*
X1999477Y549856D01*
X1999839Y549932D01*
X2000200Y549856D01*
X2000510Y549626D01*
X2000665Y549281D01*
Y548897D01*
X2000769Y548667D01*
X2001027Y548476D01*
X2001389Y548399D01*
X2001750Y548514D01*
X2002009Y548782D01*
X2002112Y549089D01*
X2002009Y549396D01*
X2001750Y549664D01*
X2001389Y549779D01*
X2001027Y549702D01*
X2000769Y549511D01*
X2000665Y549281D01*
Y548897D01*
X2000510Y548552D01*
X2000200Y548322D01*
X1999839Y548246D01*
X1999477Y548322D01*
X1999219Y548514D01*
X1999064Y548821D01*
X1999012Y549089D01*
G01X2002112Y552189D02*
X2002009Y551882D01*
X2001750Y551652D01*
X2001440Y551499D01*
X2001027Y551384D01*
X2000562Y551346D01*
X2000097Y551384D01*
X1999684Y551499D01*
X1999374Y551652D01*
X1999115Y551882D01*
X1999012Y552189D01*
X1999115Y552496D01*
X1999374Y552726D01*
X1999684Y552879D01*
X2000097Y552994D01*
X2000562Y553032D01*
X2001027Y552994D01*
X2001440Y552879D01*
X2001750Y552726D01*
X2002009Y552496D01*
X2002112Y552189D01*
G01X2001595Y554561D02*
X2001905Y554791D01*
X2002060Y555059D01*
X2002112Y555366D01*
X2002009Y555749D01*
X2001750Y556017D01*
X2001440Y556094D01*
X2001130Y556056D01*
X2000872Y555902D01*
X2000355Y555136D01*
X1999994Y554791D01*
X1999477Y554561D01*
X1999012Y554484D01*
Y556094D01*
G01Y558312D02*
X1999684Y558389D01*
X2000252Y558504D01*
X2000769Y558657D01*
X2001337Y558849D01*
X2002112Y559156D01*
Y557622D01*
G01X1999482Y562389D02*
X1996982D01*
G01X1999482Y572389D02*
Y562389D01*
G01X2000452Y582389D02*
X2002952D01*
G01X2000452Y572389D02*
Y582389D01*
G01X2001002Y572389D02*
X2000452D01*
G01X1998932D02*
X1999482D01*
G01X2001400Y1162740D02*
X2004500Y1164350D01*
G01Y1162740D02*
X2001400Y1164350D01*
G01X2003983Y1165917D02*
X2004293Y1166147D01*
X2004448Y1166415D01*
X2004500Y1166722D01*
X2004397Y1167105D01*
X2004138Y1167373D01*
X2003828Y1167450D01*
X2003518Y1167412D01*
X2003260Y1167258D01*
X2002743Y1166492D01*
X2002382Y1166147D01*
X2001865Y1165917D01*
X2001400Y1165840D01*
Y1167450D01*
G01Y1169668D02*
X2002072Y1169745D01*
X2002640Y1169860D01*
X2003157Y1170013D01*
X2003725Y1170205D01*
X2004500Y1170512D01*
Y1168978D01*
G01X2002952Y1174589D02*
X2000452D01*
G01D02*
Y1184589D01*
G01D02*
X2001002D01*
G01X1998823Y1198312D02*
Y1208312D01*
G01X1999373Y1198312D02*
X1998823D01*
G01Y1208312D02*
X2001323D01*
G01X1999083Y1226157D02*
X1995983Y1224547D01*
G01Y1226157D02*
X1999083Y1224547D01*
G01X1998721Y1222904D02*
X1998980Y1222635D01*
X1999083Y1222329D01*
X1998980Y1222022D01*
X1998670Y1221754D01*
X1998205Y1221562D01*
X1997740Y1221485D01*
X1997171D01*
X1996706Y1221562D01*
X1996293Y1221754D01*
X1996086Y1221984D01*
X1995983Y1222252D01*
X1996086Y1222559D01*
X1996293Y1222789D01*
X1996603Y1222942D01*
X1997016Y1223019D01*
X1997378Y1222942D01*
X1997740Y1222750D01*
X1997946Y1222520D01*
X1997998Y1222252D01*
X1997895Y1221945D01*
X1997636Y1221715D01*
X1997171Y1221485D01*
G01X1995983Y1219152D02*
X1996086Y1219459D01*
X1996345Y1219689D01*
X1996655Y1219842D01*
X1997068Y1219957D01*
X1997533Y1219995D01*
X1997998Y1219957D01*
X1998411Y1219842D01*
X1998721Y1219689D01*
X1998980Y1219459D01*
X1999083Y1219152D01*
X1998980Y1218845D01*
X1998721Y1218615D01*
X1998411Y1218462D01*
X1997998Y1218347D01*
X1997533Y1218309D01*
X1997068Y1218347D01*
X1996655Y1218462D01*
X1996345Y1218615D01*
X1996086Y1218845D01*
X1995983Y1219152D01*
G01Y1216052D02*
X1996086Y1216359D01*
X1996345Y1216589D01*
X1996655Y1216742D01*
X1997068Y1216857D01*
X1997533Y1216895D01*
X1997998Y1216857D01*
X1998411Y1216742D01*
X1998721Y1216589D01*
X1998980Y1216359D01*
X1999083Y1216052D01*
X1998980Y1215745D01*
X1998721Y1215515D01*
X1998411Y1215362D01*
X1997998Y1215247D01*
X1997533Y1215209D01*
X1997068Y1215247D01*
X1996655Y1215362D01*
X1996345Y1215515D01*
X1996086Y1215745D01*
X1995983Y1216052D01*
G01X1998618Y1213795D02*
X1998876Y1213565D01*
X1999031Y1213297D01*
X1999083Y1212952D01*
X1998980Y1212607D01*
X1998773Y1212339D01*
X1998411Y1212147D01*
X1997998Y1212109D01*
X1997585Y1212185D01*
X1997326Y1212377D01*
X1997120Y1212645D01*
X1997068Y1212914D01*
X1997120Y1213182D01*
X1997326Y1213527D01*
X1995983Y1213412D01*
Y1212377D01*
G01X1998823Y1800512D02*
Y1810512D01*
G01X2001323Y1800512D02*
X1998823D01*
G01Y1810512D02*
X1999373D01*
G01X2019032Y-25596D02*
X2022132Y-23986D01*
G01Y-25596D02*
X2019032Y-23986D01*
G01Y-21691D02*
X2019084Y-21423D01*
X2019239Y-21116D01*
X2019497Y-20924D01*
X2019859Y-20848D01*
X2020220Y-20924D01*
X2020530Y-21154D01*
X2020685Y-21499D01*
Y-21883D01*
X2020789Y-22113D01*
X2021047Y-22304D01*
X2021409Y-22381D01*
X2021770Y-22266D01*
X2022029Y-21998D01*
X2022132Y-21691D01*
X2022029Y-21384D01*
X2021770Y-21116D01*
X2021409Y-21001D01*
X2021047Y-21078D01*
X2020789Y-21269D01*
X2020685Y-21499D01*
Y-21883D01*
X2020530Y-22228D01*
X2020220Y-22458D01*
X2019859Y-22534D01*
X2019497Y-22458D01*
X2019239Y-22266D01*
X2019084Y-21959D01*
X2019032Y-21691D01*
G01X2022132Y-18591D02*
X2022029Y-18898D01*
X2021770Y-19128D01*
X2021460Y-19281D01*
X2021047Y-19396D01*
X2020582Y-19434D01*
X2020117Y-19396D01*
X2019704Y-19281D01*
X2019394Y-19128D01*
X2019135Y-18898D01*
X2019032Y-18591D01*
X2019135Y-18284D01*
X2019394Y-18054D01*
X2019704Y-17901D01*
X2020117Y-17786D01*
X2020582Y-17748D01*
X2021047Y-17786D01*
X2021460Y-17901D01*
X2021770Y-18054D01*
X2022029Y-18284D01*
X2022132Y-18591D01*
G01Y-15491D02*
X2022029Y-15798D01*
X2021770Y-16028D01*
X2021460Y-16181D01*
X2021047Y-16296D01*
X2020582Y-16334D01*
X2020117Y-16296D01*
X2019704Y-16181D01*
X2019394Y-16028D01*
X2019135Y-15798D01*
X2019032Y-15491D01*
X2019135Y-15184D01*
X2019394Y-14954D01*
X2019704Y-14801D01*
X2020117Y-14686D01*
X2020582Y-14648D01*
X2021047Y-14686D01*
X2021460Y-14801D01*
X2021770Y-14954D01*
X2022029Y-15184D01*
X2022132Y-15491D01*
G01X2019497Y-13234D02*
X2019239Y-13004D01*
X2019084Y-12736D01*
X2019032Y-12391D01*
X2019135Y-12046D01*
X2019342Y-11778D01*
X2019704Y-11586D01*
X2020117Y-11548D01*
X2020530Y-11624D01*
X2020789Y-11816D01*
X2020995Y-12084D01*
X2021047Y-12353D01*
X2020995Y-12621D01*
X2020789Y-12966D01*
X2022132Y-12851D01*
Y-11816D01*
G01X2007952Y582389D02*
X2012952D01*
G01X2017952D02*
X2020452D01*
G01X2011002Y572389D02*
X2009902D01*
G01X2016380Y586220D02*
X2019480Y587830D01*
G01Y586220D02*
X2016380Y587830D01*
G01X2018963Y589397D02*
X2019273Y589627D01*
X2019428Y589895D01*
X2019480Y590202D01*
X2019377Y590585D01*
X2019118Y590853D01*
X2018808Y590930D01*
X2018498Y590892D01*
X2018240Y590738D01*
X2017723Y589972D01*
X2017362Y589627D01*
X2016845Y589397D01*
X2016380Y589320D01*
Y590930D01*
G01X2016845Y592382D02*
X2016587Y592612D01*
X2016432Y592880D01*
X2016380Y593225D01*
X2016483Y593570D01*
X2016690Y593838D01*
X2017052Y594030D01*
X2017465Y594068D01*
X2017878Y593992D01*
X2018137Y593800D01*
X2018343Y593532D01*
X2018395Y593263D01*
X2018343Y592995D01*
X2018137Y592650D01*
X2019480Y592765D01*
Y593800D01*
G01X2020452Y1174589D02*
X2017952D01*
G01X2012952D02*
X2007952D01*
G01X2009902Y1184589D02*
X2011002D01*
G01X2018823Y1198312D02*
X2018273D01*
G01X2018823Y1208312D02*
Y1198312D01*
G01X2016323Y1208312D02*
X2018823D01*
G01X2009373Y1198312D02*
X2008273D01*
G01X2006323Y1208312D02*
X2011323D01*
G01X2018773Y1782257D02*
X2021873Y1783867D01*
G01Y1782257D02*
X2018773Y1783867D01*
G01X2019135Y1785510D02*
X2018876Y1785779D01*
X2018773Y1786085D01*
X2018876Y1786392D01*
X2019186Y1786660D01*
X2019651Y1786852D01*
X2020116Y1786929D01*
X2020685D01*
X2021150Y1786852D01*
X2021563Y1786660D01*
X2021770Y1786430D01*
X2021873Y1786162D01*
X2021770Y1785855D01*
X2021563Y1785625D01*
X2021253Y1785472D01*
X2020840Y1785395D01*
X2020478Y1785472D01*
X2020116Y1785664D01*
X2019910Y1785894D01*
X2019858Y1786162D01*
X2019961Y1786469D01*
X2020220Y1786699D01*
X2020685Y1786929D01*
G01X2021873Y1789262D02*
X2021770Y1788955D01*
X2021511Y1788725D01*
X2021201Y1788572D01*
X2020788Y1788457D01*
X2020323Y1788419D01*
X2019858Y1788457D01*
X2019445Y1788572D01*
X2019135Y1788725D01*
X2018876Y1788955D01*
X2018773Y1789262D01*
X2018876Y1789569D01*
X2019135Y1789799D01*
X2019445Y1789952D01*
X2019858Y1790067D01*
X2020323Y1790105D01*
X2020788Y1790067D01*
X2021201Y1789952D01*
X2021511Y1789799D01*
X2021770Y1789569D01*
X2021873Y1789262D01*
G01X2018773Y1792362D02*
X2021873D01*
X2021253Y1791902D01*
G01X2018773D02*
Y1792822D01*
G01Y1795462D02*
X2021873D01*
X2021253Y1795002D01*
G01X2018773D02*
Y1795922D01*
G01X2018823Y1810512D02*
Y1800512D01*
G01X2011323D02*
X2006323D01*
G01X2018823D02*
X2016323D01*
G01X2008273Y1810512D02*
X2009373D01*
G01X2018273D02*
X2018823D01*
G01X2021452Y-29631D02*
X2023952D01*
G01X2028952D02*
X2033952D01*
G01X2022002Y-39631D02*
X2021452D01*
G01D02*
Y-29631D01*
G01X2032002Y-39631D02*
X2030902D01*
G01X2033952Y562569D02*
X2028952D01*
G01X2023952D02*
X2021452D01*
G01D02*
Y572569D01*
G01X2020452Y582389D02*
Y572389D01*
G01D02*
X2019902D01*
G01X2030902Y572569D02*
X2032002D01*
G01X2021452D02*
X2022002D01*
G01X2020452Y1184589D02*
Y1174589D01*
G01X2019902Y1184589D02*
X2020452D01*
G01X2038952Y-29631D02*
X2041452D01*
G01D02*
Y-39631D01*
G01D02*
X2040902D01*
G01X2040982Y545364D02*
X2044082Y546974D01*
G01Y545364D02*
X2040982Y546974D01*
G01Y549269D02*
X2041034Y549537D01*
X2041189Y549844D01*
X2041447Y550036D01*
X2041809Y550112D01*
X2042170Y550036D01*
X2042480Y549806D01*
X2042635Y549461D01*
Y549077D01*
X2042739Y548847D01*
X2042997Y548656D01*
X2043359Y548579D01*
X2043720Y548694D01*
X2043979Y548962D01*
X2044082Y549269D01*
X2043979Y549576D01*
X2043720Y549844D01*
X2043359Y549959D01*
X2042997Y549882D01*
X2042739Y549691D01*
X2042635Y549461D01*
Y549077D01*
X2042480Y548732D01*
X2042170Y548502D01*
X2041809Y548426D01*
X2041447Y548502D01*
X2041189Y548694D01*
X2041034Y549001D01*
X2040982Y549269D01*
G01X2044082Y552369D02*
X2043979Y552062D01*
X2043720Y551832D01*
X2043410Y551679D01*
X2042997Y551564D01*
X2042532Y551526D01*
X2042067Y551564D01*
X2041654Y551679D01*
X2041344Y551832D01*
X2041085Y552062D01*
X2040982Y552369D01*
X2041085Y552676D01*
X2041344Y552906D01*
X2041654Y553059D01*
X2042067Y553174D01*
X2042532Y553212D01*
X2042997Y553174D01*
X2043410Y553059D01*
X2043720Y552906D01*
X2043979Y552676D01*
X2044082Y552369D01*
G01X2040982Y555469D02*
X2044082D01*
X2043462Y555009D01*
G01X2040982D02*
Y555929D01*
G01Y558569D02*
X2044082D01*
X2043462Y558109D01*
G01X2040982D02*
Y559029D01*
G01X2041452Y562569D02*
X2038952D01*
G01X2041452Y572569D02*
Y562569D01*
G01X2042419Y582531D02*
X2044919D01*
G01X2042419Y572531D02*
Y582531D01*
G01X2042969Y572531D02*
X2042419D01*
G01X2040902Y572569D02*
X2041452D01*
G01X2043550Y1162070D02*
X2046650Y1163680D01*
G01Y1162070D02*
X2043550Y1163680D01*
G01Y1165975D02*
X2046650D01*
X2046030Y1165515D01*
G01X2043550D02*
Y1166435D01*
G01Y1169075D02*
X2046650D01*
X2046030Y1168615D01*
G01X2043550D02*
Y1169535D01*
G01X2044919Y1174731D02*
X2042419D01*
G01D02*
Y1184731D01*
G01D02*
X2042969D01*
G01X2063899Y113912D02*
X2077012Y79336D01*
G01X2090125Y113912D02*
X2063899D01*
G01X2064709Y389447D02*
X2067809D01*
Y390213D01*
X2067654Y390520D01*
X2067447Y390750D01*
X2067137Y390942D01*
X2066776Y391095D01*
X2066259Y391133D01*
X2065742Y391095D01*
X2065381Y390942D01*
X2065071Y390750D01*
X2064864Y390520D01*
X2064709Y390213D01*
Y389447D01*
G01X2066362Y393697D02*
X2066517Y393850D01*
X2066776Y393965D01*
X2067137Y394042D01*
X2067447Y393965D01*
X2067654Y393812D01*
X2067809Y393543D01*
Y392508D01*
X2064709D01*
Y393773D01*
X2064916Y394042D01*
X2065226Y394195D01*
X2065587Y394272D01*
X2065949Y394195D01*
X2066259Y393965D01*
X2066362Y393697D01*
Y392508D01*
G01X2064709Y396490D02*
X2067809D01*
X2067189Y396030D01*
G01X2064709D02*
Y396950D01*
G01X2067292Y398862D02*
X2067602Y399092D01*
X2067757Y399360D01*
X2067809Y399667D01*
X2067706Y400050D01*
X2067447Y400318D01*
X2067137Y400395D01*
X2066827Y400357D01*
X2066569Y400203D01*
X2066052Y399437D01*
X2065691Y399092D01*
X2065174Y398862D01*
X2064709Y398785D01*
Y400395D01*
G01X2063015Y405229D02*
X2089241D01*
G01X2076128Y439805D02*
X2063015Y405229D01*
G01X2049919Y582531D02*
X2054919D01*
G01X2059919D02*
X2062419D01*
G01D02*
Y572531D01*
G01X2052969D02*
X2051869D01*
G01X2062419D02*
X2061869D01*
G01X2057290Y586770D02*
X2060390Y588380D01*
G01Y586770D02*
X2057290Y588380D01*
G01X2057755Y589832D02*
X2057497Y590062D01*
X2057342Y590330D01*
X2057290Y590675D01*
X2057393Y591020D01*
X2057600Y591288D01*
X2057962Y591480D01*
X2058375Y591518D01*
X2058788Y591442D01*
X2059047Y591250D01*
X2059253Y590982D01*
X2059305Y590713D01*
X2059253Y590445D01*
X2059047Y590100D01*
X2060390Y590215D01*
Y591250D01*
G01X2062419Y1174731D02*
X2059919D01*
G01X2054919D02*
X2049919D01*
G01X2062419Y1184731D02*
Y1174731D01*
G01X2061869Y1184731D02*
X2062419D01*
G01X2051869D02*
X2052969D01*
G01X2077012Y79336D02*
X2090125Y113912D01*
G01X2089241Y405229D02*
X2076128Y439805D01*
G01X2085799Y117137D02*
X2088899D01*
Y117903D01*
X2088744Y118210D01*
X2088537Y118440D01*
X2088227Y118632D01*
X2087866Y118785D01*
X2087349Y118823D01*
X2086832Y118785D01*
X2086471Y118632D01*
X2086161Y118440D01*
X2085954Y118210D01*
X2085799Y117903D01*
Y117137D01*
G01X2087452Y121387D02*
X2087607Y121540D01*
X2087866Y121655D01*
X2088227Y121732D01*
X2088537Y121655D01*
X2088744Y121502D01*
X2088899Y121233D01*
Y120198D01*
X2085799D01*
Y121463D01*
X2086006Y121732D01*
X2086316Y121885D01*
X2086677Y121962D01*
X2087039Y121885D01*
X2087349Y121655D01*
X2087452Y121387D01*
Y120198D01*
G01X2085799Y124180D02*
X2088899D01*
X2088279Y123720D01*
G01X2085799D02*
Y124640D01*
G01X2087091Y126552D02*
X2087452Y126820D01*
X2087659Y127050D01*
X2087762Y127357D01*
X2087659Y127625D01*
X2087452Y127817D01*
X2087142Y127970D01*
X2086781Y128008D01*
X2086471Y127970D01*
X2086161Y127817D01*
X2085902Y127587D01*
X2085799Y127318D01*
X2085902Y127012D01*
X2086212Y126743D01*
X2086677Y126590D01*
X2087194Y126552D01*
X2087866Y126628D01*
X2088227Y126743D01*
X2088589Y126935D01*
X2088847Y127203D01*
X2088899Y127472D01*
X2088796Y127740D01*
X2088537Y127932D01*
M02*
